FILE_TYPE=LIBRARY_PARTS;
primitive 'GENOA_SP5';
  pin
    'MA_ALERT_L':
      PIN_NUMBER='(AR74,0,0,0,0,0,0,0,0,0,0,0,0,0,0,0,0,0,0,0,0,0,0,0,0,0,0,0,0,0,0,0,0,0,0,0,0,0,0,0)';
      INPUT_LOAD='(-0.01,0.01)';
    'MA_RESET_L':
      PIN_NUMBER='(AT74,0,0,0,0,0,0,0,0,0,0,0,0,0,0,0,0,0,0,0,0,0,0,0,0,0,0,0,0,0,0,0,0,0,0,0,0,0,0,0)';
      OUTPUT_LOAD='(1.0,-1.0)';
    'MAB_DQS_L5':
      PIN_NUMBER='(CE73,0,0,0,0,0,0,0,0,0,0,0,0,0,0,0,0,0,0,0,0,0,0,0,0,0,0,0,0,0,0,0,0,0,0,0,0,0,0,0)';
      BIDIRECTIONAL='TRUE';
      INPUT_LOAD='(-0.01,0.01)';
      OUTPUT_LOAD='(1.0,-1.0)';
    'MAB_DQS_H1':
      PIN_NUMBER='(CK74,0,0,0,0,0,0,0,0,0,0,0,0,0,0,0,0,0,0,0,0,0,0,0,0,0,0,0,0,0,0,0,0,0,0,0,0,0,0,0)';
      BIDIRECTIONAL='TRUE';
      INPUT_LOAD='(-0.01,0.01)';
      OUTPUT_LOAD='(1.0,-1.0)';
    'MAB_DATA29':
      PIN_NUMBER='(DE73,0,0,0,0,0,0,0,0,0,0,0,0,0,0,0,0,0,0,0,0,0,0,0,0,0,0,0,0,0,0,0,0,0,0,0,0,0,0,0)';
      BIDIRECTIONAL='TRUE';
      INPUT_LOAD='(-0.01,0.01)';
      OUTPUT_LOAD='(1.0,-1.0)';
    'MAB_DATA18':
      PIN_NUMBER='(CR74,0,0,0,0,0,0,0,0,0,0,0,0,0,0,0,0,0,0,0,0,0,0,0,0,0,0,0,0,0,0,0,0,0,0,0,0,0,0,0)';
      BIDIRECTIONAL='TRUE';
      INPUT_LOAD='(-0.01,0.01)';
      OUTPUT_LOAD='(1.0,-1.0)';
    'MAB_DATA3':
      PIN_NUMBER='(CD72,0,0,0,0,0,0,0,0,0,0,0,0,0,0,0,0,0,0,0,0,0,0,0,0,0,0,0,0,0,0,0,0,0,0,0,0,0,0,0)';
      BIDIRECTIONAL='TRUE';
      INPUT_LOAD='(-0.01,0.01)';
      OUTPUT_LOAD='(1.0,-1.0)';
    'MAA_DQS_H7':
      PIN_NUMBER='(AA73,0,0,0,0,0,0,0,0,0,0,0,0,0,0,0,0,0,0,0,0,0,0,0,0,0,0,0,0,0,0,0,0,0,0,0,0,0,0,0)';
      BIDIRECTIONAL='TRUE';
      INPUT_LOAD='(-0.01,0.01)';
      OUTPUT_LOAD='(1.0,-1.0)';
    'MAA_DATA4':
      PIN_NUMBER='(J74,0,0,0,0,0,0,0,0,0,0,0,0,0,0,0,0,0,0,0,0,0,0,0,0,0,0,0,0,0,0,0,0,0,0,0,0,0,0,0)';
      BIDIRECTIONAL='TRUE';
      INPUT_LOAD='(-0.01,0.01)';
      OUTPUT_LOAD='(1.0,-1.0)';
    'MAA1_CS_L0':
      PIN_NUMBER='(AU74,0,0,0,0,0,0,0,0,0,0,0,0,0,0,0,0,0,0,0,0,0,0,0,0,0,0,0,0,0,0,0,0,0,0,0,0,0,0,0)';
      OUTPUT_LOAD='(1.0,-1.0)';
    'MAA0_CS_L1':
      PIN_NUMBER='(AW73,0,0,0,0,0,0,0,0,0,0,0,0,0,0,0,0,0,0,0,0,0,0,0,0,0,0,0,0,0,0,0,0,0,0,0,0,0,0,0)';
      OUTPUT_LOAD='(1.0,-1.0)';
    'MAB_DQS_L6':
      PIN_NUMBER='(CL73,0,0,0,0,0,0,0,0,0,0,0,0,0,0,0,0,0,0,0,0,0,0,0,0,0,0,0,0,0,0,0,0,0,0,0,0,0,0,0)';
      BIDIRECTIONAL='TRUE';
      INPUT_LOAD='(-0.01,0.01)';
      OUTPUT_LOAD='(1.0,-1.0)';
    'MAB_DQS_H2':
      PIN_NUMBER='(CT74,0,0,0,0,0,0,0,0,0,0,0,0,0,0,0,0,0,0,0,0,0,0,0,0,0,0,0,0,0,0,0,0,0,0,0,0,0,0,0)';
      BIDIRECTIONAL='TRUE';
      INPUT_LOAD='(-0.01,0.01)';
      OUTPUT_LOAD='(1.0,-1.0)';
    'MAB_DATA19':
      PIN_NUMBER='(CT72,0,0,0,0,0,0,0,0,0,0,0,0,0,0,0,0,0,0,0,0,0,0,0,0,0,0,0,0,0,0,0,0,0,0,0,0,0,0,0)';
      BIDIRECTIONAL='TRUE';
      INPUT_LOAD='(-0.01,0.01)';
      OUTPUT_LOAD='(1.0,-1.0)';
    'MAB_DATA4':
      PIN_NUMBER='(CF74,0,0,0,0,0,0,0,0,0,0,0,0,0,0,0,0,0,0,0,0,0,0,0,0,0,0,0,0,0,0,0,0,0,0,0,0,0,0,0)';
      BIDIRECTIONAL='TRUE';
      INPUT_LOAD='(-0.01,0.01)';
      OUTPUT_LOAD='(1.0,-1.0)';
    'MAA_DQS_H8':
      PIN_NUMBER='(AG73,0,0,0,0,0,0,0,0,0,0,0,0,0,0,0,0,0,0,0,0,0,0,0,0,0,0,0,0,0,0,0,0,0,0,0,0,0,0,0)';
      BIDIRECTIONAL='TRUE';
      INPUT_LOAD='(-0.01,0.01)';
      OUTPUT_LOAD='(1.0,-1.0)';
    'MAA_DATA30':
      PIN_NUMBER='(AH74,0,0,0,0,0,0,0,0,0,0,0,0,0,0,0,0,0,0,0,0,0,0,0,0,0,0,0,0,0,0,0,0,0,0,0,0,0,0,0)';
      BIDIRECTIONAL='TRUE';
      INPUT_LOAD='(-0.01,0.01)';
      OUTPUT_LOAD='(1.0,-1.0)';
    'MAA_DATA5':
      PIN_NUMBER='(K72,0,0,0,0,0,0,0,0,0,0,0,0,0,0,0,0,0,0,0,0,0,0,0,0,0,0,0,0,0,0,0,0,0,0,0,0,0,0,0)';
      BIDIRECTIONAL='TRUE';
      INPUT_LOAD='(-0.01,0.01)';
      OUTPUT_LOAD='(1.0,-1.0)';
    'MAA1_CS_L1':
      PIN_NUMBER='(AV72,0,0,0,0,0,0,0,0,0,0,0,0,0,0,0,0,0,0,0,0,0,0,0,0,0,0,0,0,0,0,0,0,0,0,0,0,0,0,0)';
      OUTPUT_LOAD='(1.0,-1.0)';
    'MAB_DQS_L7':
      PIN_NUMBER='(CU73,0,0,0,0,0,0,0,0,0,0,0,0,0,0,0,0,0,0,0,0,0,0,0,0,0,0,0,0,0,0,0,0,0,0,0,0,0,0,0)';
      BIDIRECTIONAL='TRUE';
      INPUT_LOAD='(-0.01,0.01)';
      OUTPUT_LOAD='(1.0,-1.0)';
    'MAB_DQS_H3':
      PIN_NUMBER='(DB74,0,0,0,0,0,0,0,0,0,0,0,0,0,0,0,0,0,0,0,0,0,0,0,0,0,0,0,0,0,0,0,0,0,0,0,0,0,0,0)';
      BIDIRECTIONAL='TRUE';
      INPUT_LOAD='(-0.01,0.01)';
      OUTPUT_LOAD='(1.0,-1.0)';
    'MAB_DATA5':
      PIN_NUMBER='(CG73,0,0,0,0,0,0,0,0,0,0,0,0,0,0,0,0,0,0,0,0,0,0,0,0,0,0,0,0,0,0,0,0,0,0,0,0,0,0,0)';
      BIDIRECTIONAL='TRUE';
      INPUT_LOAD='(-0.01,0.01)';
      OUTPUT_LOAD='(1.0,-1.0)';
    'MAA_DQS_H9':
      PIN_NUMBER='(AN73,0,0,0,0,0,0,0,0,0,0,0,0,0,0,0,0,0,0,0,0,0,0,0,0,0,0,0,0,0,0,0,0,0,0,0,0,0,0,0)';
      BIDIRECTIONAL='TRUE';
      INPUT_LOAD='(-0.01,0.01)';
      OUTPUT_LOAD='(1.0,-1.0)';
    'MAA_DATA31':
      PIN_NUMBER='(AJ73,0,0,0,0,0,0,0,0,0,0,0,0,0,0,0,0,0,0,0,0,0,0,0,0,0,0,0,0,0,0,0,0,0,0,0,0,0,0,0)';
      BIDIRECTIONAL='TRUE';
      INPUT_LOAD='(-0.01,0.01)';
      OUTPUT_LOAD='(1.0,-1.0)';
    'MAA_DATA20':
      PIN_NUMBER='(AA74,0,0,0,0,0,0,0,0,0,0,0,0,0,0,0,0,0,0,0,0,0,0,0,0,0,0,0,0,0,0,0,0,0,0,0,0,0,0,0)';
      BIDIRECTIONAL='TRUE';
      INPUT_LOAD='(-0.01,0.01)';
      OUTPUT_LOAD='(1.0,-1.0)';
    'MAA_DATA6':
      PIN_NUMBER='(K74,0,0,0,0,0,0,0,0,0,0,0,0,0,0,0,0,0,0,0,0,0,0,0,0,0,0,0,0,0,0,0,0,0,0,0,0,0,0,0)';
      BIDIRECTIONAL='TRUE';
      INPUT_LOAD='(-0.01,0.01)';
      OUTPUT_LOAD='(1.0,-1.0)';
    'MAA_CHECK0':
      PIN_NUMBER='(AJ74,0,0,0,0,0,0,0,0,0,0,0,0,0,0,0,0,0,0,0,0,0,0,0,0,0,0,0,0,0,0,0,0,0,0,0,0,0,0,0)';
      BIDIRECTIONAL='TRUE';
      INPUT_LOAD='(-0.01,0.01)';
      OUTPUT_LOAD='(1.0,-1.0)';
    'MAB_DQS_L8':
      PIN_NUMBER='(DC73,0,0,0,0,0,0,0,0,0,0,0,0,0,0,0,0,0,0,0,0,0,0,0,0,0,0,0,0,0,0,0,0,0,0,0,0,0,0,0)';
      BIDIRECTIONAL='TRUE';
      INPUT_LOAD='(-0.01,0.01)';
      OUTPUT_LOAD='(1.0,-1.0)';
    'MAB_DQS_H4':
      PIN_NUMBER='(BY72,0,0,0,0,0,0,0,0,0,0,0,0,0,0,0,0,0,0,0,0,0,0,0,0,0,0,0,0,0,0,0,0,0,0,0,0,0,0,0)';
      BIDIRECTIONAL='TRUE';
      INPUT_LOAD='(-0.01,0.01)';
      OUTPUT_LOAD='(1.0,-1.0)';
    'MAB_DATA6':
      PIN_NUMBER='(CG74,0,0,0,0,0,0,0,0,0,0,0,0,0,0,0,0,0,0,0,0,0,0,0,0,0,0,0,0,0,0,0,0,0,0,0,0,0,0,0)';
      BIDIRECTIONAL='TRUE';
      INPUT_LOAD='(-0.01,0.01)';
      OUTPUT_LOAD='(1.0,-1.0)';
    'MAA_DATA21':
      PIN_NUMBER='(AB72,0,0,0,0,0,0,0,0,0,0,0,0,0,0,0,0,0,0,0,0,0,0,0,0,0,0,0,0,0,0,0,0,0,0,0,0,0,0,0)';
      BIDIRECTIONAL='TRUE';
      INPUT_LOAD='(-0.01,0.01)';
      OUTPUT_LOAD='(1.0,-1.0)';
    'MAA_DATA10':
      PIN_NUMBER='(M74,0,0,0,0,0,0,0,0,0,0,0,0,0,0,0,0,0,0,0,0,0,0,0,0,0,0,0,0,0,0,0,0,0,0,0,0,0,0,0)';
      BIDIRECTIONAL='TRUE';
      INPUT_LOAD='(-0.01,0.01)';
      OUTPUT_LOAD='(1.0,-1.0)';
    'MAA_DATA7':
      PIN_NUMBER='(L73,0,0,0,0,0,0,0,0,0,0,0,0,0,0,0,0,0,0,0,0,0,0,0,0,0,0,0,0,0,0,0,0,0,0,0,0,0,0,0)';
      BIDIRECTIONAL='TRUE';
      INPUT_LOAD='(-0.01,0.01)';
      OUTPUT_LOAD='(1.0,-1.0)';
    'MAA_CHECK1':
      PIN_NUMBER='(AK72,0,0,0,0,0,0,0,0,0,0,0,0,0,0,0,0,0,0,0,0,0,0,0,0,0,0,0,0,0,0,0,0,0,0,0,0,0,0,0)';
      BIDIRECTIONAL='TRUE';
      INPUT_LOAD='(-0.01,0.01)';
      OUTPUT_LOAD='(1.0,-1.0)';
    'MAB_DQS_L9':
      PIN_NUMBER='(BW74,0,0,0,0,0,0,0,0,0,0,0,0,0,0,0,0,0,0,0,0,0,0,0,0,0,0,0,0,0,0,0,0,0,0,0,0,0,0,0)';
      BIDIRECTIONAL='TRUE';
      INPUT_LOAD='(-0.01,0.01)';
      OUTPUT_LOAD='(1.0,-1.0)';
    'MAB_DQS_H5':
      PIN_NUMBER='(CF72,0,0,0,0,0,0,0,0,0,0,0,0,0,0,0,0,0,0,0,0,0,0,0,0,0,0,0,0,0,0,0,0,0,0,0,0,0,0,0)';
      BIDIRECTIONAL='TRUE';
      INPUT_LOAD='(-0.01,0.01)';
      OUTPUT_LOAD='(1.0,-1.0)';
    'MAB_DATA7':
      PIN_NUMBER='(CH72,0,0,0,0,0,0,0,0,0,0,0,0,0,0,0,0,0,0,0,0,0,0,0,0,0,0,0,0,0,0,0,0,0,0,0,0,0,0,0)';
      BIDIRECTIONAL='TRUE';
      INPUT_LOAD='(-0.01,0.01)';
      OUTPUT_LOAD='(1.0,-1.0)';
    'MAA_DATA22':
      PIN_NUMBER='(AB74,0,0,0,0,0,0,0,0,0,0,0,0,0,0,0,0,0,0,0,0,0,0,0,0,0,0,0,0,0,0,0,0,0,0,0,0,0,0,0)';
      BIDIRECTIONAL='TRUE';
      INPUT_LOAD='(-0.01,0.01)';
      OUTPUT_LOAD='(1.0,-1.0)';
    'MAA_DATA11':
      PIN_NUMBER='(N73,0,0,0,0,0,0,0,0,0,0,0,0,0,0,0,0,0,0,0,0,0,0,0,0,0,0,0,0,0,0,0,0,0,0,0,0,0,0,0)';
      BIDIRECTIONAL='TRUE';
      INPUT_LOAD='(-0.01,0.01)';
      OUTPUT_LOAD='(1.0,-1.0)';
    'MAA_DATA8':
      PIN_NUMBER='(L74,0,0,0,0,0,0,0,0,0,0,0,0,0,0,0,0,0,0,0,0,0,0,0,0,0,0,0,0,0,0,0,0,0,0,0,0,0,0,0)';
      BIDIRECTIONAL='TRUE';
      INPUT_LOAD='(-0.01,0.01)';
      OUTPUT_LOAD='(1.0,-1.0)';
    'MAA_CHECK2':
      PIN_NUMBER='(AK74,0,0,0,0,0,0,0,0,0,0,0,0,0,0,0,0,0,0,0,0,0,0,0,0,0,0,0,0,0,0,0,0,0,0,0,0,0,0,0)';
      BIDIRECTIONAL='TRUE';
      INPUT_LOAD='(-0.01,0.01)';
      OUTPUT_LOAD='(1.0,-1.0)';
    'MAB_DQS_H6':
      PIN_NUMBER='(CM72,0,0,0,0,0,0,0,0,0,0,0,0,0,0,0,0,0,0,0,0,0,0,0,0,0,0,0,0,0,0,0,0,0,0,0,0,0,0,0)';
      BIDIRECTIONAL='TRUE';
      INPUT_LOAD='(-0.01,0.01)';
      OUTPUT_LOAD='(1.0,-1.0)';
    'MAB_DATA8':
      PIN_NUMBER='(CH74,0,0,0,0,0,0,0,0,0,0,0,0,0,0,0,0,0,0,0,0,0,0,0,0,0,0,0,0,0,0,0,0,0,0,0,0,0,0,0)';
      BIDIRECTIONAL='TRUE';
      INPUT_LOAD='(-0.01,0.01)';
      OUTPUT_LOAD='(1.0,-1.0)';
    'MAB0_CS_L0':
      PIN_NUMBER='(BM72,0,0,0,0,0,0,0,0,0,0,0,0,0,0,0,0,0,0,0,0,0,0,0,0,0,0,0,0,0,0,0,0,0,0,0,0,0,0,0)';
      OUTPUT_LOAD='(1.0,-1.0)';
    'MAA_DATA23':
      PIN_NUMBER='(AC73,0,0,0,0,0,0,0,0,0,0,0,0,0,0,0,0,0,0,0,0,0,0,0,0,0,0,0,0,0,0,0,0,0,0,0,0,0,0,0)';
      BIDIRECTIONAL='TRUE';
      INPUT_LOAD='(-0.01,0.01)';
      OUTPUT_LOAD='(1.0,-1.0)';
    'MAA_DATA12':
      PIN_NUMBER='(R74,0,0,0,0,0,0,0,0,0,0,0,0,0,0,0,0,0,0,0,0,0,0,0,0,0,0,0,0,0,0,0,0,0,0,0,0,0,0,0)';
      BIDIRECTIONAL='TRUE';
      INPUT_LOAD='(-0.01,0.01)';
      OUTPUT_LOAD='(1.0,-1.0)';
    'MAA_DATA9':
      PIN_NUMBER='(M72,0,0,0,0,0,0,0,0,0,0,0,0,0,0,0,0,0,0,0,0,0,0,0,0,0,0,0,0,0,0,0,0,0,0,0,0,0,0,0)';
      BIDIRECTIONAL='TRUE';
      INPUT_LOAD='(-0.01,0.01)';
      OUTPUT_LOAD='(1.0,-1.0)';
    'MAA_CHECK3':
      PIN_NUMBER='(AL73,0,0,0,0,0,0,0,0,0,0,0,0,0,0,0,0,0,0,0,0,0,0,0,0,0,0,0,0,0,0,0,0,0,0,0,0,0,0,0)';
      BIDIRECTIONAL='TRUE';
      INPUT_LOAD='(-0.01,0.01)';
      OUTPUT_LOAD='(1.0,-1.0)';
    'MAB_DQS_H7':
      PIN_NUMBER='(CV72,0,0,0,0,0,0,0,0,0,0,0,0,0,0,0,0,0,0,0,0,0,0,0,0,0,0,0,0,0,0,0,0,0,0,0,0,0,0,0)';
      BIDIRECTIONAL='TRUE';
      INPUT_LOAD='(-0.01,0.01)';
      OUTPUT_LOAD='(1.0,-1.0)';
    'MAB_DATA9':
      PIN_NUMBER='(CJ73,0,0,0,0,0,0,0,0,0,0,0,0,0,0,0,0,0,0,0,0,0,0,0,0,0,0,0,0,0,0,0,0,0,0,0,0,0,0,0)';
      BIDIRECTIONAL='TRUE';
      INPUT_LOAD='(-0.01,0.01)';
      OUTPUT_LOAD='(1.0,-1.0)';
    'MAB1_CS_L0':
      PIN_NUMBER='(BL73,0,0,0,0,0,0,0,0,0,0,0,0,0,0,0,0,0,0,0,0,0,0,0,0,0,0,0,0,0,0,0,0,0,0,0,0,0,0,0)';
      OUTPUT_LOAD='(1.0,-1.0)';
    'MAB0_CS_L1':
      PIN_NUMBER='(BN74,0,0,0,0,0,0,0,0,0,0,0,0,0,0,0,0,0,0,0,0,0,0,0,0,0,0,0,0,0,0,0,0,0,0,0,0,0,0,0)';
      OUTPUT_LOAD='(1.0,-1.0)';
    'MAA_DQS_L0':
      PIN_NUMBER='(H74,0,0,0,0,0,0,0,0,0,0,0,0,0,0,0,0,0,0,0,0,0,0,0,0,0,0,0,0,0,0,0,0,0,0,0,0,0,0,0)';
      BIDIRECTIONAL='TRUE';
      INPUT_LOAD='(-0.01,0.01)';
      OUTPUT_LOAD='(1.0,-1.0)';
    'MAA_DATA24':
      PIN_NUMBER='(AC74,0,0,0,0,0,0,0,0,0,0,0,0,0,0,0,0,0,0,0,0,0,0,0,0,0,0,0,0,0,0,0,0,0,0,0,0,0,0,0)';
      BIDIRECTIONAL='TRUE';
      INPUT_LOAD='(-0.01,0.01)';
      OUTPUT_LOAD='(1.0,-1.0)';
    'MAA_DATA13':
      PIN_NUMBER='(T72,0,0,0,0,0,0,0,0,0,0,0,0,0,0,0,0,0,0,0,0,0,0,0,0,0,0,0,0,0,0,0,0,0,0,0,0,0,0,0)';
      BIDIRECTIONAL='TRUE';
      INPUT_LOAD='(-0.01,0.01)';
      OUTPUT_LOAD='(1.0,-1.0)';
    'MAA_CHECK4':
      PIN_NUMBER='(AN74,0,0,0,0,0,0,0,0,0,0,0,0,0,0,0,0,0,0,0,0,0,0,0,0,0,0,0,0,0,0,0,0,0,0,0,0,0,0,0)';
      BIDIRECTIONAL='TRUE';
      INPUT_LOAD='(-0.01,0.01)';
      OUTPUT_LOAD='(1.0,-1.0)';
    'MAB_DQS_H8':
      PIN_NUMBER='(DD72,0,0,0,0,0,0,0,0,0,0,0,0,0,0,0,0,0,0,0,0,0,0,0,0,0,0,0,0,0,0,0,0,0,0,0,0,0,0,0)';
      BIDIRECTIONAL='TRUE';
      INPUT_LOAD='(-0.01,0.01)';
      OUTPUT_LOAD='(1.0,-1.0)';
    'MAB_DATA30':
      PIN_NUMBER='(DE74,0,0,0,0,0,0,0,0,0,0,0,0,0,0,0,0,0,0,0,0,0,0,0,0,0,0,0,0,0,0,0,0,0,0,0,0,0,0,0)';
      BIDIRECTIONAL='TRUE';
      INPUT_LOAD='(-0.01,0.01)';
      OUTPUT_LOAD='(1.0,-1.0)';
    'MAB1_CS_L1':
      PIN_NUMBER='(BM74,0,0,0,0,0,0,0,0,0,0,0,0,0,0,0,0,0,0,0,0,0,0,0,0,0,0,0,0,0,0,0,0,0,0,0,0,0,0,0)';
      OUTPUT_LOAD='(1.0,-1.0)';
    'MAA_DQS_L1':
      PIN_NUMBER='(P74,0,0,0,0,0,0,0,0,0,0,0,0,0,0,0,0,0,0,0,0,0,0,0,0,0,0,0,0,0,0,0,0,0,0,0,0,0,0,0)';
      BIDIRECTIONAL='TRUE';
      INPUT_LOAD='(-0.01,0.01)';
      OUTPUT_LOAD='(1.0,-1.0)';
    'MAA_DATA25':
      PIN_NUMBER='(AD72,0,0,0,0,0,0,0,0,0,0,0,0,0,0,0,0,0,0,0,0,0,0,0,0,0,0,0,0,0,0,0,0,0,0,0,0,0,0,0)';
      BIDIRECTIONAL='TRUE';
      INPUT_LOAD='(-0.01,0.01)';
      OUTPUT_LOAD='(1.0,-1.0)';
    'MAA_DATA14':
      PIN_NUMBER='(T74,0,0,0,0,0,0,0,0,0,0,0,0,0,0,0,0,0,0,0,0,0,0,0,0,0,0,0,0,0,0,0,0,0,0,0,0,0,0,0)';
      BIDIRECTIONAL='TRUE';
      INPUT_LOAD='(-0.01,0.01)';
      OUTPUT_LOAD='(1.0,-1.0)';
    'MAA_CHECK5':
      PIN_NUMBER='(AP72,0,0,0,0,0,0,0,0,0,0,0,0,0,0,0,0,0,0,0,0,0,0,0,0,0,0,0,0,0,0,0,0,0,0,0,0,0,0,0)';
      BIDIRECTIONAL='TRUE';
      INPUT_LOAD='(-0.01,0.01)';
      OUTPUT_LOAD='(1.0,-1.0)';
    'MAB_DATA31':
      PIN_NUMBER='(DF74,0,0,0,0,0,0,0,0,0,0,0,0,0,0,0,0,0,0,0,0,0,0,0,0,0,0,0,0,0,0,0,0,0,0,0,0,0,0,0)';
      BIDIRECTIONAL='TRUE';
      INPUT_LOAD='(-0.01,0.01)';
      OUTPUT_LOAD='(1.0,-1.0)';
    'MAB_DATA20':
      PIN_NUMBER='(CV74,0,0,0,0,0,0,0,0,0,0,0,0,0,0,0,0,0,0,0,0,0,0,0,0,0,0,0,0,0,0,0,0,0,0,0,0,0,0,0)';
      BIDIRECTIONAL='TRUE';
      INPUT_LOAD='(-0.01,0.01)';
      OUTPUT_LOAD='(1.0,-1.0)';
    'MAB_CHECK0':
      PIN_NUMBER='(BY74,0,0,0,0,0,0,0,0,0,0,0,0,0,0,0,0,0,0,0,0,0,0,0,0,0,0,0,0,0,0,0,0,0,0,0,0,0,0,0)';
      BIDIRECTIONAL='TRUE';
      INPUT_LOAD='(-0.01,0.01)';
      OUTPUT_LOAD='(1.0,-1.0)';
    'MAA_DQS_L2':
      PIN_NUMBER='(Y74,0,0,0,0,0,0,0,0,0,0,0,0,0,0,0,0,0,0,0,0,0,0,0,0,0,0,0,0,0,0,0,0,0,0,0,0,0,0,0)';
      BIDIRECTIONAL='TRUE';
      INPUT_LOAD='(-0.01,0.01)';
      OUTPUT_LOAD='(1.0,-1.0)';
    'MAA_DATA26':
      PIN_NUMBER='(AD74,0,0,0,0,0,0,0,0,0,0,0,0,0,0,0,0,0,0,0,0,0,0,0,0,0,0,0,0,0,0,0,0,0,0,0,0,0,0,0)';
      BIDIRECTIONAL='TRUE';
      INPUT_LOAD='(-0.01,0.01)';
      OUTPUT_LOAD='(1.0,-1.0)';
    'MAA_DATA15':
      PIN_NUMBER='(U73,0,0,0,0,0,0,0,0,0,0,0,0,0,0,0,0,0,0,0,0,0,0,0,0,0,0,0,0,0,0,0,0,0,0,0,0,0,0,0)';
      BIDIRECTIONAL='TRUE';
      INPUT_LOAD='(-0.01,0.01)';
      OUTPUT_LOAD='(1.0,-1.0)';
    'MAA_CHECK6':
      PIN_NUMBER='(AP74,0,0,0,0,0,0,0,0,0,0,0,0,0,0,0,0,0,0,0,0,0,0,0,0,0,0,0,0,0,0,0,0,0,0,0,0,0,0,0)';
      BIDIRECTIONAL='TRUE';
      INPUT_LOAD='(-0.01,0.01)';
      OUTPUT_LOAD='(1.0,-1.0)';
    'MAA0_RSP_L':
      PIN_NUMBER='(BN73,0,0,0,0,0,0,0,0,0,0,0,0,0,0,0,0,0,0,0,0,0,0,0,0,0,0,0,0,0,0,0,0,0,0,0,0,0,0,0)';
      INPUT_LOAD='(-0.01,0.01)';
    'MAB_DATA21':
      PIN_NUMBER='(CW73,0,0,0,0,0,0,0,0,0,0,0,0,0,0,0,0,0,0,0,0,0,0,0,0,0,0,0,0,0,0,0,0,0,0,0,0,0,0,0)';
      BIDIRECTIONAL='TRUE';
      INPUT_LOAD='(-0.01,0.01)';
      OUTPUT_LOAD='(1.0,-1.0)';
    'MAB_DATA10':
      PIN_NUMBER='(CJ74,0,0,0,0,0,0,0,0,0,0,0,0,0,0,0,0,0,0,0,0,0,0,0,0,0,0,0,0,0,0,0,0,0,0,0,0,0,0,0)';
      BIDIRECTIONAL='TRUE';
      INPUT_LOAD='(-0.01,0.01)';
      OUTPUT_LOAD='(1.0,-1.0)';
    'MAB_CHECK1':
      PIN_NUMBER='(CA73,0,0,0,0,0,0,0,0,0,0,0,0,0,0,0,0,0,0,0,0,0,0,0,0,0,0,0,0,0,0,0,0,0,0,0,0,0,0,0)';
      BIDIRECTIONAL='TRUE';
      INPUT_LOAD='(-0.01,0.01)';
      OUTPUT_LOAD='(1.0,-1.0)';
    'MAA_DQS_L3':
      PIN_NUMBER='(AF74,0,0,0,0,0,0,0,0,0,0,0,0,0,0,0,0,0,0,0,0,0,0,0,0,0,0,0,0,0,0,0,0,0,0,0,0,0,0,0)';
      BIDIRECTIONAL='TRUE';
      INPUT_LOAD='(-0.01,0.01)';
      OUTPUT_LOAD='(1.0,-1.0)';
    'MAA_DATA27':
      PIN_NUMBER='(AE73,0,0,0,0,0,0,0,0,0,0,0,0,0,0,0,0,0,0,0,0,0,0,0,0,0,0,0,0,0,0,0,0,0,0,0,0,0,0,0)';
      BIDIRECTIONAL='TRUE';
      INPUT_LOAD='(-0.01,0.01)';
      OUTPUT_LOAD='(1.0,-1.0)';
    'MAA_DATA16':
      PIN_NUMBER='(U74,0,0,0,0,0,0,0,0,0,0,0,0,0,0,0,0,0,0,0,0,0,0,0,0,0,0,0,0,0,0,0,0,0,0,0,0,0,0,0)';
      BIDIRECTIONAL='TRUE';
      INPUT_LOAD='(-0.01,0.01)';
      OUTPUT_LOAD='(1.0,-1.0)';
    'MAA_CHECK7':
      PIN_NUMBER='(AR73,0,0,0,0,0,0,0,0,0,0,0,0,0,0,0,0,0,0,0,0,0,0,0,0,0,0,0,0,0,0,0,0,0,0,0,0,0,0,0)';
      BIDIRECTIONAL='TRUE';
      INPUT_LOAD='(-0.01,0.01)';
      OUTPUT_LOAD='(1.0,-1.0)';
    'MAA_CA0':
      PIN_NUMBER='(AW74,0,0,0,0,0,0,0,0,0,0,0,0,0,0,0,0,0,0,0,0,0,0,0,0,0,0,0,0,0,0,0,0,0,0,0,0,0,0,0)';
      OUTPUT_LOAD='(1.0,-1.0)';
    'MAA1_RSP_L':
      PIN_NUMBER='(BP72,0,0,0,0,0,0,0,0,0,0,0,0,0,0,0,0,0,0,0,0,0,0,0,0,0,0,0,0,0,0,0,0,0,0,0,0,0,0,0)';
      INPUT_LOAD='(-0.01,0.01)';
    'MAB_DATA22':
      PIN_NUMBER='(CW74,0,0,0,0,0,0,0,0,0,0,0,0,0,0,0,0,0,0,0,0,0,0,0,0,0,0,0,0,0,0,0,0,0,0,0,0,0,0,0)';
      BIDIRECTIONAL='TRUE';
      INPUT_LOAD='(-0.01,0.01)';
      OUTPUT_LOAD='(1.0,-1.0)';
    'MAB_DATA11':
      PIN_NUMBER='(CK72,0,0,0,0,0,0,0,0,0,0,0,0,0,0,0,0,0,0,0,0,0,0,0,0,0,0,0,0,0,0,0,0,0,0,0,0,0,0,0)';
      BIDIRECTIONAL='TRUE';
      INPUT_LOAD='(-0.01,0.01)';
      OUTPUT_LOAD='(1.0,-1.0)';
    'MAB_CHECK2':
      PIN_NUMBER='(CA74,0,0,0,0,0,0,0,0,0,0,0,0,0,0,0,0,0,0,0,0,0,0,0,0,0,0,0,0,0,0,0,0,0,0,0,0,0,0,0)';
      BIDIRECTIONAL='TRUE';
      INPUT_LOAD='(-0.01,0.01)';
      OUTPUT_LOAD='(1.0,-1.0)';
    'MAB_CA0':
      PIN_NUMBER='(BG73,0,0,0,0,0,0,0,0,0,0,0,0,0,0,0,0,0,0,0,0,0,0,0,0,0,0,0,0,0,0,0,0,0,0,0,0,0,0,0)';
      OUTPUT_LOAD='(1.0,-1.0)';
    'MAA_DQS_L4':
      PIN_NUMBER='(AM74,0,0,0,0,0,0,0,0,0,0,0,0,0,0,0,0,0,0,0,0,0,0,0,0,0,0,0,0,0,0,0,0,0,0,0,0,0,0,0)';
      BIDIRECTIONAL='TRUE';
      INPUT_LOAD='(-0.01,0.01)';
      OUTPUT_LOAD='(1.0,-1.0)';
    'MAA_DQS_H0':
      PIN_NUMBER='(G74,0,0,0,0,0,0,0,0,0,0,0,0,0,0,0,0,0,0,0,0,0,0,0,0,0,0,0,0,0,0,0,0,0,0,0,0,0,0,0)';
      BIDIRECTIONAL='TRUE';
      INPUT_LOAD='(-0.01,0.01)';
      OUTPUT_LOAD='(1.0,-1.0)';
    'MAA_DATA28':
      PIN_NUMBER='(AG74,0,0,0,0,0,0,0,0,0,0,0,0,0,0,0,0,0,0,0,0,0,0,0,0,0,0,0,0,0,0,0,0,0,0,0,0,0,0,0)';
      BIDIRECTIONAL='TRUE';
      INPUT_LOAD='(-0.01,0.01)';
      OUTPUT_LOAD='(1.0,-1.0)';
    'MAA_DATA17':
      PIN_NUMBER='(V72,0,0,0,0,0,0,0,0,0,0,0,0,0,0,0,0,0,0,0,0,0,0,0,0,0,0,0,0,0,0,0,0,0,0,0,0,0,0,0)';
      BIDIRECTIONAL='TRUE';
      INPUT_LOAD='(-0.01,0.01)';
      OUTPUT_LOAD='(1.0,-1.0)';
    'MAA_CA1':
      PIN_NUMBER='(AY74,0,0,0,0,0,0,0,0,0,0,0,0,0,0,0,0,0,0,0,0,0,0,0,0,0,0,0,0,0,0,0,0,0,0,0,0,0,0,0)';
      OUTPUT_LOAD='(1.0,-1.0)';
    'MAB_DATA23':
      PIN_NUMBER='(CY72,0,0,0,0,0,0,0,0,0,0,0,0,0,0,0,0,0,0,0,0,0,0,0,0,0,0,0,0,0,0,0,0,0,0,0,0,0,0,0)';
      BIDIRECTIONAL='TRUE';
      INPUT_LOAD='(-0.01,0.01)';
      OUTPUT_LOAD='(1.0,-1.0)';
    'MAB_DATA12':
      PIN_NUMBER='(CM74,0,0,0,0,0,0,0,0,0,0,0,0,0,0,0,0,0,0,0,0,0,0,0,0,0,0,0,0,0,0,0,0,0,0,0,0,0,0,0)';
      BIDIRECTIONAL='TRUE';
      INPUT_LOAD='(-0.01,0.01)';
      OUTPUT_LOAD='(1.0,-1.0)';
    'MAB_CHECK3':
      PIN_NUMBER='(CB72,0,0,0,0,0,0,0,0,0,0,0,0,0,0,0,0,0,0,0,0,0,0,0,0,0,0,0,0,0,0,0,0,0,0,0,0,0,0,0)';
      BIDIRECTIONAL='TRUE';
      INPUT_LOAD='(-0.01,0.01)';
      OUTPUT_LOAD='(1.0,-1.0)';
    'MAB_CA1':
      PIN_NUMBER='(BH72,0,0,0,0,0,0,0,0,0,0,0,0,0,0,0,0,0,0,0,0,0,0,0,0,0,0,0,0,0,0,0,0,0,0,0,0,0,0,0)';
      OUTPUT_LOAD='(1.0,-1.0)';
    'MAA_DQS_L5':
      PIN_NUMBER='(H72,0,0,0,0,0,0,0,0,0,0,0,0,0,0,0,0,0,0,0,0,0,0,0,0,0,0,0,0,0,0,0,0,0,0,0,0,0,0,0)';
      BIDIRECTIONAL='TRUE';
      INPUT_LOAD='(-0.01,0.01)';
      OUTPUT_LOAD='(1.0,-1.0)';
    'MAA_DQS_H1':
      PIN_NUMBER='(N74,0,0,0,0,0,0,0,0,0,0,0,0,0,0,0,0,0,0,0,0,0,0,0,0,0,0,0,0,0,0,0,0,0,0,0,0,0,0,0)';
      BIDIRECTIONAL='TRUE';
      INPUT_LOAD='(-0.01,0.01)';
      OUTPUT_LOAD='(1.0,-1.0)';
    'MAA_DATA29':
      PIN_NUMBER='(AH72,0,0,0,0,0,0,0,0,0,0,0,0,0,0,0,0,0,0,0,0,0,0,0,0,0,0,0,0,0,0,0,0,0,0,0,0,0,0,0)';
      BIDIRECTIONAL='TRUE';
      INPUT_LOAD='(-0.01,0.01)';
      OUTPUT_LOAD='(1.0,-1.0)';
    'MAA_DATA18':
      PIN_NUMBER='(V74,0,0,0,0,0,0,0,0,0,0,0,0,0,0,0,0,0,0,0,0,0,0,0,0,0,0,0,0,0,0,0,0,0,0,0,0,0,0,0)';
      BIDIRECTIONAL='TRUE';
      INPUT_LOAD='(-0.01,0.01)';
      OUTPUT_LOAD='(1.0,-1.0)';
    'MAA_CA2':
      PIN_NUMBER='(AY72,0,0,0,0,0,0,0,0,0,0,0,0,0,0,0,0,0,0,0,0,0,0,0,0,0,0,0,0,0,0,0,0,0,0,0,0,0,0,0)';
      OUTPUT_LOAD='(1.0,-1.0)';
    'MAB_DQS_L0':
      PIN_NUMBER='(CE74,0,0,0,0,0,0,0,0,0,0,0,0,0,0,0,0,0,0,0,0,0,0,0,0,0,0,0,0,0,0,0,0,0,0,0,0,0,0,0)';
      BIDIRECTIONAL='TRUE';
      INPUT_LOAD='(-0.01,0.01)';
      OUTPUT_LOAD='(1.0,-1.0)';
    'MAB_DATA24':
      PIN_NUMBER='(CY74,0,0,0,0,0,0,0,0,0,0,0,0,0,0,0,0,0,0,0,0,0,0,0,0,0,0,0,0,0,0,0,0,0,0,0,0,0,0,0)';
      BIDIRECTIONAL='TRUE';
      INPUT_LOAD='(-0.01,0.01)';
      OUTPUT_LOAD='(1.0,-1.0)';
    'MAB_DATA13':
      PIN_NUMBER='(CN73,0,0,0,0,0,0,0,0,0,0,0,0,0,0,0,0,0,0,0,0,0,0,0,0,0,0,0,0,0,0,0,0,0,0,0,0,0,0,0)';
      BIDIRECTIONAL='TRUE';
      INPUT_LOAD='(-0.01,0.01)';
      OUTPUT_LOAD='(1.0,-1.0)';
    'MAB_CHECK4':
      PIN_NUMBER='(BT74,0,0,0,0,0,0,0,0,0,0,0,0,0,0,0,0,0,0,0,0,0,0,0,0,0,0,0,0,0,0,0,0,0,0,0,0,0,0,0)';
      BIDIRECTIONAL='TRUE';
      INPUT_LOAD='(-0.01,0.01)';
      OUTPUT_LOAD='(1.0,-1.0)';
    'MAB_CA2':
      PIN_NUMBER='(BH74,0,0,0,0,0,0,0,0,0,0,0,0,0,0,0,0,0,0,0,0,0,0,0,0,0,0,0,0,0,0,0,0,0,0,0,0,0,0,0)';
      OUTPUT_LOAD='(1.0,-1.0)';
    'MAA_DQS_L6':
      PIN_NUMBER='(P72,0,0,0,0,0,0,0,0,0,0,0,0,0,0,0,0,0,0,0,0,0,0,0,0,0,0,0,0,0,0,0,0,0,0,0,0,0,0,0)';
      BIDIRECTIONAL='TRUE';
      INPUT_LOAD='(-0.01,0.01)';
      OUTPUT_LOAD='(1.0,-1.0)';
    'MAA_DQS_H2':
      PIN_NUMBER='(W74,0,0,0,0,0,0,0,0,0,0,0,0,0,0,0,0,0,0,0,0,0,0,0,0,0,0,0,0,0,0,0,0,0,0,0,0,0,0,0)';
      BIDIRECTIONAL='TRUE';
      INPUT_LOAD='(-0.01,0.01)';
      OUTPUT_LOAD='(1.0,-1.0)';
    'MAA_DATA19':
      PIN_NUMBER='(W73,0,0,0,0,0,0,0,0,0,0,0,0,0,0,0,0,0,0,0,0,0,0,0,0,0,0,0,0,0,0,0,0,0,0,0,0,0,0,0)';
      BIDIRECTIONAL='TRUE';
      INPUT_LOAD='(-0.01,0.01)';
      OUTPUT_LOAD='(1.0,-1.0)';
    'MAA_CA3':
      PIN_NUMBER='(BA73,0,0,0,0,0,0,0,0,0,0,0,0,0,0,0,0,0,0,0,0,0,0,0,0,0,0,0,0,0,0,0,0,0,0,0,0,0,0,0)';
      OUTPUT_LOAD='(1.0,-1.0)';
    'MAB_DQS_L1':
      PIN_NUMBER='(CL74,0,0,0,0,0,0,0,0,0,0,0,0,0,0,0,0,0,0,0,0,0,0,0,0,0,0,0,0,0,0,0,0,0,0,0,0,0,0,0)';
      BIDIRECTIONAL='TRUE';
      INPUT_LOAD='(-0.01,0.01)';
      OUTPUT_LOAD='(1.0,-1.0)';
    'MAB_DATA25':
      PIN_NUMBER='(DA73,0,0,0,0,0,0,0,0,0,0,0,0,0,0,0,0,0,0,0,0,0,0,0,0,0,0,0,0,0,0,0,0,0,0,0,0,0,0,0)';
      BIDIRECTIONAL='TRUE';
      INPUT_LOAD='(-0.01,0.01)';
      OUTPUT_LOAD='(1.0,-1.0)';
    'MAB_DATA14':
      PIN_NUMBER='(CN74,0,0,0,0,0,0,0,0,0,0,0,0,0,0,0,0,0,0,0,0,0,0,0,0,0,0,0,0,0,0,0,0,0,0,0,0,0,0,0)';
      BIDIRECTIONAL='TRUE';
      INPUT_LOAD='(-0.01,0.01)';
      OUTPUT_LOAD='(1.0,-1.0)';
    'MAB_CHECK5':
      PIN_NUMBER='(BU73,0,0,0,0,0,0,0,0,0,0,0,0,0,0,0,0,0,0,0,0,0,0,0,0,0,0,0,0,0,0,0,0,0,0,0,0,0,0,0)';
      BIDIRECTIONAL='TRUE';
      INPUT_LOAD='(-0.01,0.01)';
      OUTPUT_LOAD='(1.0,-1.0)';
    'MAB_CA3':
      PIN_NUMBER='(BJ74,0,0,0,0,0,0,0,0,0,0,0,0,0,0,0,0,0,0,0,0,0,0,0,0,0,0,0,0,0,0,0,0,0,0,0,0,0,0,0)';
      OUTPUT_LOAD='(1.0,-1.0)';
    'MAA_DQS_L7':
      PIN_NUMBER='(Y72,0,0,0,0,0,0,0,0,0,0,0,0,0,0,0,0,0,0,0,0,0,0,0,0,0,0,0,0,0,0,0,0,0,0,0,0,0,0,0)';
      BIDIRECTIONAL='TRUE';
      INPUT_LOAD='(-0.01,0.01)';
      OUTPUT_LOAD='(1.0,-1.0)';
    'MAA_DQS_H3':
      PIN_NUMBER='(AE74,0,0,0,0,0,0,0,0,0,0,0,0,0,0,0,0,0,0,0,0,0,0,0,0,0,0,0,0,0,0,0,0,0,0,0,0,0,0,0)';
      BIDIRECTIONAL='TRUE';
      INPUT_LOAD='(-0.01,0.01)';
      OUTPUT_LOAD='(1.0,-1.0)';
    'MAA_DATA0':
      PIN_NUMBER='(E74,0,0,0,0,0,0,0,0,0,0,0,0,0,0,0,0,0,0,0,0,0,0,0,0,0,0,0,0,0,0,0,0,0,0,0,0,0,0,0)';
      BIDIRECTIONAL='TRUE';
      INPUT_LOAD='(-0.01,0.01)';
      OUTPUT_LOAD='(1.0,-1.0)';
    'MAA_CA4':
      PIN_NUMBER='(BA74,0,0,0,0,0,0,0,0,0,0,0,0,0,0,0,0,0,0,0,0,0,0,0,0,0,0,0,0,0,0,0,0,0,0,0,0,0,0,0)';
      OUTPUT_LOAD='(1.0,-1.0)';
    'MAB_DQS_L2':
      PIN_NUMBER='(CU74,0,0,0,0,0,0,0,0,0,0,0,0,0,0,0,0,0,0,0,0,0,0,0,0,0,0,0,0,0,0,0,0,0,0,0,0,0,0,0)';
      BIDIRECTIONAL='TRUE';
      INPUT_LOAD='(-0.01,0.01)';
      OUTPUT_LOAD='(1.0,-1.0)';
    'MAB_DATA26':
      PIN_NUMBER='(DA74,0,0,0,0,0,0,0,0,0,0,0,0,0,0,0,0,0,0,0,0,0,0,0,0,0,0,0,0,0,0,0,0,0,0,0,0,0,0,0)';
      BIDIRECTIONAL='TRUE';
      INPUT_LOAD='(-0.01,0.01)';
      OUTPUT_LOAD='(1.0,-1.0)';
    'MAB_DATA15':
      PIN_NUMBER='(CP72,0,0,0,0,0,0,0,0,0,0,0,0,0,0,0,0,0,0,0,0,0,0,0,0,0,0,0,0,0,0,0,0,0,0,0,0,0,0,0)';
      BIDIRECTIONAL='TRUE';
      INPUT_LOAD='(-0.01,0.01)';
      OUTPUT_LOAD='(1.0,-1.0)';
    'MAB_DATA0':
      PIN_NUMBER='(CB74,0,0,0,0,0,0,0,0,0,0,0,0,0,0,0,0,0,0,0,0,0,0,0,0,0,0,0,0,0,0,0,0,0,0,0,0,0,0,0)';
      BIDIRECTIONAL='TRUE';
      INPUT_LOAD='(-0.01,0.01)';
      OUTPUT_LOAD='(1.0,-1.0)';
    'MAB_CHECK6':
      PIN_NUMBER='(BU74,0,0,0,0,0,0,0,0,0,0,0,0,0,0,0,0,0,0,0,0,0,0,0,0,0,0,0,0,0,0,0,0,0,0,0,0,0,0,0)';
      BIDIRECTIONAL='TRUE';
      INPUT_LOAD='(-0.01,0.01)';
      OUTPUT_LOAD='(1.0,-1.0)';
    'MAB_CA4':
      PIN_NUMBER='(BJ73,0,0,0,0,0,0,0,0,0,0,0,0,0,0,0,0,0,0,0,0,0,0,0,0,0,0,0,0,0,0,0,0,0,0,0,0,0,0,0)';
      OUTPUT_LOAD='(1.0,-1.0)';
    'MAB0_RSP_L':
      PIN_NUMBER='(BP74,0,0,0,0,0,0,0,0,0,0,0,0,0,0,0,0,0,0,0,0,0,0,0,0,0,0,0,0,0,0,0,0,0,0,0,0,0,0,0)';
      INPUT_LOAD='(-0.01,0.01)';
    'MAA_DQS_L8':
      PIN_NUMBER='(AF72,0,0,0,0,0,0,0,0,0,0,0,0,0,0,0,0,0,0,0,0,0,0,0,0,0,0,0,0,0,0,0,0,0,0,0,0,0,0,0)';
      BIDIRECTIONAL='TRUE';
      INPUT_LOAD='(-0.01,0.01)';
      OUTPUT_LOAD='(1.0,-1.0)';
    'MAA_DQS_H4':
      PIN_NUMBER='(AL74,0,0,0,0,0,0,0,0,0,0,0,0,0,0,0,0,0,0,0,0,0,0,0,0,0,0,0,0,0,0,0,0,0,0,0,0,0,0,0)';
      BIDIRECTIONAL='TRUE';
      INPUT_LOAD='(-0.01,0.01)';
      OUTPUT_LOAD='(1.0,-1.0)';
    'MAA_DATA1':
      PIN_NUMBER='(F72,0,0,0,0,0,0,0,0,0,0,0,0,0,0,0,0,0,0,0,0,0,0,0,0,0,0,0,0,0,0,0,0,0,0,0,0,0,0,0)';
      BIDIRECTIONAL='TRUE';
      INPUT_LOAD='(-0.01,0.01)';
      OUTPUT_LOAD='(1.0,-1.0)';
    'MAA_CA5':
      PIN_NUMBER='(BB74,0,0,0,0,0,0,0,0,0,0,0,0,0,0,0,0,0,0,0,0,0,0,0,0,0,0,0,0,0,0,0,0,0,0,0,0,0,0,0)';
      OUTPUT_LOAD='(1.0,-1.0)';
    'MAB_DQS_L3':
      PIN_NUMBER='(DC74,0,0,0,0,0,0,0,0,0,0,0,0,0,0,0,0,0,0,0,0,0,0,0,0,0,0,0,0,0,0,0,0,0,0,0,0,0,0,0)';
      BIDIRECTIONAL='TRUE';
      INPUT_LOAD='(-0.01,0.01)';
      OUTPUT_LOAD='(1.0,-1.0)';
    'MAB_DATA27':
      PIN_NUMBER='(DB72,0,0,0,0,0,0,0,0,0,0,0,0,0,0,0,0,0,0,0,0,0,0,0,0,0,0,0,0,0,0,0,0,0,0,0,0,0,0,0)';
      BIDIRECTIONAL='TRUE';
      INPUT_LOAD='(-0.01,0.01)';
      OUTPUT_LOAD='(1.0,-1.0)';
    'MAB_DATA16':
      PIN_NUMBER='(CP74,0,0,0,0,0,0,0,0,0,0,0,0,0,0,0,0,0,0,0,0,0,0,0,0,0,0,0,0,0,0,0,0,0,0,0,0,0,0,0)';
      BIDIRECTIONAL='TRUE';
      INPUT_LOAD='(-0.01,0.01)';
      OUTPUT_LOAD='(1.0,-1.0)';
    'MAB_DATA1':
      PIN_NUMBER='(CC73,0,0,0,0,0,0,0,0,0,0,0,0,0,0,0,0,0,0,0,0,0,0,0,0,0,0,0,0,0,0,0,0,0,0,0,0,0,0,0)';
      BIDIRECTIONAL='TRUE';
      INPUT_LOAD='(-0.01,0.01)';
      OUTPUT_LOAD='(1.0,-1.0)';
    'MAB_CHECK7':
      PIN_NUMBER='(BV72,0,0,0,0,0,0,0,0,0,0,0,0,0,0,0,0,0,0,0,0,0,0,0,0,0,0,0,0,0,0,0,0,0,0,0,0,0,0,0)';
      BIDIRECTIONAL='TRUE';
      INPUT_LOAD='(-0.01,0.01)';
      OUTPUT_LOAD='(1.0,-1.0)';
    'MAB_CA5':
      PIN_NUMBER='(BK72,0,0,0,0,0,0,0,0,0,0,0,0,0,0,0,0,0,0,0,0,0,0,0,0,0,0,0,0,0,0,0,0,0,0,0,0,0,0,0)';
      OUTPUT_LOAD='(1.0,-1.0)';
    'MAB1_RSP_L':
      PIN_NUMBER='(BR74,0,0,0,0,0,0,0,0,0,0,0,0,0,0,0,0,0,0,0,0,0,0,0,0,0,0,0,0,0,0,0,0,0,0,0,0,0,0,0)';
      INPUT_LOAD='(-0.01,0.01)';
    'MAA_DQS_L9':
      PIN_NUMBER='(AM72,0,0,0,0,0,0,0,0,0,0,0,0,0,0,0,0,0,0,0,0,0,0,0,0,0,0,0,0,0,0,0,0,0,0,0,0,0,0,0)';
      BIDIRECTIONAL='TRUE';
      INPUT_LOAD='(-0.01,0.01)';
      OUTPUT_LOAD='(1.0,-1.0)';
    'MAA_DQS_H5':
      PIN_NUMBER='(J73,0,0,0,0,0,0,0,0,0,0,0,0,0,0,0,0,0,0,0,0,0,0,0,0,0,0,0,0,0,0,0,0,0,0,0,0,0,0,0)';
      BIDIRECTIONAL='TRUE';
      INPUT_LOAD='(-0.01,0.01)';
      OUTPUT_LOAD='(1.0,-1.0)';
    'MAA_DATA2':
      PIN_NUMBER='(F74,0,0,0,0,0,0,0,0,0,0,0,0,0,0,0,0,0,0,0,0,0,0,0,0,0,0,0,0,0,0,0,0,0,0,0,0,0,0,0)';
      BIDIRECTIONAL='TRUE';
      INPUT_LOAD='(-0.01,0.01)';
      OUTPUT_LOAD='(1.0,-1.0)';
    'MAA_CA6':
      PIN_NUMBER='(BB72,0,0,0,0,0,0,0,0,0,0,0,0,0,0,0,0,0,0,0,0,0,0,0,0,0,0,0,0,0,0,0,0,0,0,0,0,0,0,0)';
      OUTPUT_LOAD='(1.0,-1.0)';
    'MAB_DQS_L4':
      PIN_NUMBER='(BW73,0,0,0,0,0,0,0,0,0,0,0,0,0,0,0,0,0,0,0,0,0,0,0,0,0,0,0,0,0,0,0,0,0,0,0,0,0,0,0)';
      BIDIRECTIONAL='TRUE';
      INPUT_LOAD='(-0.01,0.01)';
      OUTPUT_LOAD='(1.0,-1.0)';
    'MAB_DQS_H0':
      PIN_NUMBER='(CD74,0,0,0,0,0,0,0,0,0,0,0,0,0,0,0,0,0,0,0,0,0,0,0,0,0,0,0,0,0,0,0,0,0,0,0,0,0,0,0)';
      BIDIRECTIONAL='TRUE';
      INPUT_LOAD='(-0.01,0.01)';
      OUTPUT_LOAD='(1.0,-1.0)';
    'MAB_DATA28':
      PIN_NUMBER='(DD74,0,0,0,0,0,0,0,0,0,0,0,0,0,0,0,0,0,0,0,0,0,0,0,0,0,0,0,0,0,0,0,0,0,0,0,0,0,0,0)';
      BIDIRECTIONAL='TRUE';
      INPUT_LOAD='(-0.01,0.01)';
      OUTPUT_LOAD='(1.0,-1.0)';
    'MAB_DATA17':
      PIN_NUMBER='(CR73,0,0,0,0,0,0,0,0,0,0,0,0,0,0,0,0,0,0,0,0,0,0,0,0,0,0,0,0,0,0,0,0,0,0,0,0,0,0,0)';
      BIDIRECTIONAL='TRUE';
      INPUT_LOAD='(-0.01,0.01)';
      OUTPUT_LOAD='(1.0,-1.0)';
    'MAB_DATA2':
      PIN_NUMBER='(CC74,0,0,0,0,0,0,0,0,0,0,0,0,0,0,0,0,0,0,0,0,0,0,0,0,0,0,0,0,0,0,0,0,0,0,0,0,0,0,0)';
      BIDIRECTIONAL='TRUE';
      INPUT_LOAD='(-0.01,0.01)';
      OUTPUT_LOAD='(1.0,-1.0)';
    'MAB_CA6':
      PIN_NUMBER='(BK74,0,0,0,0,0,0,0,0,0,0,0,0,0,0,0,0,0,0,0,0,0,0,0,0,0,0,0,0,0,0,0,0,0,0,0,0,0,0,0)';
      OUTPUT_LOAD='(1.0,-1.0)';
    'MAA_DQS_H6':
      PIN_NUMBER='(R73,0,0,0,0,0,0,0,0,0,0,0,0,0,0,0,0,0,0,0,0,0,0,0,0,0,0,0,0,0,0,0,0,0,0,0,0,0,0,0)';
      BIDIRECTIONAL='TRUE';
      INPUT_LOAD='(-0.01,0.01)';
      OUTPUT_LOAD='(1.0,-1.0)';
    'MAA_DATA3':
      PIN_NUMBER='(G73,0,0,0,0,0,0,0,0,0,0,0,0,0,0,0,0,0,0,0,0,0,0,0,0,0,0,0,0,0,0,0,0,0,0,0,0,0,0,0)';
      BIDIRECTIONAL='TRUE';
      INPUT_LOAD='(-0.01,0.01)';
      OUTPUT_LOAD='(1.0,-1.0)';
    'MAA0_CS_L0':
      PIN_NUMBER='(AV74,0,0,0,0,0,0,0,0,0,0,0,0,0,0,0,0,0,0,0,0,0,0,0,0,0,0,0,0,0,0,0,0,0,0,0,0,0,0,0)';
      OUTPUT_LOAD='(1.0,-1.0)';
    'MAA_PAR':
      PIN_NUMBER='(BC73,0,0,0,0,0,0,0,0,0,0,0,0,0,0,0,0,0,0,0,0,0,0,0,0,0,0,0,0,0,0,0,0,0,0,0,0,0,0,0)';
      OUTPUT_LOAD='(1.0,-1.0)';
    'MAB_PAR':
      PIN_NUMBER='(BL74,0,0,0,0,0,0,0,0,0,0,0,0,0,0,0,0,0,0,0,0,0,0,0,0,0,0,0,0,0,0,0,0,0,0,0,0,0,0,0)';
      OUTPUT_LOAD='(1.0,-1.0)';
    'MA0_CLK_H':
      PIN_NUMBER='(BC74,0,0,0,0,0,0,0,0,0,0,0,0,0,0,0,0,0,0,0,0,0,0,0,0,0,0,0,0,0,0,0,0,0,0,0,0,0,0,0)';
      OUTPUT_LOAD='(1.0,-1.0)';
    'MAB_DQS_H9':
      PIN_NUMBER='(BV74,0,0,0,0,0,0,0,0,0,0,0,0,0,0,0,0,0,0,0,0,0,0,0,0,0,0,0,0,0,0,0,0,0,0,0,0,0,0,0)';
      BIDIRECTIONAL='TRUE';
      INPUT_LOAD='(-0.01,0.01)';
      OUTPUT_LOAD='(1.0,-1.0)';
    'MA1_CLK_H':
      PIN_NUMBER='(BF74,0,0,0,0,0,0,0,0,0,0,0,0,0,0,0,0,0,0,0,0,0,0,0,0,0,0,0,0,0,0,0,0,0,0,0,0,0,0,0)';
      OUTPUT_LOAD='(1.0,-1.0)';
    'MA0_CLK_L':
      PIN_NUMBER='(BD74,0,0,0,0,0,0,0,0,0,0,0,0,0,0,0,0,0,0,0,0,0,0,0,0,0,0,0,0,0,0,0,0,0,0,0,0,0,0,0)';
      OUTPUT_LOAD='(1.0,-1.0)';
    'MA1_CLK_L':
      PIN_NUMBER='(BG74,0,0,0,0,0,0,0,0,0,0,0,0,0,0,0,0,0,0,0,0,0,0,0,0,0,0,0,0,0,0,0,0,0,0,0,0,0,0,0)';
      OUTPUT_LOAD='(1.0,-1.0)';
    'TEST39A':
      PIN_NUMBER='(BF72,0,0,0,0,0,0,0,0,0,0,0,0,0,0,0,0,0,0,0,0,0,0,0,0,0,0,0,0,0,0,0,0,0,0,0,0,0,0,0)';
      OUTPUT_LOAD='(1.0,-1.0)';
    'TEST40':
      PIN_NUMBER='(C60,0,0,0,0,0,0,0,0,0,0,0,0,0,0,0,0,0,0,0,0,0,0,0,0,0,0,0,0,0,0,0,0,0,0,0,0,0,0,0)';
      OUTPUT_LOAD='(1.0,-1.0)';
    'MB_ALERT_L':
      PIN_NUMBER='(0,AT62,0,0,0,0,0,0,0,0,0,0,0,0,0,0,0,0,0,0,0,0,0,0,0,0,0,0,0,0,0,0,0,0,0,0,0,0,0,0)';
      INPUT_LOAD='(-0.01,0.01)';
    'MB_RESET_L':
      PIN_NUMBER='(0,AU62,0,0,0,0,0,0,0,0,0,0,0,0,0,0,0,0,0,0,0,0,0,0,0,0,0,0,0,0,0,0,0,0,0,0,0,0,0,0)';
      OUTPUT_LOAD='(1.0,-1.0)';
    'MBB_DQS_L9':
      PIN_NUMBER='(0,BW64,0,0,0,0,0,0,0,0,0,0,0,0,0,0,0,0,0,0,0,0,0,0,0,0,0,0,0,0,0,0,0,0,0,0,0,0,0,0)';
      BIDIRECTIONAL='TRUE';
      INPUT_LOAD='(-0.01,0.01)';
      OUTPUT_LOAD='(1.0,-1.0)';
    'MBB_DQS_H5':
      PIN_NUMBER='(0,CF62,0,0,0,0,0,0,0,0,0,0,0,0,0,0,0,0,0,0,0,0,0,0,0,0,0,0,0,0,0,0,0,0,0,0,0,0,0,0)';
      BIDIRECTIONAL='TRUE';
      INPUT_LOAD='(-0.01,0.01)';
      OUTPUT_LOAD='(1.0,-1.0)';
    'MBA_DATA22':
      PIN_NUMBER='(0,AB63,0,0,0,0,0,0,0,0,0,0,0,0,0,0,0,0,0,0,0,0,0,0,0,0,0,0,0,0,0,0,0,0,0,0,0,0,0,0)';
      BIDIRECTIONAL='TRUE';
      INPUT_LOAD='(-0.01,0.01)';
      OUTPUT_LOAD='(1.0,-1.0)';
    'MBA_DATA11':
      PIN_NUMBER='(0,N62,0,0,0,0,0,0,0,0,0,0,0,0,0,0,0,0,0,0,0,0,0,0,0,0,0,0,0,0,0,0,0,0,0,0,0,0,0,0)';
      BIDIRECTIONAL='TRUE';
      INPUT_LOAD='(-0.01,0.01)';
      OUTPUT_LOAD='(1.0,-1.0)';
    'MBA_CHECK2':
      PIN_NUMBER='(0,AK63,0,0,0,0,0,0,0,0,0,0,0,0,0,0,0,0,0,0,0,0,0,0,0,0,0,0,0,0,0,0,0,0,0,0,0,0,0,0)';
      BIDIRECTIONAL='TRUE';
      INPUT_LOAD='(-0.01,0.01)';
      OUTPUT_LOAD='(1.0,-1.0)';
    'MBB_DQS_H6':
      PIN_NUMBER='(0,CM62,0,0,0,0,0,0,0,0,0,0,0,0,0,0,0,0,0,0,0,0,0,0,0,0,0,0,0,0,0,0,0,0,0,0,0,0,0,0)';
      BIDIRECTIONAL='TRUE';
      INPUT_LOAD='(-0.01,0.01)';
      OUTPUT_LOAD='(1.0,-1.0)';
    'MBA_DATA23':
      PIN_NUMBER='(0,AC62,0,0,0,0,0,0,0,0,0,0,0,0,0,0,0,0,0,0,0,0,0,0,0,0,0,0,0,0,0,0,0,0,0,0,0,0,0,0)';
      BIDIRECTIONAL='TRUE';
      INPUT_LOAD='(-0.01,0.01)';
      OUTPUT_LOAD='(1.0,-1.0)';
    'MBA_DATA12':
      PIN_NUMBER='(0,R64,0,0,0,0,0,0,0,0,0,0,0,0,0,0,0,0,0,0,0,0,0,0,0,0,0,0,0,0,0,0,0,0,0,0,0,0,0,0)';
      BIDIRECTIONAL='TRUE';
      INPUT_LOAD='(-0.01,0.01)';
      OUTPUT_LOAD='(1.0,-1.0)';
    'MBA_CHECK3':
      PIN_NUMBER='(0,AL62,0,0,0,0,0,0,0,0,0,0,0,0,0,0,0,0,0,0,0,0,0,0,0,0,0,0,0,0,0,0,0,0,0,0,0,0,0,0)';
      BIDIRECTIONAL='TRUE';
      INPUT_LOAD='(-0.01,0.01)';
      OUTPUT_LOAD='(1.0,-1.0)';
    'MBB_DQS_H7':
      PIN_NUMBER='(0,CV62,0,0,0,0,0,0,0,0,0,0,0,0,0,0,0,0,0,0,0,0,0,0,0,0,0,0,0,0,0,0,0,0,0,0,0,0,0,0)';
      BIDIRECTIONAL='TRUE';
      INPUT_LOAD='(-0.01,0.01)';
      OUTPUT_LOAD='(1.0,-1.0)';
    'MBB0_CS_L0':
      PIN_NUMBER='(0,BM62,0,0,0,0,0,0,0,0,0,0,0,0,0,0,0,0,0,0,0,0,0,0,0,0,0,0,0,0,0,0,0,0,0,0,0,0,0,0)';
      OUTPUT_LOAD='(1.0,-1.0)';
    'MBA_DQS_L0':
      PIN_NUMBER='(0,H63,0,0,0,0,0,0,0,0,0,0,0,0,0,0,0,0,0,0,0,0,0,0,0,0,0,0,0,0,0,0,0,0,0,0,0,0,0,0)';
      BIDIRECTIONAL='TRUE';
      INPUT_LOAD='(-0.01,0.01)';
      OUTPUT_LOAD='(1.0,-1.0)';
    'MBA_DATA13':
      PIN_NUMBER='(0,T62,0,0,0,0,0,0,0,0,0,0,0,0,0,0,0,0,0,0,0,0,0,0,0,0,0,0,0,0,0,0,0,0,0,0,0,0,0,0)';
      BIDIRECTIONAL='TRUE';
      INPUT_LOAD='(-0.01,0.01)';
      OUTPUT_LOAD='(1.0,-1.0)';
    'MBA_DATA0':
      PIN_NUMBER='(0,E64,0,0,0,0,0,0,0,0,0,0,0,0,0,0,0,0,0,0,0,0,0,0,0,0,0,0,0,0,0,0,0,0,0,0,0,0,0,0)';
      BIDIRECTIONAL='TRUE';
      INPUT_LOAD='(-0.01,0.01)';
      OUTPUT_LOAD='(1.0,-1.0)';
    'MBA_CHECK4':
      PIN_NUMBER='(0,AN64,0,0,0,0,0,0,0,0,0,0,0,0,0,0,0,0,0,0,0,0,0,0,0,0,0,0,0,0,0,0,0,0,0,0,0,0,0,0)';
      BIDIRECTIONAL='TRUE';
      INPUT_LOAD='(-0.01,0.01)';
      OUTPUT_LOAD='(1.0,-1.0)';
    'MBB_DQS_H8':
      PIN_NUMBER='(0,DD62,0,0,0,0,0,0,0,0,0,0,0,0,0,0,0,0,0,0,0,0,0,0,0,0,0,0,0,0,0,0,0,0,0,0,0,0,0,0)';
      BIDIRECTIONAL='TRUE';
      INPUT_LOAD='(-0.01,0.01)';
      OUTPUT_LOAD='(1.0,-1.0)';
    'MBB_DATA30':
      PIN_NUMBER='(0,DE64,0,0,0,0,0,0,0,0,0,0,0,0,0,0,0,0,0,0,0,0,0,0,0,0,0,0,0,0,0,0,0,0,0,0,0,0,0,0)';
      BIDIRECTIONAL='TRUE';
      INPUT_LOAD='(-0.01,0.01)';
      OUTPUT_LOAD='(1.0,-1.0)';
    'MBB_DATA0':
      PIN_NUMBER='(0,CB63,0,0,0,0,0,0,0,0,0,0,0,0,0,0,0,0,0,0,0,0,0,0,0,0,0,0,0,0,0,0,0,0,0,0,0,0,0,0)';
      BIDIRECTIONAL='TRUE';
      INPUT_LOAD='(-0.01,0.01)';
      OUTPUT_LOAD='(1.0,-1.0)';
    'MBB1_CS_L0':
      PIN_NUMBER='(0,BL62,0,0,0,0,0,0,0,0,0,0,0,0,0,0,0,0,0,0,0,0,0,0,0,0,0,0,0,0,0,0,0,0,0,0,0,0,0,0)';
      OUTPUT_LOAD='(1.0,-1.0)';
    'MBB0_CS_L1':
      PIN_NUMBER='(0,BN64,0,0,0,0,0,0,0,0,0,0,0,0,0,0,0,0,0,0,0,0,0,0,0,0,0,0,0,0,0,0,0,0,0,0,0,0,0,0)';
      OUTPUT_LOAD='(1.0,-1.0)';
    'MBA_DQS_L1':
      PIN_NUMBER='(0,P63,0,0,0,0,0,0,0,0,0,0,0,0,0,0,0,0,0,0,0,0,0,0,0,0,0,0,0,0,0,0,0,0,0,0,0,0,0,0)';
      BIDIRECTIONAL='TRUE';
      INPUT_LOAD='(-0.01,0.01)';
      OUTPUT_LOAD='(1.0,-1.0)';
    'MBA_DATA25':
      PIN_NUMBER='(0,AD62,0,0,0,0,0,0,0,0,0,0,0,0,0,0,0,0,0,0,0,0,0,0,0,0,0,0,0,0,0,0,0,0,0,0,0,0,0,0)';
      BIDIRECTIONAL='TRUE';
      INPUT_LOAD='(-0.01,0.01)';
      OUTPUT_LOAD='(1.0,-1.0)';
    'MBA_DATA14':
      PIN_NUMBER='(0,T63,0,0,0,0,0,0,0,0,0,0,0,0,0,0,0,0,0,0,0,0,0,0,0,0,0,0,0,0,0,0,0,0,0,0,0,0,0,0)';
      BIDIRECTIONAL='TRUE';
      INPUT_LOAD='(-0.01,0.01)';
      OUTPUT_LOAD='(1.0,-1.0)';
    'MBA_DATA1':
      PIN_NUMBER='(0,F62,0,0,0,0,0,0,0,0,0,0,0,0,0,0,0,0,0,0,0,0,0,0,0,0,0,0,0,0,0,0,0,0,0,0,0,0,0,0)';
      BIDIRECTIONAL='TRUE';
      INPUT_LOAD='(-0.01,0.01)';
      OUTPUT_LOAD='(1.0,-1.0)';
    'MBA_CHECK5':
      PIN_NUMBER='(0,AP62,0,0,0,0,0,0,0,0,0,0,0,0,0,0,0,0,0,0,0,0,0,0,0,0,0,0,0,0,0,0,0,0,0,0,0,0,0,0)';
      BIDIRECTIONAL='TRUE';
      INPUT_LOAD='(-0.01,0.01)';
      OUTPUT_LOAD='(1.0,-1.0)';
    'MBB_DATA31':
      PIN_NUMBER='(0,DF62,0,0,0,0,0,0,0,0,0,0,0,0,0,0,0,0,0,0,0,0,0,0,0,0,0,0,0,0,0,0,0,0,0,0,0,0,0,0)';
      BIDIRECTIONAL='TRUE';
      INPUT_LOAD='(-0.01,0.01)';
      OUTPUT_LOAD='(1.0,-1.0)';
    'MBB_DATA1':
      PIN_NUMBER='(0,CC62,0,0,0,0,0,0,0,0,0,0,0,0,0,0,0,0,0,0,0,0,0,0,0,0,0,0,0,0,0,0,0,0,0,0,0,0,0,0)';
      BIDIRECTIONAL='TRUE';
      INPUT_LOAD='(-0.01,0.01)';
      OUTPUT_LOAD='(1.0,-1.0)';
    'MBB_CHECK0':
      PIN_NUMBER='(0,BY63,0,0,0,0,0,0,0,0,0,0,0,0,0,0,0,0,0,0,0,0,0,0,0,0,0,0,0,0,0,0,0,0,0,0,0,0,0,0)';
      BIDIRECTIONAL='TRUE';
      INPUT_LOAD='(-0.01,0.01)';
      OUTPUT_LOAD='(1.0,-1.0)';
    'MBB1_CS_L1':
      PIN_NUMBER='(0,BM63,0,0,0,0,0,0,0,0,0,0,0,0,0,0,0,0,0,0,0,0,0,0,0,0,0,0,0,0,0,0,0,0,0,0,0,0,0,0)';
      OUTPUT_LOAD='(1.0,-1.0)';
    'MBA_DQS_L2':
      PIN_NUMBER='(0,Y63,0,0,0,0,0,0,0,0,0,0,0,0,0,0,0,0,0,0,0,0,0,0,0,0,0,0,0,0,0,0,0,0,0,0,0,0,0,0)';
      BIDIRECTIONAL='TRUE';
      INPUT_LOAD='(-0.01,0.01)';
      OUTPUT_LOAD='(1.0,-1.0)';
    'MBA_DATA26':
      PIN_NUMBER='(0,AD63,0,0,0,0,0,0,0,0,0,0,0,0,0,0,0,0,0,0,0,0,0,0,0,0,0,0,0,0,0,0,0,0,0,0,0,0,0,0)';
      BIDIRECTIONAL='TRUE';
      INPUT_LOAD='(-0.01,0.01)';
      OUTPUT_LOAD='(1.0,-1.0)';
    'MBA_DATA15':
      PIN_NUMBER='(0,U62,0,0,0,0,0,0,0,0,0,0,0,0,0,0,0,0,0,0,0,0,0,0,0,0,0,0,0,0,0,0,0,0,0,0,0,0,0,0)';
      BIDIRECTIONAL='TRUE';
      INPUT_LOAD='(-0.01,0.01)';
      OUTPUT_LOAD='(1.0,-1.0)';
    'MBA_DATA2':
      PIN_NUMBER='(0,F63,0,0,0,0,0,0,0,0,0,0,0,0,0,0,0,0,0,0,0,0,0,0,0,0,0,0,0,0,0,0,0,0,0,0,0,0,0,0)';
      BIDIRECTIONAL='TRUE';
      INPUT_LOAD='(-0.01,0.01)';
      OUTPUT_LOAD='(1.0,-1.0)';
    'MBA_CHECK6':
      PIN_NUMBER='(0,AP63,0,0,0,0,0,0,0,0,0,0,0,0,0,0,0,0,0,0,0,0,0,0,0,0,0,0,0,0,0,0,0,0,0,0,0,0,0,0)';
      BIDIRECTIONAL='TRUE';
      INPUT_LOAD='(-0.01,0.01)';
      OUTPUT_LOAD='(1.0,-1.0)';
    'MBB_DATA21':
      PIN_NUMBER='(0,CW62,0,0,0,0,0,0,0,0,0,0,0,0,0,0,0,0,0,0,0,0,0,0,0,0,0,0,0,0,0,0,0,0,0,0,0,0,0,0)';
      BIDIRECTIONAL='TRUE';
      INPUT_LOAD='(-0.01,0.01)';
      OUTPUT_LOAD='(1.0,-1.0)';
    'MBB_DATA10':
      PIN_NUMBER='(0,CJ64,0,0,0,0,0,0,0,0,0,0,0,0,0,0,0,0,0,0,0,0,0,0,0,0,0,0,0,0,0,0,0,0,0,0,0,0,0,0)';
      BIDIRECTIONAL='TRUE';
      INPUT_LOAD='(-0.01,0.01)';
      OUTPUT_LOAD='(1.0,-1.0)';
    'MBB_DATA2':
      PIN_NUMBER='(0,CC64,0,0,0,0,0,0,0,0,0,0,0,0,0,0,0,0,0,0,0,0,0,0,0,0,0,0,0,0,0,0,0,0,0,0,0,0,0,0)';
      BIDIRECTIONAL='TRUE';
      INPUT_LOAD='(-0.01,0.01)';
      OUTPUT_LOAD='(1.0,-1.0)';
    'MBB_CHECK1':
      PIN_NUMBER='(0,CA62,0,0,0,0,0,0,0,0,0,0,0,0,0,0,0,0,0,0,0,0,0,0,0,0,0,0,0,0,0,0,0,0,0,0,0,0,0,0)';
      BIDIRECTIONAL='TRUE';
      INPUT_LOAD='(-0.01,0.01)';
      OUTPUT_LOAD='(1.0,-1.0)';
    'MBA_DQS_L3':
      PIN_NUMBER='(0,AF63,0,0,0,0,0,0,0,0,0,0,0,0,0,0,0,0,0,0,0,0,0,0,0,0,0,0,0,0,0,0,0,0,0,0,0,0,0,0)';
      BIDIRECTIONAL='TRUE';
      INPUT_LOAD='(-0.01,0.01)';
      OUTPUT_LOAD='(1.0,-1.0)';
    'MBA_DATA27':
      PIN_NUMBER='(0,AE62,0,0,0,0,0,0,0,0,0,0,0,0,0,0,0,0,0,0,0,0,0,0,0,0,0,0,0,0,0,0,0,0,0,0,0,0,0,0)';
      BIDIRECTIONAL='TRUE';
      INPUT_LOAD='(-0.01,0.01)';
      OUTPUT_LOAD='(1.0,-1.0)';
    'MBA_DATA16':
      PIN_NUMBER='(0,U64,0,0,0,0,0,0,0,0,0,0,0,0,0,0,0,0,0,0,0,0,0,0,0,0,0,0,0,0,0,0,0,0,0,0,0,0,0,0)';
      BIDIRECTIONAL='TRUE';
      INPUT_LOAD='(-0.01,0.01)';
      OUTPUT_LOAD='(1.0,-1.0)';
    'MBA_DATA3':
      PIN_NUMBER='(0,G62,0,0,0,0,0,0,0,0,0,0,0,0,0,0,0,0,0,0,0,0,0,0,0,0,0,0,0,0,0,0,0,0,0,0,0,0,0,0)';
      BIDIRECTIONAL='TRUE';
      INPUT_LOAD='(-0.01,0.01)';
      OUTPUT_LOAD='(1.0,-1.0)';
    'MBA_CHECK7':
      PIN_NUMBER='(0,AR62,0,0,0,0,0,0,0,0,0,0,0,0,0,0,0,0,0,0,0,0,0,0,0,0,0,0,0,0,0,0,0,0,0,0,0,0,0,0)';
      BIDIRECTIONAL='TRUE';
      INPUT_LOAD='(-0.01,0.01)';
      OUTPUT_LOAD='(1.0,-1.0)';
    'MBA0_RSP_L':
      PIN_NUMBER='(0,BN62,0,0,0,0,0,0,0,0,0,0,0,0,0,0,0,0,0,0,0,0,0,0,0,0,0,0,0,0,0,0,0,0,0,0,0,0,0,0)';
      INPUT_LOAD='(-0.01,0.01)';
    'MBB_DATA22':
      PIN_NUMBER='(0,CW64,0,0,0,0,0,0,0,0,0,0,0,0,0,0,0,0,0,0,0,0,0,0,0,0,0,0,0,0,0,0,0,0,0,0,0,0,0,0)';
      BIDIRECTIONAL='TRUE';
      INPUT_LOAD='(-0.01,0.01)';
      OUTPUT_LOAD='(1.0,-1.0)';
    'MBB_DATA11':
      PIN_NUMBER='(0,CK62,0,0,0,0,0,0,0,0,0,0,0,0,0,0,0,0,0,0,0,0,0,0,0,0,0,0,0,0,0,0,0,0,0,0,0,0,0,0)';
      BIDIRECTIONAL='TRUE';
      INPUT_LOAD='(-0.01,0.01)';
      OUTPUT_LOAD='(1.0,-1.0)';
    'MBB_DATA3':
      PIN_NUMBER='(0,CD62,0,0,0,0,0,0,0,0,0,0,0,0,0,0,0,0,0,0,0,0,0,0,0,0,0,0,0,0,0,0,0,0,0,0,0,0,0,0)';
      BIDIRECTIONAL='TRUE';
      INPUT_LOAD='(-0.01,0.01)';
      OUTPUT_LOAD='(1.0,-1.0)';
    'MBB_CHECK2':
      PIN_NUMBER='(0,CA64,0,0,0,0,0,0,0,0,0,0,0,0,0,0,0,0,0,0,0,0,0,0,0,0,0,0,0,0,0,0,0,0,0,0,0,0,0,0)';
      BIDIRECTIONAL='TRUE';
      INPUT_LOAD='(-0.01,0.01)';
      OUTPUT_LOAD='(1.0,-1.0)';
    'MBA_DQS_L4':
      PIN_NUMBER='(0,AM63,0,0,0,0,0,0,0,0,0,0,0,0,0,0,0,0,0,0,0,0,0,0,0,0,0,0,0,0,0,0,0,0,0,0,0,0,0,0)';
      BIDIRECTIONAL='TRUE';
      INPUT_LOAD='(-0.01,0.01)';
      OUTPUT_LOAD='(1.0,-1.0)';
    'MBA_DQS_H0':
      PIN_NUMBER='(0,G64,0,0,0,0,0,0,0,0,0,0,0,0,0,0,0,0,0,0,0,0,0,0,0,0,0,0,0,0,0,0,0,0,0,0,0,0,0,0)';
      BIDIRECTIONAL='TRUE';
      INPUT_LOAD='(-0.01,0.01)';
      OUTPUT_LOAD='(1.0,-1.0)';
    'MBA_DATA28':
      PIN_NUMBER='(0,AG64,0,0,0,0,0,0,0,0,0,0,0,0,0,0,0,0,0,0,0,0,0,0,0,0,0,0,0,0,0,0,0,0,0,0,0,0,0,0)';
      BIDIRECTIONAL='TRUE';
      INPUT_LOAD='(-0.01,0.01)';
      OUTPUT_LOAD='(1.0,-1.0)';
    'MBA_DATA17':
      PIN_NUMBER='(0,V62,0,0,0,0,0,0,0,0,0,0,0,0,0,0,0,0,0,0,0,0,0,0,0,0,0,0,0,0,0,0,0,0,0,0,0,0,0,0)';
      BIDIRECTIONAL='TRUE';
      INPUT_LOAD='(-0.01,0.01)';
      OUTPUT_LOAD='(1.0,-1.0)';
    'MBA_DATA4':
      PIN_NUMBER='(0,J64,0,0,0,0,0,0,0,0,0,0,0,0,0,0,0,0,0,0,0,0,0,0,0,0,0,0,0,0,0,0,0,0,0,0,0,0,0,0)';
      BIDIRECTIONAL='TRUE';
      INPUT_LOAD='(-0.01,0.01)';
      OUTPUT_LOAD='(1.0,-1.0)';
    'MBA1_RSP_L':
      PIN_NUMBER='(0,BP62,0,0,0,0,0,0,0,0,0,0,0,0,0,0,0,0,0,0,0,0,0,0,0,0,0,0,0,0,0,0,0,0,0,0,0,0,0,0)';
      INPUT_LOAD='(-0.01,0.01)';
    'MBB_DATA23':
      PIN_NUMBER='(0,CY62,0,0,0,0,0,0,0,0,0,0,0,0,0,0,0,0,0,0,0,0,0,0,0,0,0,0,0,0,0,0,0,0,0,0,0,0,0,0)';
      BIDIRECTIONAL='TRUE';
      INPUT_LOAD='(-0.01,0.01)';
      OUTPUT_LOAD='(1.0,-1.0)';
    'MBB_DATA12':
      PIN_NUMBER='(0,CM63,0,0,0,0,0,0,0,0,0,0,0,0,0,0,0,0,0,0,0,0,0,0,0,0,0,0,0,0,0,0,0,0,0,0,0,0,0,0)';
      BIDIRECTIONAL='TRUE';
      INPUT_LOAD='(-0.01,0.01)';
      OUTPUT_LOAD='(1.0,-1.0)';
    'MBB_DATA4':
      PIN_NUMBER='(0,CF63,0,0,0,0,0,0,0,0,0,0,0,0,0,0,0,0,0,0,0,0,0,0,0,0,0,0,0,0,0,0,0,0,0,0,0,0,0,0)';
      BIDIRECTIONAL='TRUE';
      INPUT_LOAD='(-0.01,0.01)';
      OUTPUT_LOAD='(1.0,-1.0)';
    'MBB_CHECK3':
      PIN_NUMBER='(0,CB62,0,0,0,0,0,0,0,0,0,0,0,0,0,0,0,0,0,0,0,0,0,0,0,0,0,0,0,0,0,0,0,0,0,0,0,0,0,0)';
      BIDIRECTIONAL='TRUE';
      INPUT_LOAD='(-0.01,0.01)';
      OUTPUT_LOAD='(1.0,-1.0)';
    'MBA_DQS_L5':
      PIN_NUMBER='(0,H62,0,0,0,0,0,0,0,0,0,0,0,0,0,0,0,0,0,0,0,0,0,0,0,0,0,0,0,0,0,0,0,0,0,0,0,0,0,0)';
      BIDIRECTIONAL='TRUE';
      INPUT_LOAD='(-0.01,0.01)';
      OUTPUT_LOAD='(1.0,-1.0)';
    'MBA_DQS_H1':
      PIN_NUMBER='(0,N64,0,0,0,0,0,0,0,0,0,0,0,0,0,0,0,0,0,0,0,0,0,0,0,0,0,0,0,0,0,0,0,0,0,0,0,0,0,0)';
      BIDIRECTIONAL='TRUE';
      INPUT_LOAD='(-0.01,0.01)';
      OUTPUT_LOAD='(1.0,-1.0)';
    'MBA_DATA29':
      PIN_NUMBER='(0,AH62,0,0,0,0,0,0,0,0,0,0,0,0,0,0,0,0,0,0,0,0,0,0,0,0,0,0,0,0,0,0,0,0,0,0,0,0,0,0)';
      BIDIRECTIONAL='TRUE';
      INPUT_LOAD='(-0.01,0.01)';
      OUTPUT_LOAD='(1.0,-1.0)';
    'MBA_DATA18':
      PIN_NUMBER='(0,V63,0,0,0,0,0,0,0,0,0,0,0,0,0,0,0,0,0,0,0,0,0,0,0,0,0,0,0,0,0,0,0,0,0,0,0,0,0,0)';
      BIDIRECTIONAL='TRUE';
      INPUT_LOAD='(-0.01,0.01)';
      OUTPUT_LOAD='(1.0,-1.0)';
    'MBA_DATA5':
      PIN_NUMBER='(0,K62,0,0,0,0,0,0,0,0,0,0,0,0,0,0,0,0,0,0,0,0,0,0,0,0,0,0,0,0,0,0,0,0,0,0,0,0,0,0)';
      BIDIRECTIONAL='TRUE';
      INPUT_LOAD='(-0.01,0.01)';
      OUTPUT_LOAD='(1.0,-1.0)';
    'MBB_DQS_L0':
      PIN_NUMBER='(0,CE64,0,0,0,0,0,0,0,0,0,0,0,0,0,0,0,0,0,0,0,0,0,0,0,0,0,0,0,0,0,0,0,0,0,0,0,0,0,0)';
      BIDIRECTIONAL='TRUE';
      INPUT_LOAD='(-0.01,0.01)';
      OUTPUT_LOAD='(1.0,-1.0)';
    'MBB_DATA24':
      PIN_NUMBER='(0,CY63,0,0,0,0,0,0,0,0,0,0,0,0,0,0,0,0,0,0,0,0,0,0,0,0,0,0,0,0,0,0,0,0,0,0,0,0,0,0)';
      BIDIRECTIONAL='TRUE';
      INPUT_LOAD='(-0.01,0.01)';
      OUTPUT_LOAD='(1.0,-1.0)';
    'MBB_DATA13':
      PIN_NUMBER='(0,CN62,0,0,0,0,0,0,0,0,0,0,0,0,0,0,0,0,0,0,0,0,0,0,0,0,0,0,0,0,0,0,0,0,0,0,0,0,0,0)';
      BIDIRECTIONAL='TRUE';
      INPUT_LOAD='(-0.01,0.01)';
      OUTPUT_LOAD='(1.0,-1.0)';
    'MBB_DATA5':
      PIN_NUMBER='(0,CG62,0,0,0,0,0,0,0,0,0,0,0,0,0,0,0,0,0,0,0,0,0,0,0,0,0,0,0,0,0,0,0,0,0,0,0,0,0,0)';
      BIDIRECTIONAL='TRUE';
      INPUT_LOAD='(-0.01,0.01)';
      OUTPUT_LOAD='(1.0,-1.0)';
    'MBB_CHECK4':
      PIN_NUMBER='(0,BT63,0,0,0,0,0,0,0,0,0,0,0,0,0,0,0,0,0,0,0,0,0,0,0,0,0,0,0,0,0,0,0,0,0,0,0,0,0,0)';
      BIDIRECTIONAL='TRUE';
      INPUT_LOAD='(-0.01,0.01)';
      OUTPUT_LOAD='(1.0,-1.0)';
    'MBA_DQS_L6':
      PIN_NUMBER='(0,P62,0,0,0,0,0,0,0,0,0,0,0,0,0,0,0,0,0,0,0,0,0,0,0,0,0,0,0,0,0,0,0,0,0,0,0,0,0,0)';
      BIDIRECTIONAL='TRUE';
      INPUT_LOAD='(-0.01,0.01)';
      OUTPUT_LOAD='(1.0,-1.0)';
    'MBA_DQS_H2':
      PIN_NUMBER='(0,W64,0,0,0,0,0,0,0,0,0,0,0,0,0,0,0,0,0,0,0,0,0,0,0,0,0,0,0,0,0,0,0,0,0,0,0,0,0,0)';
      BIDIRECTIONAL='TRUE';
      INPUT_LOAD='(-0.01,0.01)';
      OUTPUT_LOAD='(1.0,-1.0)';
    'MBA_DATA19':
      PIN_NUMBER='(0,W62,0,0,0,0,0,0,0,0,0,0,0,0,0,0,0,0,0,0,0,0,0,0,0,0,0,0,0,0,0,0,0,0,0,0,0,0,0,0)';
      BIDIRECTIONAL='TRUE';
      INPUT_LOAD='(-0.01,0.01)';
      OUTPUT_LOAD='(1.0,-1.0)';
    'MBA_DATA6':
      PIN_NUMBER='(0,K63,0,0,0,0,0,0,0,0,0,0,0,0,0,0,0,0,0,0,0,0,0,0,0,0,0,0,0,0,0,0,0,0,0,0,0,0,0,0)';
      BIDIRECTIONAL='TRUE';
      INPUT_LOAD='(-0.01,0.01)';
      OUTPUT_LOAD='(1.0,-1.0)';
    'MBA_CA0':
      PIN_NUMBER='(0,AW64,0,0,0,0,0,0,0,0,0,0,0,0,0,0,0,0,0,0,0,0,0,0,0,0,0,0,0,0,0,0,0,0,0,0,0,0,0,0)';
      OUTPUT_LOAD='(1.0,-1.0)';
    'MBB_DQS_L1':
      PIN_NUMBER='(0,CL64,0,0,0,0,0,0,0,0,0,0,0,0,0,0,0,0,0,0,0,0,0,0,0,0,0,0,0,0,0,0,0,0,0,0,0,0,0,0)';
      BIDIRECTIONAL='TRUE';
      INPUT_LOAD='(-0.01,0.01)';
      OUTPUT_LOAD='(1.0,-1.0)';
    'MBB_DATA25':
      PIN_NUMBER='(0,DA62,0,0,0,0,0,0,0,0,0,0,0,0,0,0,0,0,0,0,0,0,0,0,0,0,0,0,0,0,0,0,0,0,0,0,0,0,0,0)';
      BIDIRECTIONAL='TRUE';
      INPUT_LOAD='(-0.01,0.01)';
      OUTPUT_LOAD='(1.0,-1.0)';
    'MBB_DATA14':
      PIN_NUMBER='(0,CN64,0,0,0,0,0,0,0,0,0,0,0,0,0,0,0,0,0,0,0,0,0,0,0,0,0,0,0,0,0,0,0,0,0,0,0,0,0,0)';
      BIDIRECTIONAL='TRUE';
      INPUT_LOAD='(-0.01,0.01)';
      OUTPUT_LOAD='(1.0,-1.0)';
    'MBB_DATA6':
      PIN_NUMBER='(0,CG64,0,0,0,0,0,0,0,0,0,0,0,0,0,0,0,0,0,0,0,0,0,0,0,0,0,0,0,0,0,0,0,0,0,0,0,0,0,0)';
      BIDIRECTIONAL='TRUE';
      INPUT_LOAD='(-0.01,0.01)';
      OUTPUT_LOAD='(1.0,-1.0)';
    'MBB_CHECK5':
      PIN_NUMBER='(0,BU62,0,0,0,0,0,0,0,0,0,0,0,0,0,0,0,0,0,0,0,0,0,0,0,0,0,0,0,0,0,0,0,0,0,0,0,0,0,0)';
      BIDIRECTIONAL='TRUE';
      INPUT_LOAD='(-0.01,0.01)';
      OUTPUT_LOAD='(1.0,-1.0)';
    'MBB_CA0':
      PIN_NUMBER='(0,BG62,0,0,0,0,0,0,0,0,0,0,0,0,0,0,0,0,0,0,0,0,0,0,0,0,0,0,0,0,0,0,0,0,0,0,0,0,0,0)';
      OUTPUT_LOAD='(1.0,-1.0)';
    'MBA_DQS_L7':
      PIN_NUMBER='(0,Y62,0,0,0,0,0,0,0,0,0,0,0,0,0,0,0,0,0,0,0,0,0,0,0,0,0,0,0,0,0,0,0,0,0,0,0,0,0,0)';
      BIDIRECTIONAL='TRUE';
      INPUT_LOAD='(-0.01,0.01)';
      OUTPUT_LOAD='(1.0,-1.0)';
    'MBA_DQS_H3':
      PIN_NUMBER='(0,AE64,0,0,0,0,0,0,0,0,0,0,0,0,0,0,0,0,0,0,0,0,0,0,0,0,0,0,0,0,0,0,0,0,0,0,0,0,0,0)';
      BIDIRECTIONAL='TRUE';
      INPUT_LOAD='(-0.01,0.01)';
      OUTPUT_LOAD='(1.0,-1.0)';
    'MBA_DATA7':
      PIN_NUMBER='(0,L62,0,0,0,0,0,0,0,0,0,0,0,0,0,0,0,0,0,0,0,0,0,0,0,0,0,0,0,0,0,0,0,0,0,0,0,0,0,0)';
      BIDIRECTIONAL='TRUE';
      INPUT_LOAD='(-0.01,0.01)';
      OUTPUT_LOAD='(1.0,-1.0)';
    'MBA_CA1':
      PIN_NUMBER='(0,AY63,0,0,0,0,0,0,0,0,0,0,0,0,0,0,0,0,0,0,0,0,0,0,0,0,0,0,0,0,0,0,0,0,0,0,0,0,0,0)';
      OUTPUT_LOAD='(1.0,-1.0)';
    'MBB_DQS_L2':
      PIN_NUMBER='(0,CU64,0,0,0,0,0,0,0,0,0,0,0,0,0,0,0,0,0,0,0,0,0,0,0,0,0,0,0,0,0,0,0,0,0,0,0,0,0,0)';
      BIDIRECTIONAL='TRUE';
      INPUT_LOAD='(-0.01,0.01)';
      OUTPUT_LOAD='(1.0,-1.0)';
    'MBB_DATA26':
      PIN_NUMBER='(0,DA64,0,0,0,0,0,0,0,0,0,0,0,0,0,0,0,0,0,0,0,0,0,0,0,0,0,0,0,0,0,0,0,0,0,0,0,0,0,0)';
      BIDIRECTIONAL='TRUE';
      INPUT_LOAD='(-0.01,0.01)';
      OUTPUT_LOAD='(1.0,-1.0)';
    'MBB_DATA15':
      PIN_NUMBER='(0,CP62,0,0,0,0,0,0,0,0,0,0,0,0,0,0,0,0,0,0,0,0,0,0,0,0,0,0,0,0,0,0,0,0,0,0,0,0,0,0)';
      BIDIRECTIONAL='TRUE';
      INPUT_LOAD='(-0.01,0.01)';
      OUTPUT_LOAD='(1.0,-1.0)';
    'MBB_DATA7':
      PIN_NUMBER='(0,CH62,0,0,0,0,0,0,0,0,0,0,0,0,0,0,0,0,0,0,0,0,0,0,0,0,0,0,0,0,0,0,0,0,0,0,0,0,0,0)';
      BIDIRECTIONAL='TRUE';
      INPUT_LOAD='(-0.01,0.01)';
      OUTPUT_LOAD='(1.0,-1.0)';
    'MBB_CHECK6':
      PIN_NUMBER='(0,BU64,0,0,0,0,0,0,0,0,0,0,0,0,0,0,0,0,0,0,0,0,0,0,0,0,0,0,0,0,0,0,0,0,0,0,0,0,0,0)';
      BIDIRECTIONAL='TRUE';
      INPUT_LOAD='(-0.01,0.01)';
      OUTPUT_LOAD='(1.0,-1.0)';
    'MBB_CA1':
      PIN_NUMBER='(0,BH62,0,0,0,0,0,0,0,0,0,0,0,0,0,0,0,0,0,0,0,0,0,0,0,0,0,0,0,0,0,0,0,0,0,0,0,0,0,0)';
      OUTPUT_LOAD='(1.0,-1.0)';
    'MBA_DQS_L8':
      PIN_NUMBER='(0,AF62,0,0,0,0,0,0,0,0,0,0,0,0,0,0,0,0,0,0,0,0,0,0,0,0,0,0,0,0,0,0,0,0,0,0,0,0,0,0)';
      BIDIRECTIONAL='TRUE';
      INPUT_LOAD='(-0.01,0.01)';
      OUTPUT_LOAD='(1.0,-1.0)';
    'MBA_DQS_H4':
      PIN_NUMBER='(0,AL64,0,0,0,0,0,0,0,0,0,0,0,0,0,0,0,0,0,0,0,0,0,0,0,0,0,0,0,0,0,0,0,0,0,0,0,0,0,0)';
      BIDIRECTIONAL='TRUE';
      INPUT_LOAD='(-0.01,0.01)';
      OUTPUT_LOAD='(1.0,-1.0)';
    'MBA_DATA8':
      PIN_NUMBER='(0,L64,0,0,0,0,0,0,0,0,0,0,0,0,0,0,0,0,0,0,0,0,0,0,0,0,0,0,0,0,0,0,0,0,0,0,0,0,0,0)';
      BIDIRECTIONAL='TRUE';
      INPUT_LOAD='(-0.01,0.01)';
      OUTPUT_LOAD='(1.0,-1.0)';
    'MBA_CA2':
      PIN_NUMBER='(0,AY62,0,0,0,0,0,0,0,0,0,0,0,0,0,0,0,0,0,0,0,0,0,0,0,0,0,0,0,0,0,0,0,0,0,0,0,0,0,0)';
      OUTPUT_LOAD='(1.0,-1.0)';
    'MBB_DQS_L3':
      PIN_NUMBER='(0,DC64,0,0,0,0,0,0,0,0,0,0,0,0,0,0,0,0,0,0,0,0,0,0,0,0,0,0,0,0,0,0,0,0,0,0,0,0,0,0)';
      BIDIRECTIONAL='TRUE';
      INPUT_LOAD='(-0.01,0.01)';
      OUTPUT_LOAD='(1.0,-1.0)';
    'MBB_DATA27':
      PIN_NUMBER='(0,DB62,0,0,0,0,0,0,0,0,0,0,0,0,0,0,0,0,0,0,0,0,0,0,0,0,0,0,0,0,0,0,0,0,0,0,0,0,0,0)';
      BIDIRECTIONAL='TRUE';
      INPUT_LOAD='(-0.01,0.01)';
      OUTPUT_LOAD='(1.0,-1.0)';
    'MBB_DATA16':
      PIN_NUMBER='(0,CP63,0,0,0,0,0,0,0,0,0,0,0,0,0,0,0,0,0,0,0,0,0,0,0,0,0,0,0,0,0,0,0,0,0,0,0,0,0,0)';
      BIDIRECTIONAL='TRUE';
      INPUT_LOAD='(-0.01,0.01)';
      OUTPUT_LOAD='(1.0,-1.0)';
    'MBB_DATA8':
      PIN_NUMBER='(0,CH63,0,0,0,0,0,0,0,0,0,0,0,0,0,0,0,0,0,0,0,0,0,0,0,0,0,0,0,0,0,0,0,0,0,0,0,0,0,0)';
      BIDIRECTIONAL='TRUE';
      INPUT_LOAD='(-0.01,0.01)';
      OUTPUT_LOAD='(1.0,-1.0)';
    'MBB_CHECK7':
      PIN_NUMBER='(0,BV62,0,0,0,0,0,0,0,0,0,0,0,0,0,0,0,0,0,0,0,0,0,0,0,0,0,0,0,0,0,0,0,0,0,0,0,0,0,0)';
      BIDIRECTIONAL='TRUE';
      INPUT_LOAD='(-0.01,0.01)';
      OUTPUT_LOAD='(1.0,-1.0)';
    'MBB_CA2':
      PIN_NUMBER='(0,BH63,0,0,0,0,0,0,0,0,0,0,0,0,0,0,0,0,0,0,0,0,0,0,0,0,0,0,0,0,0,0,0,0,0,0,0,0,0,0)';
      OUTPUT_LOAD='(1.0,-1.0)';
    'MBB0_RSP_L':
      PIN_NUMBER='(0,BP63,0,0,0,0,0,0,0,0,0,0,0,0,0,0,0,0,0,0,0,0,0,0,0,0,0,0,0,0,0,0,0,0,0,0,0,0,0,0)';
      INPUT_LOAD='(-0.01,0.01)';
    'MBA_DQS_L9':
      PIN_NUMBER='(0,AM62,0,0,0,0,0,0,0,0,0,0,0,0,0,0,0,0,0,0,0,0,0,0,0,0,0,0,0,0,0,0,0,0,0,0,0,0,0,0)';
      BIDIRECTIONAL='TRUE';
      INPUT_LOAD='(-0.01,0.01)';
      OUTPUT_LOAD='(1.0,-1.0)';
    'MBA_DQS_H5':
      PIN_NUMBER='(0,J62,0,0,0,0,0,0,0,0,0,0,0,0,0,0,0,0,0,0,0,0,0,0,0,0,0,0,0,0,0,0,0,0,0,0,0,0,0,0)';
      BIDIRECTIONAL='TRUE';
      INPUT_LOAD='(-0.01,0.01)';
      OUTPUT_LOAD='(1.0,-1.0)';
    'MBA_DATA9':
      PIN_NUMBER='(0,M62,0,0,0,0,0,0,0,0,0,0,0,0,0,0,0,0,0,0,0,0,0,0,0,0,0,0,0,0,0,0,0,0,0,0,0,0,0,0)';
      BIDIRECTIONAL='TRUE';
      INPUT_LOAD='(-0.01,0.01)';
      OUTPUT_LOAD='(1.0,-1.0)';
    'MBA_CA3':
      PIN_NUMBER='(0,BA62,0,0,0,0,0,0,0,0,0,0,0,0,0,0,0,0,0,0,0,0,0,0,0,0,0,0,0,0,0,0,0,0,0,0,0,0,0,0)';
      OUTPUT_LOAD='(1.0,-1.0)';
    'MBB_DQS_L4':
      PIN_NUMBER='(0,BW62,0,0,0,0,0,0,0,0,0,0,0,0,0,0,0,0,0,0,0,0,0,0,0,0,0,0,0,0,0,0,0,0,0,0,0,0,0,0)';
      BIDIRECTIONAL='TRUE';
      INPUT_LOAD='(-0.01,0.01)';
      OUTPUT_LOAD='(1.0,-1.0)';
    'MBB_DQS_H0':
      PIN_NUMBER='(0,CD63,0,0,0,0,0,0,0,0,0,0,0,0,0,0,0,0,0,0,0,0,0,0,0,0,0,0,0,0,0,0,0,0,0,0,0,0,0,0)';
      BIDIRECTIONAL='TRUE';
      INPUT_LOAD='(-0.01,0.01)';
      OUTPUT_LOAD='(1.0,-1.0)';
    'MBB_DATA28':
      PIN_NUMBER='(0,DD63,0,0,0,0,0,0,0,0,0,0,0,0,0,0,0,0,0,0,0,0,0,0,0,0,0,0,0,0,0,0,0,0,0,0,0,0,0,0)';
      BIDIRECTIONAL='TRUE';
      INPUT_LOAD='(-0.01,0.01)';
      OUTPUT_LOAD='(1.0,-1.0)';
    'MBB_DATA17':
      PIN_NUMBER='(0,CR62,0,0,0,0,0,0,0,0,0,0,0,0,0,0,0,0,0,0,0,0,0,0,0,0,0,0,0,0,0,0,0,0,0,0,0,0,0,0)';
      BIDIRECTIONAL='TRUE';
      INPUT_LOAD='(-0.01,0.01)';
      OUTPUT_LOAD='(1.0,-1.0)';
    'MBB_DATA9':
      PIN_NUMBER='(0,CJ62,0,0,0,0,0,0,0,0,0,0,0,0,0,0,0,0,0,0,0,0,0,0,0,0,0,0,0,0,0,0,0,0,0,0,0,0,0,0)';
      BIDIRECTIONAL='TRUE';
      INPUT_LOAD='(-0.01,0.01)';
      OUTPUT_LOAD='(1.0,-1.0)';
    'MBB_CA3':
      PIN_NUMBER='(0,BJ64,0,0,0,0,0,0,0,0,0,0,0,0,0,0,0,0,0,0,0,0,0,0,0,0,0,0,0,0,0,0,0,0,0,0,0,0,0,0)';
      OUTPUT_LOAD='(1.0,-1.0)';
    'MBB1_RSP_L':
      PIN_NUMBER='(0,BR64,0,0,0,0,0,0,0,0,0,0,0,0,0,0,0,0,0,0,0,0,0,0,0,0,0,0,0,0,0,0,0,0,0,0,0,0,0,0)';
      INPUT_LOAD='(-0.01,0.01)';
    'MBA_DQS_H6':
      PIN_NUMBER='(0,R62,0,0,0,0,0,0,0,0,0,0,0,0,0,0,0,0,0,0,0,0,0,0,0,0,0,0,0,0,0,0,0,0,0,0,0,0,0,0)';
      BIDIRECTIONAL='TRUE';
      INPUT_LOAD='(-0.01,0.01)';
      OUTPUT_LOAD='(1.0,-1.0)';
    'MBA_CA4':
      PIN_NUMBER='(0,BA64,0,0,0,0,0,0,0,0,0,0,0,0,0,0,0,0,0,0,0,0,0,0,0,0,0,0,0,0,0,0,0,0,0,0,0,0,0,0)';
      OUTPUT_LOAD='(1.0,-1.0)';
    'MBB_DQS_L5':
      PIN_NUMBER='(0,CE62,0,0,0,0,0,0,0,0,0,0,0,0,0,0,0,0,0,0,0,0,0,0,0,0,0,0,0,0,0,0,0,0,0,0,0,0,0,0)';
      BIDIRECTIONAL='TRUE';
      INPUT_LOAD='(-0.01,0.01)';
      OUTPUT_LOAD='(1.0,-1.0)';
    'MBB_DQS_H1':
      PIN_NUMBER='(0,CK63,0,0,0,0,0,0,0,0,0,0,0,0,0,0,0,0,0,0,0,0,0,0,0,0,0,0,0,0,0,0,0,0,0,0,0,0,0,0)';
      BIDIRECTIONAL='TRUE';
      INPUT_LOAD='(-0.01,0.01)';
      OUTPUT_LOAD='(1.0,-1.0)';
    'MBB_DATA29':
      PIN_NUMBER='(0,DE62,0,0,0,0,0,0,0,0,0,0,0,0,0,0,0,0,0,0,0,0,0,0,0,0,0,0,0,0,0,0,0,0,0,0,0,0,0,0)';
      BIDIRECTIONAL='TRUE';
      INPUT_LOAD='(-0.01,0.01)';
      OUTPUT_LOAD='(1.0,-1.0)';
    'MBB_DATA18':
      PIN_NUMBER='(0,CR64,0,0,0,0,0,0,0,0,0,0,0,0,0,0,0,0,0,0,0,0,0,0,0,0,0,0,0,0,0,0,0,0,0,0,0,0,0,0)';
      BIDIRECTIONAL='TRUE';
      INPUT_LOAD='(-0.01,0.01)';
      OUTPUT_LOAD='(1.0,-1.0)';
    'MBB_CA4':
      PIN_NUMBER='(0,BJ62,0,0,0,0,0,0,0,0,0,0,0,0,0,0,0,0,0,0,0,0,0,0,0,0,0,0,0,0,0,0,0,0,0,0,0,0,0,0)';
      OUTPUT_LOAD='(1.0,-1.0)';
    'MBA_DQS_H7':
      PIN_NUMBER='(0,AA62,0,0,0,0,0,0,0,0,0,0,0,0,0,0,0,0,0,0,0,0,0,0,0,0,0,0,0,0,0,0,0,0,0,0,0,0,0,0)';
      BIDIRECTIONAL='TRUE';
      INPUT_LOAD='(-0.01,0.01)';
      OUTPUT_LOAD='(1.0,-1.0)';
    'MBA_CA5':
      PIN_NUMBER='(0,BB63,0,0,0,0,0,0,0,0,0,0,0,0,0,0,0,0,0,0,0,0,0,0,0,0,0,0,0,0,0,0,0,0,0,0,0,0,0,0)';
      OUTPUT_LOAD='(1.0,-1.0)';
    'MBA0_CS_L0':
      PIN_NUMBER='(0,AV63,0,0,0,0,0,0,0,0,0,0,0,0,0,0,0,0,0,0,0,0,0,0,0,0,0,0,0,0,0,0,0,0,0,0,0,0,0,0)';
      OUTPUT_LOAD='(1.0,-1.0)';
    'MBB_DQS_L6':
      PIN_NUMBER='(0,CL62,0,0,0,0,0,0,0,0,0,0,0,0,0,0,0,0,0,0,0,0,0,0,0,0,0,0,0,0,0,0,0,0,0,0,0,0,0,0)';
      BIDIRECTIONAL='TRUE';
      INPUT_LOAD='(-0.01,0.01)';
      OUTPUT_LOAD='(1.0,-1.0)';
    'MBB_DQS_H2':
      PIN_NUMBER='(0,CT63,0,0,0,0,0,0,0,0,0,0,0,0,0,0,0,0,0,0,0,0,0,0,0,0,0,0,0,0,0,0,0,0,0,0,0,0,0,0)';
      BIDIRECTIONAL='TRUE';
      INPUT_LOAD='(-0.01,0.01)';
      OUTPUT_LOAD='(1.0,-1.0)';
    'MBB_CA5':
      PIN_NUMBER='(0,BK62,0,0,0,0,0,0,0,0,0,0,0,0,0,0,0,0,0,0,0,0,0,0,0,0,0,0,0,0,0,0,0,0,0,0,0,0,0,0)';
      OUTPUT_LOAD='(1.0,-1.0)';
    'MBA_DQS_H8':
      PIN_NUMBER='(0,AG62,0,0,0,0,0,0,0,0,0,0,0,0,0,0,0,0,0,0,0,0,0,0,0,0,0,0,0,0,0,0,0,0,0,0,0,0,0,0)';
      BIDIRECTIONAL='TRUE';
      INPUT_LOAD='(-0.01,0.01)';
      OUTPUT_LOAD='(1.0,-1.0)';
    'MBA_DATA30':
      PIN_NUMBER='(0,AH63,0,0,0,0,0,0,0,0,0,0,0,0,0,0,0,0,0,0,0,0,0,0,0,0,0,0,0,0,0,0,0,0,0,0,0,0,0,0)';
      BIDIRECTIONAL='TRUE';
      INPUT_LOAD='(-0.01,0.01)';
      OUTPUT_LOAD='(1.0,-1.0)';
    'MBA_CA6':
      PIN_NUMBER='(0,BB62,0,0,0,0,0,0,0,0,0,0,0,0,0,0,0,0,0,0,0,0,0,0,0,0,0,0,0,0,0,0,0,0,0,0,0,0,0,0)';
      OUTPUT_LOAD='(1.0,-1.0)';
    'MBA1_CS_L0':
      PIN_NUMBER='(0,AU64,0,0,0,0,0,0,0,0,0,0,0,0,0,0,0,0,0,0,0,0,0,0,0,0,0,0,0,0,0,0,0,0,0,0,0,0,0,0)';
      OUTPUT_LOAD='(1.0,-1.0)';
    'MBA0_CS_L1':
      PIN_NUMBER='(0,AW62,0,0,0,0,0,0,0,0,0,0,0,0,0,0,0,0,0,0,0,0,0,0,0,0,0,0,0,0,0,0,0,0,0,0,0,0,0,0)';
      OUTPUT_LOAD='(1.0,-1.0)';
    'MBB_DQS_L7':
      PIN_NUMBER='(0,CU62,0,0,0,0,0,0,0,0,0,0,0,0,0,0,0,0,0,0,0,0,0,0,0,0,0,0,0,0,0,0,0,0,0,0,0,0,0,0)';
      BIDIRECTIONAL='TRUE';
      INPUT_LOAD='(-0.01,0.01)';
      OUTPUT_LOAD='(1.0,-1.0)';
    'MBB_DQS_H3':
      PIN_NUMBER='(0,DB63,0,0,0,0,0,0,0,0,0,0,0,0,0,0,0,0,0,0,0,0,0,0,0,0,0,0,0,0,0,0,0,0,0,0,0,0,0,0)';
      BIDIRECTIONAL='TRUE';
      INPUT_LOAD='(-0.01,0.01)';
      OUTPUT_LOAD='(1.0,-1.0)';
    'MBB_CA6':
      PIN_NUMBER='(0,BK63,0,0,0,0,0,0,0,0,0,0,0,0,0,0,0,0,0,0,0,0,0,0,0,0,0,0,0,0,0,0,0,0,0,0,0,0,0,0)';
      OUTPUT_LOAD='(1.0,-1.0)';
    'MBA_DQS_H9':
      PIN_NUMBER='(0,AN62,0,0,0,0,0,0,0,0,0,0,0,0,0,0,0,0,0,0,0,0,0,0,0,0,0,0,0,0,0,0,0,0,0,0,0,0,0,0)';
      BIDIRECTIONAL='TRUE';
      INPUT_LOAD='(-0.01,0.01)';
      OUTPUT_LOAD='(1.0,-1.0)';
    'MBA_DATA31':
      PIN_NUMBER='(0,AJ62,0,0,0,0,0,0,0,0,0,0,0,0,0,0,0,0,0,0,0,0,0,0,0,0,0,0,0,0,0,0,0,0,0,0,0,0,0,0)';
      BIDIRECTIONAL='TRUE';
      INPUT_LOAD='(-0.01,0.01)';
      OUTPUT_LOAD='(1.0,-1.0)';
    'MBA_DATA20':
      PIN_NUMBER='(0,AA64,0,0,0,0,0,0,0,0,0,0,0,0,0,0,0,0,0,0,0,0,0,0,0,0,0,0,0,0,0,0,0,0,0,0,0,0,0,0)';
      BIDIRECTIONAL='TRUE';
      INPUT_LOAD='(-0.01,0.01)';
      OUTPUT_LOAD='(1.0,-1.0)';
    'MBA_CHECK0':
      PIN_NUMBER='(0,AJ64,0,0,0,0,0,0,0,0,0,0,0,0,0,0,0,0,0,0,0,0,0,0,0,0,0,0,0,0,0,0,0,0,0,0,0,0,0,0)';
      BIDIRECTIONAL='TRUE';
      INPUT_LOAD='(-0.01,0.01)';
      OUTPUT_LOAD='(1.0,-1.0)';
    'MBA1_CS_L1':
      PIN_NUMBER='(0,AV62,0,0,0,0,0,0,0,0,0,0,0,0,0,0,0,0,0,0,0,0,0,0,0,0,0,0,0,0,0,0,0,0,0,0,0,0,0,0)';
      OUTPUT_LOAD='(1.0,-1.0)';
    'MBB_DQS_L8':
      PIN_NUMBER='(0,DC62,0,0,0,0,0,0,0,0,0,0,0,0,0,0,0,0,0,0,0,0,0,0,0,0,0,0,0,0,0,0,0,0,0,0,0,0,0,0)';
      BIDIRECTIONAL='TRUE';
      INPUT_LOAD='(-0.01,0.01)';
      OUTPUT_LOAD='(1.0,-1.0)';
    'MBB_DQS_H4':
      PIN_NUMBER='(0,BY62,0,0,0,0,0,0,0,0,0,0,0,0,0,0,0,0,0,0,0,0,0,0,0,0,0,0,0,0,0,0,0,0,0,0,0,0,0,0)';
      BIDIRECTIONAL='TRUE';
      INPUT_LOAD='(-0.01,0.01)';
      OUTPUT_LOAD='(1.0,-1.0)';
    'MBA_DATA21':
      PIN_NUMBER='(0,AB62,0,0,0,0,0,0,0,0,0,0,0,0,0,0,0,0,0,0,0,0,0,0,0,0,0,0,0,0,0,0,0,0,0,0,0,0,0,0)';
      BIDIRECTIONAL='TRUE';
      INPUT_LOAD='(-0.01,0.01)';
      OUTPUT_LOAD='(1.0,-1.0)';
    'MBA_DATA10':
      PIN_NUMBER='(0,M63,0,0,0,0,0,0,0,0,0,0,0,0,0,0,0,0,0,0,0,0,0,0,0,0,0,0,0,0,0,0,0,0,0,0,0,0,0,0)';
      BIDIRECTIONAL='TRUE';
      INPUT_LOAD='(-0.01,0.01)';
      OUTPUT_LOAD='(1.0,-1.0)';
    'MBA_CHECK1':
      PIN_NUMBER='(0,AK62,0,0,0,0,0,0,0,0,0,0,0,0,0,0,0,0,0,0,0,0,0,0,0,0,0,0,0,0,0,0,0,0,0,0,0,0,0,0)';
      BIDIRECTIONAL='TRUE';
      INPUT_LOAD='(-0.01,0.01)';
      OUTPUT_LOAD='(1.0,-1.0)';
    'MBB_DQS_H9':
      PIN_NUMBER='(0,BV63,0,0,0,0,0,0,0,0,0,0,0,0,0,0,0,0,0,0,0,0,0,0,0,0,0,0,0,0,0,0,0,0,0,0,0,0,0,0)';
      BIDIRECTIONAL='TRUE';
      INPUT_LOAD='(-0.01,0.01)';
      OUTPUT_LOAD='(1.0,-1.0)';
    'MBA_PAR':
      PIN_NUMBER='(0,BC62,0,0,0,0,0,0,0,0,0,0,0,0,0,0,0,0,0,0,0,0,0,0,0,0,0,0,0,0,0,0,0,0,0,0,0,0,0,0)';
      OUTPUT_LOAD='(1.0,-1.0)';
    'MBB_PAR':
      PIN_NUMBER='(0,BL64,0,0,0,0,0,0,0,0,0,0,0,0,0,0,0,0,0,0,0,0,0,0,0,0,0,0,0,0,0,0,0,0,0,0,0,0,0,0)';
      OUTPUT_LOAD='(1.0,-1.0)';
    'MB0_CLK_H':
      PIN_NUMBER='(0,BC64,0,0,0,0,0,0,0,0,0,0,0,0,0,0,0,0,0,0,0,0,0,0,0,0,0,0,0,0,0,0,0,0,0,0,0,0,0,0)';
      OUTPUT_LOAD='(1.0,-1.0)';
    'MB0_CLK_L':
      PIN_NUMBER='(0,BD63,0,0,0,0,0,0,0,0,0,0,0,0,0,0,0,0,0,0,0,0,0,0,0,0,0,0,0,0,0,0,0,0,0,0,0,0,0,0)';
      OUTPUT_LOAD='(1.0,-1.0)';
    'MB1_CLK_H':
      PIN_NUMBER='(0,BF63,0,0,0,0,0,0,0,0,0,0,0,0,0,0,0,0,0,0,0,0,0,0,0,0,0,0,0,0,0,0,0,0,0,0,0,0,0,0)';
      OUTPUT_LOAD='(1.0,-1.0)';
    'MB1_CLK_L':
      PIN_NUMBER='(0,BG64,0,0,0,0,0,0,0,0,0,0,0,0,0,0,0,0,0,0,0,0,0,0,0,0,0,0,0,0,0,0,0,0,0,0,0,0,0,0)';
      OUTPUT_LOAD='(1.0,-1.0)';
    'MBB_DATA19':
      PIN_NUMBER='(0,CT62,0,0,0,0,0,0,0,0,0,0,0,0,0,0,0,0,0,0,0,0,0,0,0,0,0,0,0,0,0,0,0,0,0,0,0,0,0,0)';
      BIDIRECTIONAL='TRUE';
      INPUT_LOAD='(-0.01,0.01)';
      OUTPUT_LOAD='(1.0,-1.0)';
    'MBA_DATA24':
      PIN_NUMBER='(0,AC64,0,0,0,0,0,0,0,0,0,0,0,0,0,0,0,0,0,0,0,0,0,0,0,0,0,0,0,0,0,0,0,0,0,0,0,0,0,0)';
      BIDIRECTIONAL='TRUE';
      INPUT_LOAD='(-0.01,0.01)';
      OUTPUT_LOAD='(1.0,-1.0)';
    'MBB_DATA20':
      PIN_NUMBER='(0,CV63,0,0,0,0,0,0,0,0,0,0,0,0,0,0,0,0,0,0,0,0,0,0,0,0,0,0,0,0,0,0,0,0,0,0,0,0,0,0)';
      BIDIRECTIONAL='TRUE';
      INPUT_LOAD='(-0.01,0.01)';
      OUTPUT_LOAD='(1.0,-1.0)';
    'TEST39B':
      PIN_NUMBER='(0,BF62,0,0,0,0,0,0,0,0,0,0,0,0,0,0,0,0,0,0,0,0,0,0,0,0,0,0,0,0,0,0,0,0,0,0,0,0,0,0)';
      OUTPUT_LOAD='(1.0,-1.0)';
    'MC_ALERT_L':
      PIN_NUMBER='(0,0,AT55,0,0,0,0,0,0,0,0,0,0,0,0,0,0,0,0,0,0,0,0,0,0,0,0,0,0,0,0,0,0,0,0,0,0,0,0,0)';
      INPUT_LOAD='(-0.01,0.01)';
    'MC_RESET_L':
      PIN_NUMBER='(0,0,AU55,0,0,0,0,0,0,0,0,0,0,0,0,0,0,0,0,0,0,0,0,0,0,0,0,0,0,0,0,0,0,0,0,0,0,0,0,0)';
      OUTPUT_LOAD='(1.0,-1.0)';
    'MCB_DQS_H8':
      PIN_NUMBER='(0,0,DD55,0,0,0,0,0,0,0,0,0,0,0,0,0,0,0,0,0,0,0,0,0,0,0,0,0,0,0,0,0,0,0,0,0,0,0,0,0)';
      BIDIRECTIONAL='TRUE';
      INPUT_LOAD='(-0.01,0.01)';
      OUTPUT_LOAD='(1.0,-1.0)';
    'MCB_DATA30':
      PIN_NUMBER='(0,0,DE57,0,0,0,0,0,0,0,0,0,0,0,0,0,0,0,0,0,0,0,0,0,0,0,0,0,0,0,0,0,0,0,0,0,0,0,0,0)';
      BIDIRECTIONAL='TRUE';
      INPUT_LOAD='(-0.01,0.01)';
      OUTPUT_LOAD='(1.0,-1.0)';
    'MCB_DATA8':
      PIN_NUMBER='(0,0,CH56,0,0,0,0,0,0,0,0,0,0,0,0,0,0,0,0,0,0,0,0,0,0,0,0,0,0,0,0,0,0,0,0,0,0,0,0,0)';
      BIDIRECTIONAL='TRUE';
      INPUT_LOAD='(-0.01,0.01)';
      OUTPUT_LOAD='(1.0,-1.0)';
    'MCB1_CS_L1':
      PIN_NUMBER='(0,0,BM56,0,0,0,0,0,0,0,0,0,0,0,0,0,0,0,0,0,0,0,0,0,0,0,0,0,0,0,0,0,0,0,0,0,0,0,0,0)';
      OUTPUT_LOAD='(1.0,-1.0)';
    'MCB0_CS_L1':
      PIN_NUMBER='(0,0,BN57,0,0,0,0,0,0,0,0,0,0,0,0,0,0,0,0,0,0,0,0,0,0,0,0,0,0,0,0,0,0,0,0,0,0,0,0,0)';
      OUTPUT_LOAD='(1.0,-1.0)';
    'MCA_DQS_L1':
      PIN_NUMBER='(0,0,P56,0,0,0,0,0,0,0,0,0,0,0,0,0,0,0,0,0,0,0,0,0,0,0,0,0,0,0,0,0,0,0,0,0,0,0,0,0)';
      BIDIRECTIONAL='TRUE';
      INPUT_LOAD='(-0.01,0.01)';
      OUTPUT_LOAD='(1.0,-1.0)';
    'MCA_DATA25':
      PIN_NUMBER='(0,0,AD55,0,0,0,0,0,0,0,0,0,0,0,0,0,0,0,0,0,0,0,0,0,0,0,0,0,0,0,0,0,0,0,0,0,0,0,0,0)';
      BIDIRECTIONAL='TRUE';
      INPUT_LOAD='(-0.01,0.01)';
      OUTPUT_LOAD='(1.0,-1.0)';
    'MCA_DATA14':
      PIN_NUMBER='(0,0,T56,0,0,0,0,0,0,0,0,0,0,0,0,0,0,0,0,0,0,0,0,0,0,0,0,0,0,0,0,0,0,0,0,0,0,0,0,0)';
      BIDIRECTIONAL='TRUE';
      INPUT_LOAD='(-0.01,0.01)';
      OUTPUT_LOAD='(1.0,-1.0)';
    'MCA_DATA9':
      PIN_NUMBER='(0,0,M55,0,0,0,0,0,0,0,0,0,0,0,0,0,0,0,0,0,0,0,0,0,0,0,0,0,0,0,0,0,0,0,0,0,0,0,0,0)';
      BIDIRECTIONAL='TRUE';
      INPUT_LOAD='(-0.01,0.01)';
      OUTPUT_LOAD='(1.0,-1.0)';
    'MCA_CHECK5':
      PIN_NUMBER='(0,0,AP55,0,0,0,0,0,0,0,0,0,0,0,0,0,0,0,0,0,0,0,0,0,0,0,0,0,0,0,0,0,0,0,0,0,0,0,0,0)';
      BIDIRECTIONAL='TRUE';
      INPUT_LOAD='(-0.01,0.01)';
      OUTPUT_LOAD='(1.0,-1.0)';
    'MCB_DATA31':
      PIN_NUMBER='(0,0,DF55,0,0,0,0,0,0,0,0,0,0,0,0,0,0,0,0,0,0,0,0,0,0,0,0,0,0,0,0,0,0,0,0,0,0,0,0,0)';
      BIDIRECTIONAL='TRUE';
      INPUT_LOAD='(-0.01,0.01)';
      OUTPUT_LOAD='(1.0,-1.0)';
    'MCB_DATA20':
      PIN_NUMBER='(0,0,CV56,0,0,0,0,0,0,0,0,0,0,0,0,0,0,0,0,0,0,0,0,0,0,0,0,0,0,0,0,0,0,0,0,0,0,0,0,0)';
      BIDIRECTIONAL='TRUE';
      INPUT_LOAD='(-0.01,0.01)';
      OUTPUT_LOAD='(1.0,-1.0)';
    'MCB_DATA9':
      PIN_NUMBER='(0,0,CJ55,0,0,0,0,0,0,0,0,0,0,0,0,0,0,0,0,0,0,0,0,0,0,0,0,0,0,0,0,0,0,0,0,0,0,0,0,0)';
      BIDIRECTIONAL='TRUE';
      INPUT_LOAD='(-0.01,0.01)';
      OUTPUT_LOAD='(1.0,-1.0)';
    'MCB_CHECK0':
      PIN_NUMBER='(0,0,BY56,0,0,0,0,0,0,0,0,0,0,0,0,0,0,0,0,0,0,0,0,0,0,0,0,0,0,0,0,0,0,0,0,0,0,0,0,0)';
      BIDIRECTIONAL='TRUE';
      INPUT_LOAD='(-0.01,0.01)';
      OUTPUT_LOAD='(1.0,-1.0)';
    'MCA_DQS_L2':
      PIN_NUMBER='(0,0,Y56,0,0,0,0,0,0,0,0,0,0,0,0,0,0,0,0,0,0,0,0,0,0,0,0,0,0,0,0,0,0,0,0,0,0,0,0,0)';
      BIDIRECTIONAL='TRUE';
      INPUT_LOAD='(-0.01,0.01)';
      OUTPUT_LOAD='(1.0,-1.0)';
    'MCA_DATA26':
      PIN_NUMBER='(0,0,AD56,0,0,0,0,0,0,0,0,0,0,0,0,0,0,0,0,0,0,0,0,0,0,0,0,0,0,0,0,0,0,0,0,0,0,0,0,0)';
      BIDIRECTIONAL='TRUE';
      INPUT_LOAD='(-0.01,0.01)';
      OUTPUT_LOAD='(1.0,-1.0)';
    'MCA_DATA15':
      PIN_NUMBER='(0,0,U55,0,0,0,0,0,0,0,0,0,0,0,0,0,0,0,0,0,0,0,0,0,0,0,0,0,0,0,0,0,0,0,0,0,0,0,0,0)';
      BIDIRECTIONAL='TRUE';
      INPUT_LOAD='(-0.01,0.01)';
      OUTPUT_LOAD='(1.0,-1.0)';
    'MCA_CHECK6':
      PIN_NUMBER='(0,0,AP56,0,0,0,0,0,0,0,0,0,0,0,0,0,0,0,0,0,0,0,0,0,0,0,0,0,0,0,0,0,0,0,0,0,0,0,0,0)';
      BIDIRECTIONAL='TRUE';
      INPUT_LOAD='(-0.01,0.01)';
      OUTPUT_LOAD='(1.0,-1.0)';
    'MCA0_RSP_L':
      PIN_NUMBER='(0,0,BN55,0,0,0,0,0,0,0,0,0,0,0,0,0,0,0,0,0,0,0,0,0,0,0,0,0,0,0,0,0,0,0,0,0,0,0,0,0)';
      INPUT_LOAD='(-0.01,0.01)';
    'MCB_DATA21':
      PIN_NUMBER='(0,0,CW55,0,0,0,0,0,0,0,0,0,0,0,0,0,0,0,0,0,0,0,0,0,0,0,0,0,0,0,0,0,0,0,0,0,0,0,0,0)';
      BIDIRECTIONAL='TRUE';
      INPUT_LOAD='(-0.01,0.01)';
      OUTPUT_LOAD='(1.0,-1.0)';
    'MCB_DATA10':
      PIN_NUMBER='(0,0,CJ57,0,0,0,0,0,0,0,0,0,0,0,0,0,0,0,0,0,0,0,0,0,0,0,0,0,0,0,0,0,0,0,0,0,0,0,0,0)';
      BIDIRECTIONAL='TRUE';
      INPUT_LOAD='(-0.01,0.01)';
      OUTPUT_LOAD='(1.0,-1.0)';
    'MCB_CHECK1':
      PIN_NUMBER='(0,0,CA55,0,0,0,0,0,0,0,0,0,0,0,0,0,0,0,0,0,0,0,0,0,0,0,0,0,0,0,0,0,0,0,0,0,0,0,0,0)';
      BIDIRECTIONAL='TRUE';
      INPUT_LOAD='(-0.01,0.01)';
      OUTPUT_LOAD='(1.0,-1.0)';
    'MCA_DQS_L3':
      PIN_NUMBER='(0,0,AF56,0,0,0,0,0,0,0,0,0,0,0,0,0,0,0,0,0,0,0,0,0,0,0,0,0,0,0,0,0,0,0,0,0,0,0,0,0)';
      BIDIRECTIONAL='TRUE';
      INPUT_LOAD='(-0.01,0.01)';
      OUTPUT_LOAD='(1.0,-1.0)';
    'MCA_DATA27':
      PIN_NUMBER='(0,0,AE55,0,0,0,0,0,0,0,0,0,0,0,0,0,0,0,0,0,0,0,0,0,0,0,0,0,0,0,0,0,0,0,0,0,0,0,0,0)';
      BIDIRECTIONAL='TRUE';
      INPUT_LOAD='(-0.01,0.01)';
      OUTPUT_LOAD='(1.0,-1.0)';
    'MCA_DATA16':
      PIN_NUMBER='(0,0,U57,0,0,0,0,0,0,0,0,0,0,0,0,0,0,0,0,0,0,0,0,0,0,0,0,0,0,0,0,0,0,0,0,0,0,0,0,0)';
      BIDIRECTIONAL='TRUE';
      INPUT_LOAD='(-0.01,0.01)';
      OUTPUT_LOAD='(1.0,-1.0)';
    'MCA_CHECK7':
      PIN_NUMBER='(0,0,AR55,0,0,0,0,0,0,0,0,0,0,0,0,0,0,0,0,0,0,0,0,0,0,0,0,0,0,0,0,0,0,0,0,0,0,0,0,0)';
      BIDIRECTIONAL='TRUE';
      INPUT_LOAD='(-0.01,0.01)';
      OUTPUT_LOAD='(1.0,-1.0)';
    'MCA1_RSP_L':
      PIN_NUMBER='(0,0,BP55,0,0,0,0,0,0,0,0,0,0,0,0,0,0,0,0,0,0,0,0,0,0,0,0,0,0,0,0,0,0,0,0,0,0,0,0,0)';
      INPUT_LOAD='(-0.01,0.01)';
    'MCB_DATA22':
      PIN_NUMBER='(0,0,CW57,0,0,0,0,0,0,0,0,0,0,0,0,0,0,0,0,0,0,0,0,0,0,0,0,0,0,0,0,0,0,0,0,0,0,0,0,0)';
      BIDIRECTIONAL='TRUE';
      INPUT_LOAD='(-0.01,0.01)';
      OUTPUT_LOAD='(1.0,-1.0)';
    'MCB_DATA11':
      PIN_NUMBER='(0,0,CK55,0,0,0,0,0,0,0,0,0,0,0,0,0,0,0,0,0,0,0,0,0,0,0,0,0,0,0,0,0,0,0,0,0,0,0,0,0)';
      BIDIRECTIONAL='TRUE';
      INPUT_LOAD='(-0.01,0.01)';
      OUTPUT_LOAD='(1.0,-1.0)';
    'MCB_CHECK2':
      PIN_NUMBER='(0,0,CA57,0,0,0,0,0,0,0,0,0,0,0,0,0,0,0,0,0,0,0,0,0,0,0,0,0,0,0,0,0,0,0,0,0,0,0,0,0)';
      BIDIRECTIONAL='TRUE';
      INPUT_LOAD='(-0.01,0.01)';
      OUTPUT_LOAD='(1.0,-1.0)';
    'MCA_DQS_L4':
      PIN_NUMBER='(0,0,AM56,0,0,0,0,0,0,0,0,0,0,0,0,0,0,0,0,0,0,0,0,0,0,0,0,0,0,0,0,0,0,0,0,0,0,0,0,0)';
      BIDIRECTIONAL='TRUE';
      INPUT_LOAD='(-0.01,0.01)';
      OUTPUT_LOAD='(1.0,-1.0)';
    'MCA_DQS_H0':
      PIN_NUMBER='(0,0,G57,0,0,0,0,0,0,0,0,0,0,0,0,0,0,0,0,0,0,0,0,0,0,0,0,0,0,0,0,0,0,0,0,0,0,0,0,0)';
      BIDIRECTIONAL='TRUE';
      INPUT_LOAD='(-0.01,0.01)';
      OUTPUT_LOAD='(1.0,-1.0)';
    'MCA_DATA28':
      PIN_NUMBER='(0,0,AG57,0,0,0,0,0,0,0,0,0,0,0,0,0,0,0,0,0,0,0,0,0,0,0,0,0,0,0,0,0,0,0,0,0,0,0,0,0)';
      BIDIRECTIONAL='TRUE';
      INPUT_LOAD='(-0.01,0.01)';
      OUTPUT_LOAD='(1.0,-1.0)';
    'MCA_DATA17':
      PIN_NUMBER='(0,0,V55,0,0,0,0,0,0,0,0,0,0,0,0,0,0,0,0,0,0,0,0,0,0,0,0,0,0,0,0,0,0,0,0,0,0,0,0,0)';
      BIDIRECTIONAL='TRUE';
      INPUT_LOAD='(-0.01,0.01)';
      OUTPUT_LOAD='(1.0,-1.0)';
    'MCB_DATA23':
      PIN_NUMBER='(0,0,CY55,0,0,0,0,0,0,0,0,0,0,0,0,0,0,0,0,0,0,0,0,0,0,0,0,0,0,0,0,0,0,0,0,0,0,0,0,0)';
      BIDIRECTIONAL='TRUE';
      INPUT_LOAD='(-0.01,0.01)';
      OUTPUT_LOAD='(1.0,-1.0)';
    'MCB_DATA12':
      PIN_NUMBER='(0,0,CM56,0,0,0,0,0,0,0,0,0,0,0,0,0,0,0,0,0,0,0,0,0,0,0,0,0,0,0,0,0,0,0,0,0,0,0,0,0)';
      BIDIRECTIONAL='TRUE';
      INPUT_LOAD='(-0.01,0.01)';
      OUTPUT_LOAD='(1.0,-1.0)';
    'MCB_CHECK3':
      PIN_NUMBER='(0,0,CB55,0,0,0,0,0,0,0,0,0,0,0,0,0,0,0,0,0,0,0,0,0,0,0,0,0,0,0,0,0,0,0,0,0,0,0,0,0)';
      BIDIRECTIONAL='TRUE';
      INPUT_LOAD='(-0.01,0.01)';
      OUTPUT_LOAD='(1.0,-1.0)';
    'MCA_DQS_L5':
      PIN_NUMBER='(0,0,H55,0,0,0,0,0,0,0,0,0,0,0,0,0,0,0,0,0,0,0,0,0,0,0,0,0,0,0,0,0,0,0,0,0,0,0,0,0)';
      BIDIRECTIONAL='TRUE';
      INPUT_LOAD='(-0.01,0.01)';
      OUTPUT_LOAD='(1.0,-1.0)';
    'MCA_DQS_H1':
      PIN_NUMBER='(0,0,N57,0,0,0,0,0,0,0,0,0,0,0,0,0,0,0,0,0,0,0,0,0,0,0,0,0,0,0,0,0,0,0,0,0,0,0,0,0)';
      BIDIRECTIONAL='TRUE';
      INPUT_LOAD='(-0.01,0.01)';
      OUTPUT_LOAD='(1.0,-1.0)';
    'MCA_DATA29':
      PIN_NUMBER='(0,0,AH55,0,0,0,0,0,0,0,0,0,0,0,0,0,0,0,0,0,0,0,0,0,0,0,0,0,0,0,0,0,0,0,0,0,0,0,0,0)';
      BIDIRECTIONAL='TRUE';
      INPUT_LOAD='(-0.01,0.01)';
      OUTPUT_LOAD='(1.0,-1.0)';
    'MCA_DATA18':
      PIN_NUMBER='(0,0,V56,0,0,0,0,0,0,0,0,0,0,0,0,0,0,0,0,0,0,0,0,0,0,0,0,0,0,0,0,0,0,0,0,0,0,0,0,0)';
      BIDIRECTIONAL='TRUE';
      INPUT_LOAD='(-0.01,0.01)';
      OUTPUT_LOAD='(1.0,-1.0)';
    'MCB_DQS_L0':
      PIN_NUMBER='(0,0,CE57,0,0,0,0,0,0,0,0,0,0,0,0,0,0,0,0,0,0,0,0,0,0,0,0,0,0,0,0,0,0,0,0,0,0,0,0,0)';
      BIDIRECTIONAL='TRUE';
      INPUT_LOAD='(-0.01,0.01)';
      OUTPUT_LOAD='(1.0,-1.0)';
    'MCB_DATA24':
      PIN_NUMBER='(0,0,CY56,0,0,0,0,0,0,0,0,0,0,0,0,0,0,0,0,0,0,0,0,0,0,0,0,0,0,0,0,0,0,0,0,0,0,0,0,0)';
      BIDIRECTIONAL='TRUE';
      INPUT_LOAD='(-0.01,0.01)';
      OUTPUT_LOAD='(1.0,-1.0)';
    'MCB_DATA13':
      PIN_NUMBER='(0,0,CN55,0,0,0,0,0,0,0,0,0,0,0,0,0,0,0,0,0,0,0,0,0,0,0,0,0,0,0,0,0,0,0,0,0,0,0,0,0)';
      BIDIRECTIONAL='TRUE';
      INPUT_LOAD='(-0.01,0.01)';
      OUTPUT_LOAD='(1.0,-1.0)';
    'MCB_CHECK4':
      PIN_NUMBER='(0,0,BT56,0,0,0,0,0,0,0,0,0,0,0,0,0,0,0,0,0,0,0,0,0,0,0,0,0,0,0,0,0,0,0,0,0,0,0,0,0)';
      BIDIRECTIONAL='TRUE';
      INPUT_LOAD='(-0.01,0.01)';
      OUTPUT_LOAD='(1.0,-1.0)';
    'MCA_DQS_L6':
      PIN_NUMBER='(0,0,P55,0,0,0,0,0,0,0,0,0,0,0,0,0,0,0,0,0,0,0,0,0,0,0,0,0,0,0,0,0,0,0,0,0,0,0,0,0)';
      BIDIRECTIONAL='TRUE';
      INPUT_LOAD='(-0.01,0.01)';
      OUTPUT_LOAD='(1.0,-1.0)';
    'MCA_DQS_H2':
      PIN_NUMBER='(0,0,W57,0,0,0,0,0,0,0,0,0,0,0,0,0,0,0,0,0,0,0,0,0,0,0,0,0,0,0,0,0,0,0,0,0,0,0,0,0)';
      BIDIRECTIONAL='TRUE';
      INPUT_LOAD='(-0.01,0.01)';
      OUTPUT_LOAD='(1.0,-1.0)';
    'MCA_DATA19':
      PIN_NUMBER='(0,0,W55,0,0,0,0,0,0,0,0,0,0,0,0,0,0,0,0,0,0,0,0,0,0,0,0,0,0,0,0,0,0,0,0,0,0,0,0,0)';
      BIDIRECTIONAL='TRUE';
      INPUT_LOAD='(-0.01,0.01)';
      OUTPUT_LOAD='(1.0,-1.0)';
    'MCB_DQS_L1':
      PIN_NUMBER='(0,0,CL57,0,0,0,0,0,0,0,0,0,0,0,0,0,0,0,0,0,0,0,0,0,0,0,0,0,0,0,0,0,0,0,0,0,0,0,0,0)';
      BIDIRECTIONAL='TRUE';
      INPUT_LOAD='(-0.01,0.01)';
      OUTPUT_LOAD='(1.0,-1.0)';
    'MCB_DATA25':
      PIN_NUMBER='(0,0,DA55,0,0,0,0,0,0,0,0,0,0,0,0,0,0,0,0,0,0,0,0,0,0,0,0,0,0,0,0,0,0,0,0,0,0,0,0,0)';
      BIDIRECTIONAL='TRUE';
      INPUT_LOAD='(-0.01,0.01)';
      OUTPUT_LOAD='(1.0,-1.0)';
    'MCB_DATA14':
      PIN_NUMBER='(0,0,CN57,0,0,0,0,0,0,0,0,0,0,0,0,0,0,0,0,0,0,0,0,0,0,0,0,0,0,0,0,0,0,0,0,0,0,0,0,0)';
      BIDIRECTIONAL='TRUE';
      INPUT_LOAD='(-0.01,0.01)';
      OUTPUT_LOAD='(1.0,-1.0)';
    'MCB_CHECK5':
      PIN_NUMBER='(0,0,BU55,0,0,0,0,0,0,0,0,0,0,0,0,0,0,0,0,0,0,0,0,0,0,0,0,0,0,0,0,0,0,0,0,0,0,0,0,0)';
      BIDIRECTIONAL='TRUE';
      INPUT_LOAD='(-0.01,0.01)';
      OUTPUT_LOAD='(1.0,-1.0)';
    'MCA_DQS_L7':
      PIN_NUMBER='(0,0,Y55,0,0,0,0,0,0,0,0,0,0,0,0,0,0,0,0,0,0,0,0,0,0,0,0,0,0,0,0,0,0,0,0,0,0,0,0,0)';
      BIDIRECTIONAL='TRUE';
      INPUT_LOAD='(-0.01,0.01)';
      OUTPUT_LOAD='(1.0,-1.0)';
    'MCA_DQS_H3':
      PIN_NUMBER='(0,0,AE57,0,0,0,0,0,0,0,0,0,0,0,0,0,0,0,0,0,0,0,0,0,0,0,0,0,0,0,0,0,0,0,0,0,0,0,0,0)';
      BIDIRECTIONAL='TRUE';
      INPUT_LOAD='(-0.01,0.01)';
      OUTPUT_LOAD='(1.0,-1.0)';
    'MCB_DQS_L2':
      PIN_NUMBER='(0,0,CU57,0,0,0,0,0,0,0,0,0,0,0,0,0,0,0,0,0,0,0,0,0,0,0,0,0,0,0,0,0,0,0,0,0,0,0,0,0)';
      BIDIRECTIONAL='TRUE';
      INPUT_LOAD='(-0.01,0.01)';
      OUTPUT_LOAD='(1.0,-1.0)';
    'MCB_DATA26':
      PIN_NUMBER='(0,0,DA57,0,0,0,0,0,0,0,0,0,0,0,0,0,0,0,0,0,0,0,0,0,0,0,0,0,0,0,0,0,0,0,0,0,0,0,0,0)';
      BIDIRECTIONAL='TRUE';
      INPUT_LOAD='(-0.01,0.01)';
      OUTPUT_LOAD='(1.0,-1.0)';
    'MCB_DATA15':
      PIN_NUMBER='(0,0,CP55,0,0,0,0,0,0,0,0,0,0,0,0,0,0,0,0,0,0,0,0,0,0,0,0,0,0,0,0,0,0,0,0,0,0,0,0,0)';
      BIDIRECTIONAL='TRUE';
      INPUT_LOAD='(-0.01,0.01)';
      OUTPUT_LOAD='(1.0,-1.0)';
    'MCB_CHECK6':
      PIN_NUMBER='(0,0,BU57,0,0,0,0,0,0,0,0,0,0,0,0,0,0,0,0,0,0,0,0,0,0,0,0,0,0,0,0,0,0,0,0,0,0,0,0,0)';
      BIDIRECTIONAL='TRUE';
      INPUT_LOAD='(-0.01,0.01)';
      OUTPUT_LOAD='(1.0,-1.0)';
    'MCA_DQS_L8':
      PIN_NUMBER='(0,0,AF55,0,0,0,0,0,0,0,0,0,0,0,0,0,0,0,0,0,0,0,0,0,0,0,0,0,0,0,0,0,0,0,0,0,0,0,0,0)';
      BIDIRECTIONAL='TRUE';
      INPUT_LOAD='(-0.01,0.01)';
      OUTPUT_LOAD='(1.0,-1.0)';
    'MCA_DQS_H4':
      PIN_NUMBER='(0,0,AL57,0,0,0,0,0,0,0,0,0,0,0,0,0,0,0,0,0,0,0,0,0,0,0,0,0,0,0,0,0,0,0,0,0,0,0,0,0)';
      BIDIRECTIONAL='TRUE';
      INPUT_LOAD='(-0.01,0.01)';
      OUTPUT_LOAD='(1.0,-1.0)';
    'MCA_CA0':
      PIN_NUMBER='(0,0,AW57,0,0,0,0,0,0,0,0,0,0,0,0,0,0,0,0,0,0,0,0,0,0,0,0,0,0,0,0,0,0,0,0,0,0,0,0,0)';
      OUTPUT_LOAD='(1.0,-1.0)';
    'MCB_DQS_L3':
      PIN_NUMBER='(0,0,DC57,0,0,0,0,0,0,0,0,0,0,0,0,0,0,0,0,0,0,0,0,0,0,0,0,0,0,0,0,0,0,0,0,0,0,0,0,0)';
      BIDIRECTIONAL='TRUE';
      INPUT_LOAD='(-0.01,0.01)';
      OUTPUT_LOAD='(1.0,-1.0)';
    'MCB_DATA27':
      PIN_NUMBER='(0,0,DB55,0,0,0,0,0,0,0,0,0,0,0,0,0,0,0,0,0,0,0,0,0,0,0,0,0,0,0,0,0,0,0,0,0,0,0,0,0)';
      BIDIRECTIONAL='TRUE';
      INPUT_LOAD='(-0.01,0.01)';
      OUTPUT_LOAD='(1.0,-1.0)';
    'MCB_DATA16':
      PIN_NUMBER='(0,0,CP56,0,0,0,0,0,0,0,0,0,0,0,0,0,0,0,0,0,0,0,0,0,0,0,0,0,0,0,0,0,0,0,0,0,0,0,0,0)';
      BIDIRECTIONAL='TRUE';
      INPUT_LOAD='(-0.01,0.01)';
      OUTPUT_LOAD='(1.0,-1.0)';
    'MCB_CHECK7':
      PIN_NUMBER='(0,0,BV55,0,0,0,0,0,0,0,0,0,0,0,0,0,0,0,0,0,0,0,0,0,0,0,0,0,0,0,0,0,0,0,0,0,0,0,0,0)';
      BIDIRECTIONAL='TRUE';
      INPUT_LOAD='(-0.01,0.01)';
      OUTPUT_LOAD='(1.0,-1.0)';
    'MCB_CA0':
      PIN_NUMBER='(0,0,BG55,0,0,0,0,0,0,0,0,0,0,0,0,0,0,0,0,0,0,0,0,0,0,0,0,0,0,0,0,0,0,0,0,0,0,0,0,0)';
      OUTPUT_LOAD='(1.0,-1.0)';
    'MCB1_RSP_L':
      PIN_NUMBER='(0,0,BR57,0,0,0,0,0,0,0,0,0,0,0,0,0,0,0,0,0,0,0,0,0,0,0,0,0,0,0,0,0,0,0,0,0,0,0,0,0)';
      INPUT_LOAD='(-0.01,0.01)';
    'MCB0_RSP_L':
      PIN_NUMBER='(0,0,BP56,0,0,0,0,0,0,0,0,0,0,0,0,0,0,0,0,0,0,0,0,0,0,0,0,0,0,0,0,0,0,0,0,0,0,0,0,0)';
      INPUT_LOAD='(-0.01,0.01)';
    'MCA_DQS_L9':
      PIN_NUMBER='(0,0,AM55,0,0,0,0,0,0,0,0,0,0,0,0,0,0,0,0,0,0,0,0,0,0,0,0,0,0,0,0,0,0,0,0,0,0,0,0,0)';
      BIDIRECTIONAL='TRUE';
      INPUT_LOAD='(-0.01,0.01)';
      OUTPUT_LOAD='(1.0,-1.0)';
    'MCA_DQS_H5':
      PIN_NUMBER='(0,0,J55,0,0,0,0,0,0,0,0,0,0,0,0,0,0,0,0,0,0,0,0,0,0,0,0,0,0,0,0,0,0,0,0,0,0,0,0,0)';
      BIDIRECTIONAL='TRUE';
      INPUT_LOAD='(-0.01,0.01)';
      OUTPUT_LOAD='(1.0,-1.0)';
    'MCA_DATA0':
      PIN_NUMBER='(0,0,E57,0,0,0,0,0,0,0,0,0,0,0,0,0,0,0,0,0,0,0,0,0,0,0,0,0,0,0,0,0,0,0,0,0,0,0,0,0)';
      BIDIRECTIONAL='TRUE';
      INPUT_LOAD='(-0.01,0.01)';
      OUTPUT_LOAD='(1.0,-1.0)';
    'MCA_CA1':
      PIN_NUMBER='(0,0,AY56,0,0,0,0,0,0,0,0,0,0,0,0,0,0,0,0,0,0,0,0,0,0,0,0,0,0,0,0,0,0,0,0,0,0,0,0,0)';
      OUTPUT_LOAD='(1.0,-1.0)';
    'MCB_DQS_L4':
      PIN_NUMBER='(0,0,BW55,0,0,0,0,0,0,0,0,0,0,0,0,0,0,0,0,0,0,0,0,0,0,0,0,0,0,0,0,0,0,0,0,0,0,0,0,0)';
      BIDIRECTIONAL='TRUE';
      INPUT_LOAD='(-0.01,0.01)';
      OUTPUT_LOAD='(1.0,-1.0)';
    'MCB_DQS_H0':
      PIN_NUMBER='(0,0,CD56,0,0,0,0,0,0,0,0,0,0,0,0,0,0,0,0,0,0,0,0,0,0,0,0,0,0,0,0,0,0,0,0,0,0,0,0,0)';
      BIDIRECTIONAL='TRUE';
      INPUT_LOAD='(-0.01,0.01)';
      OUTPUT_LOAD='(1.0,-1.0)';
    'MCB_DATA28':
      PIN_NUMBER='(0,0,DD56,0,0,0,0,0,0,0,0,0,0,0,0,0,0,0,0,0,0,0,0,0,0,0,0,0,0,0,0,0,0,0,0,0,0,0,0,0)';
      BIDIRECTIONAL='TRUE';
      INPUT_LOAD='(-0.01,0.01)';
      OUTPUT_LOAD='(1.0,-1.0)';
    'MCB_DATA17':
      PIN_NUMBER='(0,0,CR55,0,0,0,0,0,0,0,0,0,0,0,0,0,0,0,0,0,0,0,0,0,0,0,0,0,0,0,0,0,0,0,0,0,0,0,0,0)';
      BIDIRECTIONAL='TRUE';
      INPUT_LOAD='(-0.01,0.01)';
      OUTPUT_LOAD='(1.0,-1.0)';
    'MCB_DATA0':
      PIN_NUMBER='(0,0,CB56,0,0,0,0,0,0,0,0,0,0,0,0,0,0,0,0,0,0,0,0,0,0,0,0,0,0,0,0,0,0,0,0,0,0,0,0,0)';
      BIDIRECTIONAL='TRUE';
      INPUT_LOAD='(-0.01,0.01)';
      OUTPUT_LOAD='(1.0,-1.0)';
    'MCB_CA1':
      PIN_NUMBER='(0,0,BH55,0,0,0,0,0,0,0,0,0,0,0,0,0,0,0,0,0,0,0,0,0,0,0,0,0,0,0,0,0,0,0,0,0,0,0,0,0)';
      OUTPUT_LOAD='(1.0,-1.0)';
    'MCA_DQS_H6':
      PIN_NUMBER='(0,0,R55,0,0,0,0,0,0,0,0,0,0,0,0,0,0,0,0,0,0,0,0,0,0,0,0,0,0,0,0,0,0,0,0,0,0,0,0,0)';
      BIDIRECTIONAL='TRUE';
      INPUT_LOAD='(-0.01,0.01)';
      OUTPUT_LOAD='(1.0,-1.0)';
    'MCA_DATA1':
      PIN_NUMBER='(0,0,F55,0,0,0,0,0,0,0,0,0,0,0,0,0,0,0,0,0,0,0,0,0,0,0,0,0,0,0,0,0,0,0,0,0,0,0,0,0)';
      BIDIRECTIONAL='TRUE';
      INPUT_LOAD='(-0.01,0.01)';
      OUTPUT_LOAD='(1.0,-1.0)';
    'MCA_CA2':
      PIN_NUMBER='(0,0,AY55,0,0,0,0,0,0,0,0,0,0,0,0,0,0,0,0,0,0,0,0,0,0,0,0,0,0,0,0,0,0,0,0,0,0,0,0,0)';
      OUTPUT_LOAD='(1.0,-1.0)';
    'MCA0_CS_L0':
      PIN_NUMBER='(0,0,AV56,0,0,0,0,0,0,0,0,0,0,0,0,0,0,0,0,0,0,0,0,0,0,0,0,0,0,0,0,0,0,0,0,0,0,0,0,0)';
      OUTPUT_LOAD='(1.0,-1.0)';
    'MCB_DQS_L5':
      PIN_NUMBER='(0,0,CE55,0,0,0,0,0,0,0,0,0,0,0,0,0,0,0,0,0,0,0,0,0,0,0,0,0,0,0,0,0,0,0,0,0,0,0,0,0)';
      BIDIRECTIONAL='TRUE';
      INPUT_LOAD='(-0.01,0.01)';
      OUTPUT_LOAD='(1.0,-1.0)';
    'MCB_DQS_H1':
      PIN_NUMBER='(0,0,CK56,0,0,0,0,0,0,0,0,0,0,0,0,0,0,0,0,0,0,0,0,0,0,0,0,0,0,0,0,0,0,0,0,0,0,0,0,0)';
      BIDIRECTIONAL='TRUE';
      INPUT_LOAD='(-0.01,0.01)';
      OUTPUT_LOAD='(1.0,-1.0)';
    'MCB_DATA29':
      PIN_NUMBER='(0,0,DE55,0,0,0,0,0,0,0,0,0,0,0,0,0,0,0,0,0,0,0,0,0,0,0,0,0,0,0,0,0,0,0,0,0,0,0,0,0)';
      BIDIRECTIONAL='TRUE';
      INPUT_LOAD='(-0.01,0.01)';
      OUTPUT_LOAD='(1.0,-1.0)';
    'MCB_DATA18':
      PIN_NUMBER='(0,0,CR57,0,0,0,0,0,0,0,0,0,0,0,0,0,0,0,0,0,0,0,0,0,0,0,0,0,0,0,0,0,0,0,0,0,0,0,0,0)';
      BIDIRECTIONAL='TRUE';
      INPUT_LOAD='(-0.01,0.01)';
      OUTPUT_LOAD='(1.0,-1.0)';
    'MCB_DATA1':
      PIN_NUMBER='(0,0,CC55,0,0,0,0,0,0,0,0,0,0,0,0,0,0,0,0,0,0,0,0,0,0,0,0,0,0,0,0,0,0,0,0,0,0,0,0,0)';
      BIDIRECTIONAL='TRUE';
      INPUT_LOAD='(-0.01,0.01)';
      OUTPUT_LOAD='(1.0,-1.0)';
    'MCB_CA2':
      PIN_NUMBER='(0,0,BH56,0,0,0,0,0,0,0,0,0,0,0,0,0,0,0,0,0,0,0,0,0,0,0,0,0,0,0,0,0,0,0,0,0,0,0,0,0)';
      OUTPUT_LOAD='(1.0,-1.0)';
    'MCA_DQS_H7':
      PIN_NUMBER='(0,0,AA55,0,0,0,0,0,0,0,0,0,0,0,0,0,0,0,0,0,0,0,0,0,0,0,0,0,0,0,0,0,0,0,0,0,0,0,0,0)';
      BIDIRECTIONAL='TRUE';
      INPUT_LOAD='(-0.01,0.01)';
      OUTPUT_LOAD='(1.0,-1.0)';
    'MCA_DATA2':
      PIN_NUMBER='(0,0,F56,0,0,0,0,0,0,0,0,0,0,0,0,0,0,0,0,0,0,0,0,0,0,0,0,0,0,0,0,0,0,0,0,0,0,0,0,0)';
      BIDIRECTIONAL='TRUE';
      INPUT_LOAD='(-0.01,0.01)';
      OUTPUT_LOAD='(1.0,-1.0)';
    'MCA_CA3':
      PIN_NUMBER='(0,0,BA55,0,0,0,0,0,0,0,0,0,0,0,0,0,0,0,0,0,0,0,0,0,0,0,0,0,0,0,0,0,0,0,0,0,0,0,0,0)';
      OUTPUT_LOAD='(1.0,-1.0)';
    'MCA1_CS_L0':
      PIN_NUMBER='(0,0,AU57,0,0,0,0,0,0,0,0,0,0,0,0,0,0,0,0,0,0,0,0,0,0,0,0,0,0,0,0,0,0,0,0,0,0,0,0,0)';
      OUTPUT_LOAD='(1.0,-1.0)';
    'MCA0_CS_L1':
      PIN_NUMBER='(0,0,AW55,0,0,0,0,0,0,0,0,0,0,0,0,0,0,0,0,0,0,0,0,0,0,0,0,0,0,0,0,0,0,0,0,0,0,0,0,0)';
      OUTPUT_LOAD='(1.0,-1.0)';
    'MCB_DQS_L6':
      PIN_NUMBER='(0,0,CL55,0,0,0,0,0,0,0,0,0,0,0,0,0,0,0,0,0,0,0,0,0,0,0,0,0,0,0,0,0,0,0,0,0,0,0,0,0)';
      BIDIRECTIONAL='TRUE';
      INPUT_LOAD='(-0.01,0.01)';
      OUTPUT_LOAD='(1.0,-1.0)';
    'MCB_DQS_H2':
      PIN_NUMBER='(0,0,CT56,0,0,0,0,0,0,0,0,0,0,0,0,0,0,0,0,0,0,0,0,0,0,0,0,0,0,0,0,0,0,0,0,0,0,0,0,0)';
      BIDIRECTIONAL='TRUE';
      INPUT_LOAD='(-0.01,0.01)';
      OUTPUT_LOAD='(1.0,-1.0)';
    'MCB_DATA19':
      PIN_NUMBER='(0,0,CT55,0,0,0,0,0,0,0,0,0,0,0,0,0,0,0,0,0,0,0,0,0,0,0,0,0,0,0,0,0,0,0,0,0,0,0,0,0)';
      BIDIRECTIONAL='TRUE';
      INPUT_LOAD='(-0.01,0.01)';
      OUTPUT_LOAD='(1.0,-1.0)';
    'MCB_DATA2':
      PIN_NUMBER='(0,0,CC57,0,0,0,0,0,0,0,0,0,0,0,0,0,0,0,0,0,0,0,0,0,0,0,0,0,0,0,0,0,0,0,0,0,0,0,0,0)';
      BIDIRECTIONAL='TRUE';
      INPUT_LOAD='(-0.01,0.01)';
      OUTPUT_LOAD='(1.0,-1.0)';
    'MCB_CA3':
      PIN_NUMBER='(0,0,BJ57,0,0,0,0,0,0,0,0,0,0,0,0,0,0,0,0,0,0,0,0,0,0,0,0,0,0,0,0,0,0,0,0,0,0,0,0,0)';
      OUTPUT_LOAD='(1.0,-1.0)';
    'MCA_DQS_H8':
      PIN_NUMBER='(0,0,AG55,0,0,0,0,0,0,0,0,0,0,0,0,0,0,0,0,0,0,0,0,0,0,0,0,0,0,0,0,0,0,0,0,0,0,0,0,0)';
      BIDIRECTIONAL='TRUE';
      INPUT_LOAD='(-0.01,0.01)';
      OUTPUT_LOAD='(1.0,-1.0)';
    'MCA_DATA30':
      PIN_NUMBER='(0,0,AH56,0,0,0,0,0,0,0,0,0,0,0,0,0,0,0,0,0,0,0,0,0,0,0,0,0,0,0,0,0,0,0,0,0,0,0,0,0)';
      BIDIRECTIONAL='TRUE';
      INPUT_LOAD='(-0.01,0.01)';
      OUTPUT_LOAD='(1.0,-1.0)';
    'MCA_DATA3':
      PIN_NUMBER='(0,0,G55,0,0,0,0,0,0,0,0,0,0,0,0,0,0,0,0,0,0,0,0,0,0,0,0,0,0,0,0,0,0,0,0,0,0,0,0,0)';
      BIDIRECTIONAL='TRUE';
      INPUT_LOAD='(-0.01,0.01)';
      OUTPUT_LOAD='(1.0,-1.0)';
    'MCA_CA4':
      PIN_NUMBER='(0,0,BA57,0,0,0,0,0,0,0,0,0,0,0,0,0,0,0,0,0,0,0,0,0,0,0,0,0,0,0,0,0,0,0,0,0,0,0,0,0)';
      OUTPUT_LOAD='(1.0,-1.0)';
    'MCA1_CS_L1':
      PIN_NUMBER='(0,0,AV55,0,0,0,0,0,0,0,0,0,0,0,0,0,0,0,0,0,0,0,0,0,0,0,0,0,0,0,0,0,0,0,0,0,0,0,0,0)';
      OUTPUT_LOAD='(1.0,-1.0)';
    'MCB_DQS_L7':
      PIN_NUMBER='(0,0,CU55,0,0,0,0,0,0,0,0,0,0,0,0,0,0,0,0,0,0,0,0,0,0,0,0,0,0,0,0,0,0,0,0,0,0,0,0,0)';
      BIDIRECTIONAL='TRUE';
      INPUT_LOAD='(-0.01,0.01)';
      OUTPUT_LOAD='(1.0,-1.0)';
    'MCB_DQS_H3':
      PIN_NUMBER='(0,0,DB56,0,0,0,0,0,0,0,0,0,0,0,0,0,0,0,0,0,0,0,0,0,0,0,0,0,0,0,0,0,0,0,0,0,0,0,0,0)';
      BIDIRECTIONAL='TRUE';
      INPUT_LOAD='(-0.01,0.01)';
      OUTPUT_LOAD='(1.0,-1.0)';
    'MCB_DATA3':
      PIN_NUMBER='(0,0,CD55,0,0,0,0,0,0,0,0,0,0,0,0,0,0,0,0,0,0,0,0,0,0,0,0,0,0,0,0,0,0,0,0,0,0,0,0,0)';
      BIDIRECTIONAL='TRUE';
      INPUT_LOAD='(-0.01,0.01)';
      OUTPUT_LOAD='(1.0,-1.0)';
    'MCB_CA4':
      PIN_NUMBER='(0,0,BJ55,0,0,0,0,0,0,0,0,0,0,0,0,0,0,0,0,0,0,0,0,0,0,0,0,0,0,0,0,0,0,0,0,0,0,0,0,0)';
      OUTPUT_LOAD='(1.0,-1.0)';
    'MCA_DQS_H9':
      PIN_NUMBER='(0,0,AN55,0,0,0,0,0,0,0,0,0,0,0,0,0,0,0,0,0,0,0,0,0,0,0,0,0,0,0,0,0,0,0,0,0,0,0,0,0)';
      BIDIRECTIONAL='TRUE';
      INPUT_LOAD='(-0.01,0.01)';
      OUTPUT_LOAD='(1.0,-1.0)';
    'MCA_DATA31':
      PIN_NUMBER='(0,0,AJ55,0,0,0,0,0,0,0,0,0,0,0,0,0,0,0,0,0,0,0,0,0,0,0,0,0,0,0,0,0,0,0,0,0,0,0,0,0)';
      BIDIRECTIONAL='TRUE';
      INPUT_LOAD='(-0.01,0.01)';
      OUTPUT_LOAD='(1.0,-1.0)';
    'MCA_DATA20':
      PIN_NUMBER='(0,0,AA57,0,0,0,0,0,0,0,0,0,0,0,0,0,0,0,0,0,0,0,0,0,0,0,0,0,0,0,0,0,0,0,0,0,0,0,0,0)';
      BIDIRECTIONAL='TRUE';
      INPUT_LOAD='(-0.01,0.01)';
      OUTPUT_LOAD='(1.0,-1.0)';
    'MCA_DATA4':
      PIN_NUMBER='(0,0,J57,0,0,0,0,0,0,0,0,0,0,0,0,0,0,0,0,0,0,0,0,0,0,0,0,0,0,0,0,0,0,0,0,0,0,0,0,0)';
      BIDIRECTIONAL='TRUE';
      INPUT_LOAD='(-0.01,0.01)';
      OUTPUT_LOAD='(1.0,-1.0)';
    'MCA_CHECK0':
      PIN_NUMBER='(0,0,AJ57,0,0,0,0,0,0,0,0,0,0,0,0,0,0,0,0,0,0,0,0,0,0,0,0,0,0,0,0,0,0,0,0,0,0,0,0,0)';
      BIDIRECTIONAL='TRUE';
      INPUT_LOAD='(-0.01,0.01)';
      OUTPUT_LOAD='(1.0,-1.0)';
    'MCA_CA5':
      PIN_NUMBER='(0,0,BB56,0,0,0,0,0,0,0,0,0,0,0,0,0,0,0,0,0,0,0,0,0,0,0,0,0,0,0,0,0,0,0,0,0,0,0,0,0)';
      OUTPUT_LOAD='(1.0,-1.0)';
    'MCB_DQS_L8':
      PIN_NUMBER='(0,0,DC55,0,0,0,0,0,0,0,0,0,0,0,0,0,0,0,0,0,0,0,0,0,0,0,0,0,0,0,0,0,0,0,0,0,0,0,0,0)';
      BIDIRECTIONAL='TRUE';
      INPUT_LOAD='(-0.01,0.01)';
      OUTPUT_LOAD='(1.0,-1.0)';
    'MCB_DQS_H4':
      PIN_NUMBER='(0,0,BY55,0,0,0,0,0,0,0,0,0,0,0,0,0,0,0,0,0,0,0,0,0,0,0,0,0,0,0,0,0,0,0,0,0,0,0,0,0)';
      BIDIRECTIONAL='TRUE';
      INPUT_LOAD='(-0.01,0.01)';
      OUTPUT_LOAD='(1.0,-1.0)';
    'MCB_DATA4':
      PIN_NUMBER='(0,0,CF56,0,0,0,0,0,0,0,0,0,0,0,0,0,0,0,0,0,0,0,0,0,0,0,0,0,0,0,0,0,0,0,0,0,0,0,0,0)';
      BIDIRECTIONAL='TRUE';
      INPUT_LOAD='(-0.01,0.01)';
      OUTPUT_LOAD='(1.0,-1.0)';
    'MCB_CA5':
      PIN_NUMBER='(0,0,BK55,0,0,0,0,0,0,0,0,0,0,0,0,0,0,0,0,0,0,0,0,0,0,0,0,0,0,0,0,0,0,0,0,0,0,0,0,0)';
      OUTPUT_LOAD='(1.0,-1.0)';
    'MCA_DATA21':
      PIN_NUMBER='(0,0,AB55,0,0,0,0,0,0,0,0,0,0,0,0,0,0,0,0,0,0,0,0,0,0,0,0,0,0,0,0,0,0,0,0,0,0,0,0,0)';
      BIDIRECTIONAL='TRUE';
      INPUT_LOAD='(-0.01,0.01)';
      OUTPUT_LOAD='(1.0,-1.0)';
    'MCA_DATA10':
      PIN_NUMBER='(0,0,M56,0,0,0,0,0,0,0,0,0,0,0,0,0,0,0,0,0,0,0,0,0,0,0,0,0,0,0,0,0,0,0,0,0,0,0,0,0)';
      BIDIRECTIONAL='TRUE';
      INPUT_LOAD='(-0.01,0.01)';
      OUTPUT_LOAD='(1.0,-1.0)';
    'MCA_DATA5':
      PIN_NUMBER='(0,0,K55,0,0,0,0,0,0,0,0,0,0,0,0,0,0,0,0,0,0,0,0,0,0,0,0,0,0,0,0,0,0,0,0,0,0,0,0,0)';
      BIDIRECTIONAL='TRUE';
      INPUT_LOAD='(-0.01,0.01)';
      OUTPUT_LOAD='(1.0,-1.0)';
    'MCA_CHECK1':
      PIN_NUMBER='(0,0,AK55,0,0,0,0,0,0,0,0,0,0,0,0,0,0,0,0,0,0,0,0,0,0,0,0,0,0,0,0,0,0,0,0,0,0,0,0,0)';
      BIDIRECTIONAL='TRUE';
      INPUT_LOAD='(-0.01,0.01)';
      OUTPUT_LOAD='(1.0,-1.0)';
    'MCA_CA6':
      PIN_NUMBER='(0,0,BB55,0,0,0,0,0,0,0,0,0,0,0,0,0,0,0,0,0,0,0,0,0,0,0,0,0,0,0,0,0,0,0,0,0,0,0,0,0)';
      OUTPUT_LOAD='(1.0,-1.0)';
    'MCB_DQS_L9':
      PIN_NUMBER='(0,0,BW57,0,0,0,0,0,0,0,0,0,0,0,0,0,0,0,0,0,0,0,0,0,0,0,0,0,0,0,0,0,0,0,0,0,0,0,0,0)';
      BIDIRECTIONAL='TRUE';
      INPUT_LOAD='(-0.01,0.01)';
      OUTPUT_LOAD='(1.0,-1.0)';
    'MCB_DQS_H5':
      PIN_NUMBER='(0,0,CF55,0,0,0,0,0,0,0,0,0,0,0,0,0,0,0,0,0,0,0,0,0,0,0,0,0,0,0,0,0,0,0,0,0,0,0,0,0)';
      BIDIRECTIONAL='TRUE';
      INPUT_LOAD='(-0.01,0.01)';
      OUTPUT_LOAD='(1.0,-1.0)';
    'MCB_DATA5':
      PIN_NUMBER='(0,0,CG55,0,0,0,0,0,0,0,0,0,0,0,0,0,0,0,0,0,0,0,0,0,0,0,0,0,0,0,0,0,0,0,0,0,0,0,0,0)';
      BIDIRECTIONAL='TRUE';
      INPUT_LOAD='(-0.01,0.01)';
      OUTPUT_LOAD='(1.0,-1.0)';
    'MCB_CA6':
      PIN_NUMBER='(0,0,BK56,0,0,0,0,0,0,0,0,0,0,0,0,0,0,0,0,0,0,0,0,0,0,0,0,0,0,0,0,0,0,0,0,0,0,0,0,0)';
      OUTPUT_LOAD='(1.0,-1.0)';
    'MCA_DATA22':
      PIN_NUMBER='(0,0,AB56,0,0,0,0,0,0,0,0,0,0,0,0,0,0,0,0,0,0,0,0,0,0,0,0,0,0,0,0,0,0,0,0,0,0,0,0,0)';
      BIDIRECTIONAL='TRUE';
      INPUT_LOAD='(-0.01,0.01)';
      OUTPUT_LOAD='(1.0,-1.0)';
    'MCA_DATA11':
      PIN_NUMBER='(0,0,N55,0,0,0,0,0,0,0,0,0,0,0,0,0,0,0,0,0,0,0,0,0,0,0,0,0,0,0,0,0,0,0,0,0,0,0,0,0)';
      BIDIRECTIONAL='TRUE';
      INPUT_LOAD='(-0.01,0.01)';
      OUTPUT_LOAD='(1.0,-1.0)';
    'MCA_DATA6':
      PIN_NUMBER='(0,0,K56,0,0,0,0,0,0,0,0,0,0,0,0,0,0,0,0,0,0,0,0,0,0,0,0,0,0,0,0,0,0,0,0,0,0,0,0,0)';
      BIDIRECTIONAL='TRUE';
      INPUT_LOAD='(-0.01,0.01)';
      OUTPUT_LOAD='(1.0,-1.0)';
    'MCA_CHECK2':
      PIN_NUMBER='(0,0,AK56,0,0,0,0,0,0,0,0,0,0,0,0,0,0,0,0,0,0,0,0,0,0,0,0,0,0,0,0,0,0,0,0,0,0,0,0,0)';
      BIDIRECTIONAL='TRUE';
      INPUT_LOAD='(-0.01,0.01)';
      OUTPUT_LOAD='(1.0,-1.0)';
    'MCB_DQS_H6':
      PIN_NUMBER='(0,0,CM55,0,0,0,0,0,0,0,0,0,0,0,0,0,0,0,0,0,0,0,0,0,0,0,0,0,0,0,0,0,0,0,0,0,0,0,0,0)';
      BIDIRECTIONAL='TRUE';
      INPUT_LOAD='(-0.01,0.01)';
      OUTPUT_LOAD='(1.0,-1.0)';
    'MCB_DATA6':
      PIN_NUMBER='(0,0,CG57,0,0,0,0,0,0,0,0,0,0,0,0,0,0,0,0,0,0,0,0,0,0,0,0,0,0,0,0,0,0,0,0,0,0,0,0,0)';
      BIDIRECTIONAL='TRUE';
      INPUT_LOAD='(-0.01,0.01)';
      OUTPUT_LOAD='(1.0,-1.0)';
    'MCA_DATA23':
      PIN_NUMBER='(0,0,AC55,0,0,0,0,0,0,0,0,0,0,0,0,0,0,0,0,0,0,0,0,0,0,0,0,0,0,0,0,0,0,0,0,0,0,0,0,0)';
      BIDIRECTIONAL='TRUE';
      INPUT_LOAD='(-0.01,0.01)';
      OUTPUT_LOAD='(1.0,-1.0)';
    'MCA_DATA12':
      PIN_NUMBER='(0,0,R57,0,0,0,0,0,0,0,0,0,0,0,0,0,0,0,0,0,0,0,0,0,0,0,0,0,0,0,0,0,0,0,0,0,0,0,0,0)';
      BIDIRECTIONAL='TRUE';
      INPUT_LOAD='(-0.01,0.01)';
      OUTPUT_LOAD='(1.0,-1.0)';
    'MCA_DATA7':
      PIN_NUMBER='(0,0,L55,0,0,0,0,0,0,0,0,0,0,0,0,0,0,0,0,0,0,0,0,0,0,0,0,0,0,0,0,0,0,0,0,0,0,0,0,0)';
      BIDIRECTIONAL='TRUE';
      INPUT_LOAD='(-0.01,0.01)';
      OUTPUT_LOAD='(1.0,-1.0)';
    'MCA_CHECK3':
      PIN_NUMBER='(0,0,AL55,0,0,0,0,0,0,0,0,0,0,0,0,0,0,0,0,0,0,0,0,0,0,0,0,0,0,0,0,0,0,0,0,0,0,0,0,0)';
      BIDIRECTIONAL='TRUE';
      INPUT_LOAD='(-0.01,0.01)';
      OUTPUT_LOAD='(1.0,-1.0)';
    'MCB_DQS_H7':
      PIN_NUMBER='(0,0,CV55,0,0,0,0,0,0,0,0,0,0,0,0,0,0,0,0,0,0,0,0,0,0,0,0,0,0,0,0,0,0,0,0,0,0,0,0,0)';
      BIDIRECTIONAL='TRUE';
      INPUT_LOAD='(-0.01,0.01)';
      OUTPUT_LOAD='(1.0,-1.0)';
    'MCB_DATA7':
      PIN_NUMBER='(0,0,CH55,0,0,0,0,0,0,0,0,0,0,0,0,0,0,0,0,0,0,0,0,0,0,0,0,0,0,0,0,0,0,0,0,0,0,0,0,0)';
      BIDIRECTIONAL='TRUE';
      INPUT_LOAD='(-0.01,0.01)';
      OUTPUT_LOAD='(1.0,-1.0)';
    'MCB1_CS_L0':
      PIN_NUMBER='(0,0,BL55,0,0,0,0,0,0,0,0,0,0,0,0,0,0,0,0,0,0,0,0,0,0,0,0,0,0,0,0,0,0,0,0,0,0,0,0,0)';
      OUTPUT_LOAD='(1.0,-1.0)';
    'MCB0_CS_L0':
      PIN_NUMBER='(0,0,BM55,0,0,0,0,0,0,0,0,0,0,0,0,0,0,0,0,0,0,0,0,0,0,0,0,0,0,0,0,0,0,0,0,0,0,0,0,0)';
      OUTPUT_LOAD='(1.0,-1.0)';
    'MCA_DQS_L0':
      PIN_NUMBER='(0,0,H56,0,0,0,0,0,0,0,0,0,0,0,0,0,0,0,0,0,0,0,0,0,0,0,0,0,0,0,0,0,0,0,0,0,0,0,0,0)';
      BIDIRECTIONAL='TRUE';
      INPUT_LOAD='(-0.01,0.01)';
      OUTPUT_LOAD='(1.0,-1.0)';
    'MCA_DATA24':
      PIN_NUMBER='(0,0,AC57,0,0,0,0,0,0,0,0,0,0,0,0,0,0,0,0,0,0,0,0,0,0,0,0,0,0,0,0,0,0,0,0,0,0,0,0,0)';
      BIDIRECTIONAL='TRUE';
      INPUT_LOAD='(-0.01,0.01)';
      OUTPUT_LOAD='(1.0,-1.0)';
    'MCA_DATA13':
      PIN_NUMBER='(0,0,T55,0,0,0,0,0,0,0,0,0,0,0,0,0,0,0,0,0,0,0,0,0,0,0,0,0,0,0,0,0,0,0,0,0,0,0,0,0)';
      BIDIRECTIONAL='TRUE';
      INPUT_LOAD='(-0.01,0.01)';
      OUTPUT_LOAD='(1.0,-1.0)';
    'MCA_DATA8':
      PIN_NUMBER='(0,0,L57,0,0,0,0,0,0,0,0,0,0,0,0,0,0,0,0,0,0,0,0,0,0,0,0,0,0,0,0,0,0,0,0,0,0,0,0,0)';
      BIDIRECTIONAL='TRUE';
      INPUT_LOAD='(-0.01,0.01)';
      OUTPUT_LOAD='(1.0,-1.0)';
    'MCA_CHECK4':
      PIN_NUMBER='(0,0,AN57,0,0,0,0,0,0,0,0,0,0,0,0,0,0,0,0,0,0,0,0,0,0,0,0,0,0,0,0,0,0,0,0,0,0,0,0,0)';
      BIDIRECTIONAL='TRUE';
      INPUT_LOAD='(-0.01,0.01)';
      OUTPUT_LOAD='(1.0,-1.0)';
    'MCB_DQS_H9':
      PIN_NUMBER='(0,0,BV56,0,0,0,0,0,0,0,0,0,0,0,0,0,0,0,0,0,0,0,0,0,0,0,0,0,0,0,0,0,0,0,0,0,0,0,0,0)';
      BIDIRECTIONAL='TRUE';
      INPUT_LOAD='(-0.01,0.01)';
      OUTPUT_LOAD='(1.0,-1.0)';
    'MCA_PAR':
      PIN_NUMBER='(0,0,BC55,0,0,0,0,0,0,0,0,0,0,0,0,0,0,0,0,0,0,0,0,0,0,0,0,0,0,0,0,0,0,0,0,0,0,0,0,0)';
      OUTPUT_LOAD='(1.0,-1.0)';
    'MCB_PAR':
      PIN_NUMBER='(0,0,BL57,0,0,0,0,0,0,0,0,0,0,0,0,0,0,0,0,0,0,0,0,0,0,0,0,0,0,0,0,0,0,0,0,0,0,0,0,0)';
      OUTPUT_LOAD='(1.0,-1.0)';
    'MC0_CLK_H':
      PIN_NUMBER='(0,0,BC57,0,0,0,0,0,0,0,0,0,0,0,0,0,0,0,0,0,0,0,0,0,0,0,0,0,0,0,0,0,0,0,0,0,0,0,0,0)';
      OUTPUT_LOAD='(1.0,-1.0)';
    'MC0_CLK_L':
      PIN_NUMBER='(0,0,BD56,0,0,0,0,0,0,0,0,0,0,0,0,0,0,0,0,0,0,0,0,0,0,0,0,0,0,0,0,0,0,0,0,0,0,0,0,0)';
      OUTPUT_LOAD='(1.0,-1.0)';
    'MC1_CLK_H':
      PIN_NUMBER='(0,0,BF56,0,0,0,0,0,0,0,0,0,0,0,0,0,0,0,0,0,0,0,0,0,0,0,0,0,0,0,0,0,0,0,0,0,0,0,0,0)';
      OUTPUT_LOAD='(1.0,-1.0)';
    'MC1_CLK_L':
      PIN_NUMBER='(0,0,BG57,0,0,0,0,0,0,0,0,0,0,0,0,0,0,0,0,0,0,0,0,0,0,0,0,0,0,0,0,0,0,0,0,0,0,0,0,0)';
      OUTPUT_LOAD='(1.0,-1.0)';
    'TEST39C':
      PIN_NUMBER='(0,0,BF55,0,0,0,0,0,0,0,0,0,0,0,0,0,0,0,0,0,0,0,0,0,0,0,0,0,0,0,0,0,0,0,0,0,0,0,0,0)';
      OUTPUT_LOAD='(1.0,-1.0)';
    'MD_ALERT_L':
      PIN_NUMBER='(0,0,0,AT58,0,0,0,0,0,0,0,0,0,0,0,0,0,0,0,0,0,0,0,0,0,0,0,0,0,0,0,0,0,0,0,0,0,0,0,0)';
      INPUT_LOAD='(-0.01,0.01)';
    'MD_RESET_L':
      PIN_NUMBER='(0,0,0,AU59,0,0,0,0,0,0,0,0,0,0,0,0,0,0,0,0,0,0,0,0,0,0,0,0,0,0,0,0,0,0,0,0,0,0,0,0)';
      OUTPUT_LOAD='(1.0,-1.0)';
    'MDB_DATA23':
      PIN_NUMBER='(0,0,0,CY58,0,0,0,0,0,0,0,0,0,0,0,0,0,0,0,0,0,0,0,0,0,0,0,0,0,0,0,0,0,0,0,0,0,0,0,0)';
      BIDIRECTIONAL='TRUE';
      INPUT_LOAD='(-0.01,0.01)';
      OUTPUT_LOAD='(1.0,-1.0)';
    'MDB_DATA12':
      PIN_NUMBER='(0,0,0,CM60,0,0,0,0,0,0,0,0,0,0,0,0,0,0,0,0,0,0,0,0,0,0,0,0,0,0,0,0,0,0,0,0,0,0,0,0)';
      BIDIRECTIONAL='TRUE';
      INPUT_LOAD='(-0.01,0.01)';
      OUTPUT_LOAD='(1.0,-1.0)';
    'MDB_DATA2':
      PIN_NUMBER='(0,0,0,CC60,0,0,0,0,0,0,0,0,0,0,0,0,0,0,0,0,0,0,0,0,0,0,0,0,0,0,0,0,0,0,0,0,0,0,0,0)';
      BIDIRECTIONAL='TRUE';
      INPUT_LOAD='(-0.01,0.01)';
      OUTPUT_LOAD='(1.0,-1.0)';
    'MDB_CHECK3':
      PIN_NUMBER='(0,0,0,CB58,0,0,0,0,0,0,0,0,0,0,0,0,0,0,0,0,0,0,0,0,0,0,0,0,0,0,0,0,0,0,0,0,0,0,0,0)';
      BIDIRECTIONAL='TRUE';
      INPUT_LOAD='(-0.01,0.01)';
      OUTPUT_LOAD='(1.0,-1.0)';
    'MDA_DQS_L5':
      PIN_NUMBER='(0,0,0,H58,0,0,0,0,0,0,0,0,0,0,0,0,0,0,0,0,0,0,0,0,0,0,0,0,0,0,0,0,0,0,0,0,0,0,0,0)';
      BIDIRECTIONAL='TRUE';
      INPUT_LOAD='(-0.01,0.01)';
      OUTPUT_LOAD='(1.0,-1.0)';
    'MDA_DQS_H1':
      PIN_NUMBER='(0,0,0,N60,0,0,0,0,0,0,0,0,0,0,0,0,0,0,0,0,0,0,0,0,0,0,0,0,0,0,0,0,0,0,0,0,0,0,0,0)';
      BIDIRECTIONAL='TRUE';
      INPUT_LOAD='(-0.01,0.01)';
      OUTPUT_LOAD='(1.0,-1.0)';
    'MDA_DATA29':
      PIN_NUMBER='(0,0,0,AH58,0,0,0,0,0,0,0,0,0,0,0,0,0,0,0,0,0,0,0,0,0,0,0,0,0,0,0,0,0,0,0,0,0,0,0,0)';
      BIDIRECTIONAL='TRUE';
      INPUT_LOAD='(-0.01,0.01)';
      OUTPUT_LOAD='(1.0,-1.0)';
    'MDA_DATA18':
      PIN_NUMBER='(0,0,0,V60,0,0,0,0,0,0,0,0,0,0,0,0,0,0,0,0,0,0,0,0,0,0,0,0,0,0,0,0,0,0,0,0,0,0,0,0)';
      BIDIRECTIONAL='TRUE';
      INPUT_LOAD='(-0.01,0.01)';
      OUTPUT_LOAD='(1.0,-1.0)';
    'MDA_DATA3':
      PIN_NUMBER='(0,0,0,G59,0,0,0,0,0,0,0,0,0,0,0,0,0,0,0,0,0,0,0,0,0,0,0,0,0,0,0,0,0,0,0,0,0,0,0,0)';
      BIDIRECTIONAL='TRUE';
      INPUT_LOAD='(-0.01,0.01)';
      OUTPUT_LOAD='(1.0,-1.0)';
    'MDB_DQS_L0':
      PIN_NUMBER='(0,0,0,CE60,0,0,0,0,0,0,0,0,0,0,0,0,0,0,0,0,0,0,0,0,0,0,0,0,0,0,0,0,0,0,0,0,0,0,0,0)';
      BIDIRECTIONAL='TRUE';
      INPUT_LOAD='(-0.01,0.01)';
      OUTPUT_LOAD='(1.0,-1.0)';
    'MDB_DATA24':
      PIN_NUMBER='(0,0,0,CY60,0,0,0,0,0,0,0,0,0,0,0,0,0,0,0,0,0,0,0,0,0,0,0,0,0,0,0,0,0,0,0,0,0,0,0,0)';
      BIDIRECTIONAL='TRUE';
      INPUT_LOAD='(-0.01,0.01)';
      OUTPUT_LOAD='(1.0,-1.0)';
    'MDB_DATA13':
      PIN_NUMBER='(0,0,0,CN59,0,0,0,0,0,0,0,0,0,0,0,0,0,0,0,0,0,0,0,0,0,0,0,0,0,0,0,0,0,0,0,0,0,0,0,0)';
      BIDIRECTIONAL='TRUE';
      INPUT_LOAD='(-0.01,0.01)';
      OUTPUT_LOAD='(1.0,-1.0)';
    'MDB_DATA3':
      PIN_NUMBER='(0,0,0,CD58,0,0,0,0,0,0,0,0,0,0,0,0,0,0,0,0,0,0,0,0,0,0,0,0,0,0,0,0,0,0,0,0,0,0,0,0)';
      BIDIRECTIONAL='TRUE';
      INPUT_LOAD='(-0.01,0.01)';
      OUTPUT_LOAD='(1.0,-1.0)';
    'MDB_CHECK4':
      PIN_NUMBER='(0,0,0,BT60,0,0,0,0,0,0,0,0,0,0,0,0,0,0,0,0,0,0,0,0,0,0,0,0,0,0,0,0,0,0,0,0,0,0,0,0)';
      BIDIRECTIONAL='TRUE';
      INPUT_LOAD='(-0.01,0.01)';
      OUTPUT_LOAD='(1.0,-1.0)';
    'MDA_DQS_L6':
      PIN_NUMBER='(0,0,0,P58,0,0,0,0,0,0,0,0,0,0,0,0,0,0,0,0,0,0,0,0,0,0,0,0,0,0,0,0,0,0,0,0,0,0,0,0)';
      BIDIRECTIONAL='TRUE';
      INPUT_LOAD='(-0.01,0.01)';
      OUTPUT_LOAD='(1.0,-1.0)';
    'MDA_DQS_H2':
      PIN_NUMBER='(0,0,0,W60,0,0,0,0,0,0,0,0,0,0,0,0,0,0,0,0,0,0,0,0,0,0,0,0,0,0,0,0,0,0,0,0,0,0,0,0)';
      BIDIRECTIONAL='TRUE';
      INPUT_LOAD='(-0.01,0.01)';
      OUTPUT_LOAD='(1.0,-1.0)';
    'MDA_DATA19':
      PIN_NUMBER='(0,0,0,W59,0,0,0,0,0,0,0,0,0,0,0,0,0,0,0,0,0,0,0,0,0,0,0,0,0,0,0,0,0,0,0,0,0,0,0,0)';
      BIDIRECTIONAL='TRUE';
      INPUT_LOAD='(-0.01,0.01)';
      OUTPUT_LOAD='(1.0,-1.0)';
    'MDA_DATA4':
      PIN_NUMBER='(0,0,0,J60,0,0,0,0,0,0,0,0,0,0,0,0,0,0,0,0,0,0,0,0,0,0,0,0,0,0,0,0,0,0,0,0,0,0,0,0)';
      BIDIRECTIONAL='TRUE';
      INPUT_LOAD='(-0.01,0.01)';
      OUTPUT_LOAD='(1.0,-1.0)';
    'MDB_DQS_L1':
      PIN_NUMBER='(0,0,0,CL60,0,0,0,0,0,0,0,0,0,0,0,0,0,0,0,0,0,0,0,0,0,0,0,0,0,0,0,0,0,0,0,0,0,0,0,0)';
      BIDIRECTIONAL='TRUE';
      INPUT_LOAD='(-0.01,0.01)';
      OUTPUT_LOAD='(1.0,-1.0)';
    'MDB_DATA25':
      PIN_NUMBER='(0,0,0,DA59,0,0,0,0,0,0,0,0,0,0,0,0,0,0,0,0,0,0,0,0,0,0,0,0,0,0,0,0,0,0,0,0,0,0,0,0)';
      BIDIRECTIONAL='TRUE';
      INPUT_LOAD='(-0.01,0.01)';
      OUTPUT_LOAD='(1.0,-1.0)';
    'MDB_DATA14':
      PIN_NUMBER='(0,0,0,CN60,0,0,0,0,0,0,0,0,0,0,0,0,0,0,0,0,0,0,0,0,0,0,0,0,0,0,0,0,0,0,0,0,0,0,0,0)';
      BIDIRECTIONAL='TRUE';
      INPUT_LOAD='(-0.01,0.01)';
      OUTPUT_LOAD='(1.0,-1.0)';
    'MDB_DATA4':
      PIN_NUMBER='(0,0,0,CF60,0,0,0,0,0,0,0,0,0,0,0,0,0,0,0,0,0,0,0,0,0,0,0,0,0,0,0,0,0,0,0,0,0,0,0,0)';
      BIDIRECTIONAL='TRUE';
      INPUT_LOAD='(-0.01,0.01)';
      OUTPUT_LOAD='(1.0,-1.0)';
    'MDB_CHECK5':
      PIN_NUMBER='(0,0,0,BU59,0,0,0,0,0,0,0,0,0,0,0,0,0,0,0,0,0,0,0,0,0,0,0,0,0,0,0,0,0,0,0,0,0,0,0,0)';
      BIDIRECTIONAL='TRUE';
      INPUT_LOAD='(-0.01,0.01)';
      OUTPUT_LOAD='(1.0,-1.0)';
    'MDA_DQS_L7':
      PIN_NUMBER='(0,0,0,Y58,0,0,0,0,0,0,0,0,0,0,0,0,0,0,0,0,0,0,0,0,0,0,0,0,0,0,0,0,0,0,0,0,0,0,0,0)';
      BIDIRECTIONAL='TRUE';
      INPUT_LOAD='(-0.01,0.01)';
      OUTPUT_LOAD='(1.0,-1.0)';
    'MDA_DQS_H3':
      PIN_NUMBER='(0,0,0,AE60,0,0,0,0,0,0,0,0,0,0,0,0,0,0,0,0,0,0,0,0,0,0,0,0,0,0,0,0,0,0,0,0,0,0,0,0)';
      BIDIRECTIONAL='TRUE';
      INPUT_LOAD='(-0.01,0.01)';
      OUTPUT_LOAD='(1.0,-1.0)';
    'MDA_DATA5':
      PIN_NUMBER='(0,0,0,K58,0,0,0,0,0,0,0,0,0,0,0,0,0,0,0,0,0,0,0,0,0,0,0,0,0,0,0,0,0,0,0,0,0,0,0,0)';
      BIDIRECTIONAL='TRUE';
      INPUT_LOAD='(-0.01,0.01)';
      OUTPUT_LOAD='(1.0,-1.0)';
    'MDB_DQS_L2':
      PIN_NUMBER='(0,0,0,CU60,0,0,0,0,0,0,0,0,0,0,0,0,0,0,0,0,0,0,0,0,0,0,0,0,0,0,0,0,0,0,0,0,0,0,0,0)';
      BIDIRECTIONAL='TRUE';
      INPUT_LOAD='(-0.01,0.01)';
      OUTPUT_LOAD='(1.0,-1.0)';
    'MDB_DATA26':
      PIN_NUMBER='(0,0,0,DA60,0,0,0,0,0,0,0,0,0,0,0,0,0,0,0,0,0,0,0,0,0,0,0,0,0,0,0,0,0,0,0,0,0,0,0,0)';
      BIDIRECTIONAL='TRUE';
      INPUT_LOAD='(-0.01,0.01)';
      OUTPUT_LOAD='(1.0,-1.0)';
    'MDB_DATA15':
      PIN_NUMBER='(0,0,0,CP58,0,0,0,0,0,0,0,0,0,0,0,0,0,0,0,0,0,0,0,0,0,0,0,0,0,0,0,0,0,0,0,0,0,0,0,0)';
      BIDIRECTIONAL='TRUE';
      INPUT_LOAD='(-0.01,0.01)';
      OUTPUT_LOAD='(1.0,-1.0)';
    'MDB_DATA5':
      PIN_NUMBER='(0,0,0,CG59,0,0,0,0,0,0,0,0,0,0,0,0,0,0,0,0,0,0,0,0,0,0,0,0,0,0,0,0,0,0,0,0,0,0,0,0)';
      BIDIRECTIONAL='TRUE';
      INPUT_LOAD='(-0.01,0.01)';
      OUTPUT_LOAD='(1.0,-1.0)';
    'MDB_CHECK6':
      PIN_NUMBER='(0,0,0,BU60,0,0,0,0,0,0,0,0,0,0,0,0,0,0,0,0,0,0,0,0,0,0,0,0,0,0,0,0,0,0,0,0,0,0,0,0)';
      BIDIRECTIONAL='TRUE';
      INPUT_LOAD='(-0.01,0.01)';
      OUTPUT_LOAD='(1.0,-1.0)';
    'MDA_DQS_L8':
      PIN_NUMBER='(0,0,0,AF58,0,0,0,0,0,0,0,0,0,0,0,0,0,0,0,0,0,0,0,0,0,0,0,0,0,0,0,0,0,0,0,0,0,0,0,0)';
      BIDIRECTIONAL='TRUE';
      INPUT_LOAD='(-0.01,0.01)';
      OUTPUT_LOAD='(1.0,-1.0)';
    'MDA_DQS_H4':
      PIN_NUMBER='(0,0,0,AL60,0,0,0,0,0,0,0,0,0,0,0,0,0,0,0,0,0,0,0,0,0,0,0,0,0,0,0,0,0,0,0,0,0,0,0,0)';
      BIDIRECTIONAL='TRUE';
      INPUT_LOAD='(-0.01,0.01)';
      OUTPUT_LOAD='(1.0,-1.0)';
    'MDA_DATA6':
      PIN_NUMBER='(0,0,0,K60,0,0,0,0,0,0,0,0,0,0,0,0,0,0,0,0,0,0,0,0,0,0,0,0,0,0,0,0,0,0,0,0,0,0,0,0)';
      BIDIRECTIONAL='TRUE';
      INPUT_LOAD='(-0.01,0.01)';
      OUTPUT_LOAD='(1.0,-1.0)';
    'MDB_DQS_L3':
      PIN_NUMBER='(0,0,0,DC60,0,0,0,0,0,0,0,0,0,0,0,0,0,0,0,0,0,0,0,0,0,0,0,0,0,0,0,0,0,0,0,0,0,0,0,0)';
      BIDIRECTIONAL='TRUE';
      INPUT_LOAD='(-0.01,0.01)';
      OUTPUT_LOAD='(1.0,-1.0)';
    'MDB_DATA27':
      PIN_NUMBER='(0,0,0,DB58,0,0,0,0,0,0,0,0,0,0,0,0,0,0,0,0,0,0,0,0,0,0,0,0,0,0,0,0,0,0,0,0,0,0,0,0)';
      BIDIRECTIONAL='TRUE';
      INPUT_LOAD='(-0.01,0.01)';
      OUTPUT_LOAD='(1.0,-1.0)';
    'MDB_DATA16':
      PIN_NUMBER='(0,0,0,CP60,0,0,0,0,0,0,0,0,0,0,0,0,0,0,0,0,0,0,0,0,0,0,0,0,0,0,0,0,0,0,0,0,0,0,0,0)';
      BIDIRECTIONAL='TRUE';
      INPUT_LOAD='(-0.01,0.01)';
      OUTPUT_LOAD='(1.0,-1.0)';
    'MDB_DATA6':
      PIN_NUMBER='(0,0,0,CG60,0,0,0,0,0,0,0,0,0,0,0,0,0,0,0,0,0,0,0,0,0,0,0,0,0,0,0,0,0,0,0,0,0,0,0,0)';
      BIDIRECTIONAL='TRUE';
      INPUT_LOAD='(-0.01,0.01)';
      OUTPUT_LOAD='(1.0,-1.0)';
    'MDB_CHECK7':
      PIN_NUMBER='(0,0,0,BV58,0,0,0,0,0,0,0,0,0,0,0,0,0,0,0,0,0,0,0,0,0,0,0,0,0,0,0,0,0,0,0,0,0,0,0,0)';
      BIDIRECTIONAL='TRUE';
      INPUT_LOAD='(-0.01,0.01)';
      OUTPUT_LOAD='(1.0,-1.0)';
    'MDB0_RSP_L':
      PIN_NUMBER='(0,0,0,BP60,0,0,0,0,0,0,0,0,0,0,0,0,0,0,0,0,0,0,0,0,0,0,0,0,0,0,0,0,0,0,0,0,0,0,0,0)';
      INPUT_LOAD='(-0.01,0.01)';
    'MDA_DQS_L9':
      PIN_NUMBER='(0,0,0,AM58,0,0,0,0,0,0,0,0,0,0,0,0,0,0,0,0,0,0,0,0,0,0,0,0,0,0,0,0,0,0,0,0,0,0,0,0)';
      BIDIRECTIONAL='TRUE';
      INPUT_LOAD='(-0.01,0.01)';
      OUTPUT_LOAD='(1.0,-1.0)';
    'MDA_DQS_H5':
      PIN_NUMBER='(0,0,0,J59,0,0,0,0,0,0,0,0,0,0,0,0,0,0,0,0,0,0,0,0,0,0,0,0,0,0,0,0,0,0,0,0,0,0,0,0)';
      BIDIRECTIONAL='TRUE';
      INPUT_LOAD='(-0.01,0.01)';
      OUTPUT_LOAD='(1.0,-1.0)';
    'MDA_DATA7':
      PIN_NUMBER='(0,0,0,L59,0,0,0,0,0,0,0,0,0,0,0,0,0,0,0,0,0,0,0,0,0,0,0,0,0,0,0,0,0,0,0,0,0,0,0,0)';
      BIDIRECTIONAL='TRUE';
      INPUT_LOAD='(-0.01,0.01)';
      OUTPUT_LOAD='(1.0,-1.0)';
    'MDB_DQS_L4':
      PIN_NUMBER='(0,0,0,BW59,0,0,0,0,0,0,0,0,0,0,0,0,0,0,0,0,0,0,0,0,0,0,0,0,0,0,0,0,0,0,0,0,0,0,0,0)';
      BIDIRECTIONAL='TRUE';
      INPUT_LOAD='(-0.01,0.01)';
      OUTPUT_LOAD='(1.0,-1.0)';
    'MDB_DQS_H0':
      PIN_NUMBER='(0,0,0,CD60,0,0,0,0,0,0,0,0,0,0,0,0,0,0,0,0,0,0,0,0,0,0,0,0,0,0,0,0,0,0,0,0,0,0,0,0)';
      BIDIRECTIONAL='TRUE';
      INPUT_LOAD='(-0.01,0.01)';
      OUTPUT_LOAD='(1.0,-1.0)';
    'MDB_DATA28':
      PIN_NUMBER='(0,0,0,DD60,0,0,0,0,0,0,0,0,0,0,0,0,0,0,0,0,0,0,0,0,0,0,0,0,0,0,0,0,0,0,0,0,0,0,0,0)';
      BIDIRECTIONAL='TRUE';
      INPUT_LOAD='(-0.01,0.01)';
      OUTPUT_LOAD='(1.0,-1.0)';
    'MDB_DATA17':
      PIN_NUMBER='(0,0,0,CR59,0,0,0,0,0,0,0,0,0,0,0,0,0,0,0,0,0,0,0,0,0,0,0,0,0,0,0,0,0,0,0,0,0,0,0,0)';
      BIDIRECTIONAL='TRUE';
      INPUT_LOAD='(-0.01,0.01)';
      OUTPUT_LOAD='(1.0,-1.0)';
    'MDB_DATA7':
      PIN_NUMBER='(0,0,0,CH58,0,0,0,0,0,0,0,0,0,0,0,0,0,0,0,0,0,0,0,0,0,0,0,0,0,0,0,0,0,0,0,0,0,0,0,0)';
      BIDIRECTIONAL='TRUE';
      INPUT_LOAD='(-0.01,0.01)';
      OUTPUT_LOAD='(1.0,-1.0)';
    'MDB1_RSP_L':
      PIN_NUMBER='(0,0,0,BR60,0,0,0,0,0,0,0,0,0,0,0,0,0,0,0,0,0,0,0,0,0,0,0,0,0,0,0,0,0,0,0,0,0,0,0,0)';
      INPUT_LOAD='(-0.01,0.01)';
    'MDA_DQS_H6':
      PIN_NUMBER='(0,0,0,R59,0,0,0,0,0,0,0,0,0,0,0,0,0,0,0,0,0,0,0,0,0,0,0,0,0,0,0,0,0,0,0,0,0,0,0,0)';
      BIDIRECTIONAL='TRUE';
      INPUT_LOAD='(-0.01,0.01)';
      OUTPUT_LOAD='(1.0,-1.0)';
    'MDA_DATA8':
      PIN_NUMBER='(0,0,0,L60,0,0,0,0,0,0,0,0,0,0,0,0,0,0,0,0,0,0,0,0,0,0,0,0,0,0,0,0,0,0,0,0,0,0,0,0)';
      BIDIRECTIONAL='TRUE';
      INPUT_LOAD='(-0.01,0.01)';
      OUTPUT_LOAD='(1.0,-1.0)';
    'MDB_DQS_L5':
      PIN_NUMBER='(0,0,0,CE59,0,0,0,0,0,0,0,0,0,0,0,0,0,0,0,0,0,0,0,0,0,0,0,0,0,0,0,0,0,0,0,0,0,0,0,0)';
      BIDIRECTIONAL='TRUE';
      INPUT_LOAD='(-0.01,0.01)';
      OUTPUT_LOAD='(1.0,-1.0)';
    'MDB_DQS_H1':
      PIN_NUMBER='(0,0,0,CK60,0,0,0,0,0,0,0,0,0,0,0,0,0,0,0,0,0,0,0,0,0,0,0,0,0,0,0,0,0,0,0,0,0,0,0,0)';
      BIDIRECTIONAL='TRUE';
      INPUT_LOAD='(-0.01,0.01)';
      OUTPUT_LOAD='(1.0,-1.0)';
    'MDB_DATA29':
      PIN_NUMBER='(0,0,0,DE59,0,0,0,0,0,0,0,0,0,0,0,0,0,0,0,0,0,0,0,0,0,0,0,0,0,0,0,0,0,0,0,0,0,0,0,0)';
      BIDIRECTIONAL='TRUE';
      INPUT_LOAD='(-0.01,0.01)';
      OUTPUT_LOAD='(1.0,-1.0)';
    'MDB_DATA18':
      PIN_NUMBER='(0,0,0,CR60,0,0,0,0,0,0,0,0,0,0,0,0,0,0,0,0,0,0,0,0,0,0,0,0,0,0,0,0,0,0,0,0,0,0,0,0)';
      BIDIRECTIONAL='TRUE';
      INPUT_LOAD='(-0.01,0.01)';
      OUTPUT_LOAD='(1.0,-1.0)';
    'MDB_DATA8':
      PIN_NUMBER='(0,0,0,CH60,0,0,0,0,0,0,0,0,0,0,0,0,0,0,0,0,0,0,0,0,0,0,0,0,0,0,0,0,0,0,0,0,0,0,0,0)';
      BIDIRECTIONAL='TRUE';
      INPUT_LOAD='(-0.01,0.01)';
      OUTPUT_LOAD='(1.0,-1.0)';
    'MDA_DQS_H7':
      PIN_NUMBER='(0,0,0,AA59,0,0,0,0,0,0,0,0,0,0,0,0,0,0,0,0,0,0,0,0,0,0,0,0,0,0,0,0,0,0,0,0,0,0,0,0)';
      BIDIRECTIONAL='TRUE';
      INPUT_LOAD='(-0.01,0.01)';
      OUTPUT_LOAD='(1.0,-1.0)';
    'MDA_DATA9':
      PIN_NUMBER='(0,0,0,M58,0,0,0,0,0,0,0,0,0,0,0,0,0,0,0,0,0,0,0,0,0,0,0,0,0,0,0,0,0,0,0,0,0,0,0,0)';
      BIDIRECTIONAL='TRUE';
      INPUT_LOAD='(-0.01,0.01)';
      OUTPUT_LOAD='(1.0,-1.0)';
    'MDA_CA0':
      PIN_NUMBER='(0,0,0,AW60,0,0,0,0,0,0,0,0,0,0,0,0,0,0,0,0,0,0,0,0,0,0,0,0,0,0,0,0,0,0,0,0,0,0,0,0)';
      OUTPUT_LOAD='(1.0,-1.0)';
    'MDA0_CS_L0':
      PIN_NUMBER='(0,0,0,AV60,0,0,0,0,0,0,0,0,0,0,0,0,0,0,0,0,0,0,0,0,0,0,0,0,0,0,0,0,0,0,0,0,0,0,0,0)';
      OUTPUT_LOAD='(1.0,-1.0)';
    'MDB_DQS_L6':
      PIN_NUMBER='(0,0,0,CL59,0,0,0,0,0,0,0,0,0,0,0,0,0,0,0,0,0,0,0,0,0,0,0,0,0,0,0,0,0,0,0,0,0,0,0,0)';
      BIDIRECTIONAL='TRUE';
      INPUT_LOAD='(-0.01,0.01)';
      OUTPUT_LOAD='(1.0,-1.0)';
    'MDB_DQS_H2':
      PIN_NUMBER='(0,0,0,CT60,0,0,0,0,0,0,0,0,0,0,0,0,0,0,0,0,0,0,0,0,0,0,0,0,0,0,0,0,0,0,0,0,0,0,0,0)';
      BIDIRECTIONAL='TRUE';
      INPUT_LOAD='(-0.01,0.01)';
      OUTPUT_LOAD='(1.0,-1.0)';
    'MDB_DATA19':
      PIN_NUMBER='(0,0,0,CT58,0,0,0,0,0,0,0,0,0,0,0,0,0,0,0,0,0,0,0,0,0,0,0,0,0,0,0,0,0,0,0,0,0,0,0,0)';
      BIDIRECTIONAL='TRUE';
      INPUT_LOAD='(-0.01,0.01)';
      OUTPUT_LOAD='(1.0,-1.0)';
    'MDB_DATA9':
      PIN_NUMBER='(0,0,0,CJ59,0,0,0,0,0,0,0,0,0,0,0,0,0,0,0,0,0,0,0,0,0,0,0,0,0,0,0,0,0,0,0,0,0,0,0,0)';
      BIDIRECTIONAL='TRUE';
      INPUT_LOAD='(-0.01,0.01)';
      OUTPUT_LOAD='(1.0,-1.0)';
    'MDB_CA0':
      PIN_NUMBER='(0,0,0,BG59,0,0,0,0,0,0,0,0,0,0,0,0,0,0,0,0,0,0,0,0,0,0,0,0,0,0,0,0,0,0,0,0,0,0,0,0)';
      OUTPUT_LOAD='(1.0,-1.0)';
    'MDA_DQS_H8':
      PIN_NUMBER='(0,0,0,AG59,0,0,0,0,0,0,0,0,0,0,0,0,0,0,0,0,0,0,0,0,0,0,0,0,0,0,0,0,0,0,0,0,0,0,0,0)';
      BIDIRECTIONAL='TRUE';
      INPUT_LOAD='(-0.01,0.01)';
      OUTPUT_LOAD='(1.0,-1.0)';
    'MDA_DATA30':
      PIN_NUMBER='(0,0,0,AH60,0,0,0,0,0,0,0,0,0,0,0,0,0,0,0,0,0,0,0,0,0,0,0,0,0,0,0,0,0,0,0,0,0,0,0,0)';
      BIDIRECTIONAL='TRUE';
      INPUT_LOAD='(-0.01,0.01)';
      OUTPUT_LOAD='(1.0,-1.0)';
    'MDA_CA1':
      PIN_NUMBER='(0,0,0,AY60,0,0,0,0,0,0,0,0,0,0,0,0,0,0,0,0,0,0,0,0,0,0,0,0,0,0,0,0,0,0,0,0,0,0,0,0)';
      OUTPUT_LOAD='(1.0,-1.0)';
    'MDA1_CS_L0':
      PIN_NUMBER='(0,0,0,AU60,0,0,0,0,0,0,0,0,0,0,0,0,0,0,0,0,0,0,0,0,0,0,0,0,0,0,0,0,0,0,0,0,0,0,0,0)';
      OUTPUT_LOAD='(1.0,-1.0)';
    'MDA0_CS_L1':
      PIN_NUMBER='(0,0,0,AW59,0,0,0,0,0,0,0,0,0,0,0,0,0,0,0,0,0,0,0,0,0,0,0,0,0,0,0,0,0,0,0,0,0,0,0,0)';
      OUTPUT_LOAD='(1.0,-1.0)';
    'MDB_DQS_L7':
      PIN_NUMBER='(0,0,0,CU59,0,0,0,0,0,0,0,0,0,0,0,0,0,0,0,0,0,0,0,0,0,0,0,0,0,0,0,0,0,0,0,0,0,0,0,0)';
      BIDIRECTIONAL='TRUE';
      INPUT_LOAD='(-0.01,0.01)';
      OUTPUT_LOAD='(1.0,-1.0)';
    'MDB_DQS_H3':
      PIN_NUMBER='(0,0,0,DB60,0,0,0,0,0,0,0,0,0,0,0,0,0,0,0,0,0,0,0,0,0,0,0,0,0,0,0,0,0,0,0,0,0,0,0,0)';
      BIDIRECTIONAL='TRUE';
      INPUT_LOAD='(-0.01,0.01)';
      OUTPUT_LOAD='(1.0,-1.0)';
    'MDB_CA1':
      PIN_NUMBER='(0,0,0,BH58,0,0,0,0,0,0,0,0,0,0,0,0,0,0,0,0,0,0,0,0,0,0,0,0,0,0,0,0,0,0,0,0,0,0,0,0)';
      OUTPUT_LOAD='(1.0,-1.0)';
    'MDA_DQS_H9':
      PIN_NUMBER='(0,0,0,AN59,0,0,0,0,0,0,0,0,0,0,0,0,0,0,0,0,0,0,0,0,0,0,0,0,0,0,0,0,0,0,0,0,0,0,0,0)';
      BIDIRECTIONAL='TRUE';
      INPUT_LOAD='(-0.01,0.01)';
      OUTPUT_LOAD='(1.0,-1.0)';
    'MDA_DATA31':
      PIN_NUMBER='(0,0,0,AJ59,0,0,0,0,0,0,0,0,0,0,0,0,0,0,0,0,0,0,0,0,0,0,0,0,0,0,0,0,0,0,0,0,0,0,0,0)';
      BIDIRECTIONAL='TRUE';
      INPUT_LOAD='(-0.01,0.01)';
      OUTPUT_LOAD='(1.0,-1.0)';
    'MDA_DATA20':
      PIN_NUMBER='(0,0,0,AA60,0,0,0,0,0,0,0,0,0,0,0,0,0,0,0,0,0,0,0,0,0,0,0,0,0,0,0,0,0,0,0,0,0,0,0,0)';
      BIDIRECTIONAL='TRUE';
      INPUT_LOAD='(-0.01,0.01)';
      OUTPUT_LOAD='(1.0,-1.0)';
    'MDA_CHECK0':
      PIN_NUMBER='(0,0,0,AJ60,0,0,0,0,0,0,0,0,0,0,0,0,0,0,0,0,0,0,0,0,0,0,0,0,0,0,0,0,0,0,0,0,0,0,0,0)';
      BIDIRECTIONAL='TRUE';
      INPUT_LOAD='(-0.01,0.01)';
      OUTPUT_LOAD='(1.0,-1.0)';
    'MDA_CA2':
      PIN_NUMBER='(0,0,0,AY58,0,0,0,0,0,0,0,0,0,0,0,0,0,0,0,0,0,0,0,0,0,0,0,0,0,0,0,0,0,0,0,0,0,0,0,0)';
      OUTPUT_LOAD='(1.0,-1.0)';
    'MDA1_CS_L1':
      PIN_NUMBER='(0,0,0,AV58,0,0,0,0,0,0,0,0,0,0,0,0,0,0,0,0,0,0,0,0,0,0,0,0,0,0,0,0,0,0,0,0,0,0,0,0)';
      OUTPUT_LOAD='(1.0,-1.0)';
    'MDB_DQS_L8':
      PIN_NUMBER='(0,0,0,DC59,0,0,0,0,0,0,0,0,0,0,0,0,0,0,0,0,0,0,0,0,0,0,0,0,0,0,0,0,0,0,0,0,0,0,0,0)';
      BIDIRECTIONAL='TRUE';
      INPUT_LOAD='(-0.01,0.01)';
      OUTPUT_LOAD='(1.0,-1.0)';
    'MDB_DQS_H4':
      PIN_NUMBER='(0,0,0,BY58,0,0,0,0,0,0,0,0,0,0,0,0,0,0,0,0,0,0,0,0,0,0,0,0,0,0,0,0,0,0,0,0,0,0,0,0)';
      BIDIRECTIONAL='TRUE';
      INPUT_LOAD='(-0.01,0.01)';
      OUTPUT_LOAD='(1.0,-1.0)';
    'MDB_CA2':
      PIN_NUMBER='(0,0,0,BH60,0,0,0,0,0,0,0,0,0,0,0,0,0,0,0,0,0,0,0,0,0,0,0,0,0,0,0,0,0,0,0,0,0,0,0,0)';
      OUTPUT_LOAD='(1.0,-1.0)';
    'MDA_DATA21':
      PIN_NUMBER='(0,0,0,AB58,0,0,0,0,0,0,0,0,0,0,0,0,0,0,0,0,0,0,0,0,0,0,0,0,0,0,0,0,0,0,0,0,0,0,0,0)';
      BIDIRECTIONAL='TRUE';
      INPUT_LOAD='(-0.01,0.01)';
      OUTPUT_LOAD='(1.0,-1.0)';
    'MDA_DATA10':
      PIN_NUMBER='(0,0,0,M60,0,0,0,0,0,0,0,0,0,0,0,0,0,0,0,0,0,0,0,0,0,0,0,0,0,0,0,0,0,0,0,0,0,0,0,0)';
      BIDIRECTIONAL='TRUE';
      INPUT_LOAD='(-0.01,0.01)';
      OUTPUT_LOAD='(1.0,-1.0)';
    'MDA_CHECK1':
      PIN_NUMBER='(0,0,0,AK58,0,0,0,0,0,0,0,0,0,0,0,0,0,0,0,0,0,0,0,0,0,0,0,0,0,0,0,0,0,0,0,0,0,0,0,0)';
      BIDIRECTIONAL='TRUE';
      INPUT_LOAD='(-0.01,0.01)';
      OUTPUT_LOAD='(1.0,-1.0)';
    'MDA_CA3':
      PIN_NUMBER='(0,0,0,BA59,0,0,0,0,0,0,0,0,0,0,0,0,0,0,0,0,0,0,0,0,0,0,0,0,0,0,0,0,0,0,0,0,0,0,0,0)';
      OUTPUT_LOAD='(1.0,-1.0)';
    'MDB_DQS_L9':
      PIN_NUMBER='(0,0,0,BW60,0,0,0,0,0,0,0,0,0,0,0,0,0,0,0,0,0,0,0,0,0,0,0,0,0,0,0,0,0,0,0,0,0,0,0,0)';
      BIDIRECTIONAL='TRUE';
      INPUT_LOAD='(-0.01,0.01)';
      OUTPUT_LOAD='(1.0,-1.0)';
    'MDB_DQS_H5':
      PIN_NUMBER='(0,0,0,CF58,0,0,0,0,0,0,0,0,0,0,0,0,0,0,0,0,0,0,0,0,0,0,0,0,0,0,0,0,0,0,0,0,0,0,0,0)';
      BIDIRECTIONAL='TRUE';
      INPUT_LOAD='(-0.01,0.01)';
      OUTPUT_LOAD='(1.0,-1.0)';
    'MDA_DATA22':
      PIN_NUMBER='(0,0,0,AB60,0,0,0,0,0,0,0,0,0,0,0,0,0,0,0,0,0,0,0,0,0,0,0,0,0,0,0,0,0,0,0,0,0,0,0,0)';
      BIDIRECTIONAL='TRUE';
      INPUT_LOAD='(-0.01,0.01)';
      OUTPUT_LOAD='(1.0,-1.0)';
    'MDA_DATA11':
      PIN_NUMBER='(0,0,0,N59,0,0,0,0,0,0,0,0,0,0,0,0,0,0,0,0,0,0,0,0,0,0,0,0,0,0,0,0,0,0,0,0,0,0,0,0)';
      BIDIRECTIONAL='TRUE';
      INPUT_LOAD='(-0.01,0.01)';
      OUTPUT_LOAD='(1.0,-1.0)';
    'MDA_CHECK2':
      PIN_NUMBER='(0,0,0,AK60,0,0,0,0,0,0,0,0,0,0,0,0,0,0,0,0,0,0,0,0,0,0,0,0,0,0,0,0,0,0,0,0,0,0,0,0)';
      BIDIRECTIONAL='TRUE';
      INPUT_LOAD='(-0.01,0.01)';
      OUTPUT_LOAD='(1.0,-1.0)';
    'MDA_CA4':
      PIN_NUMBER='(0,0,0,BA60,0,0,0,0,0,0,0,0,0,0,0,0,0,0,0,0,0,0,0,0,0,0,0,0,0,0,0,0,0,0,0,0,0,0,0,0)';
      OUTPUT_LOAD='(1.0,-1.0)';
    'MDB_DQS_H6':
      PIN_NUMBER='(0,0,0,CM58,0,0,0,0,0,0,0,0,0,0,0,0,0,0,0,0,0,0,0,0,0,0,0,0,0,0,0,0,0,0,0,0,0,0,0,0)';
      BIDIRECTIONAL='TRUE';
      INPUT_LOAD='(-0.01,0.01)';
      OUTPUT_LOAD='(1.0,-1.0)';
    'MDB_CA4':
      PIN_NUMBER='(0,0,0,BJ59,0,0,0,0,0,0,0,0,0,0,0,0,0,0,0,0,0,0,0,0,0,0,0,0,0,0,0,0,0,0,0,0,0,0,0,0)';
      OUTPUT_LOAD='(1.0,-1.0)';
    'MDA_DATA23':
      PIN_NUMBER='(0,0,0,AC59,0,0,0,0,0,0,0,0,0,0,0,0,0,0,0,0,0,0,0,0,0,0,0,0,0,0,0,0,0,0,0,0,0,0,0,0)';
      BIDIRECTIONAL='TRUE';
      INPUT_LOAD='(-0.01,0.01)';
      OUTPUT_LOAD='(1.0,-1.0)';
    'MDA_DATA12':
      PIN_NUMBER='(0,0,0,R60,0,0,0,0,0,0,0,0,0,0,0,0,0,0,0,0,0,0,0,0,0,0,0,0,0,0,0,0,0,0,0,0,0,0,0,0)';
      BIDIRECTIONAL='TRUE';
      INPUT_LOAD='(-0.01,0.01)';
      OUTPUT_LOAD='(1.0,-1.0)';
    'MDA_CHECK3':
      PIN_NUMBER='(0,0,0,AL59,0,0,0,0,0,0,0,0,0,0,0,0,0,0,0,0,0,0,0,0,0,0,0,0,0,0,0,0,0,0,0,0,0,0,0,0)';
      BIDIRECTIONAL='TRUE';
      INPUT_LOAD='(-0.01,0.01)';
      OUTPUT_LOAD='(1.0,-1.0)';
    'MDA_CA5':
      PIN_NUMBER='(0,0,0,BB60,0,0,0,0,0,0,0,0,0,0,0,0,0,0,0,0,0,0,0,0,0,0,0,0,0,0,0,0,0,0,0,0,0,0,0,0)';
      OUTPUT_LOAD='(1.0,-1.0)';
    'MDB_DQS_H7':
      PIN_NUMBER='(0,0,0,CV58,0,0,0,0,0,0,0,0,0,0,0,0,0,0,0,0,0,0,0,0,0,0,0,0,0,0,0,0,0,0,0,0,0,0,0,0)';
      BIDIRECTIONAL='TRUE';
      INPUT_LOAD='(-0.01,0.01)';
      OUTPUT_LOAD='(1.0,-1.0)';
    'MDB_CA5':
      PIN_NUMBER='(0,0,0,BK58,0,0,0,0,0,0,0,0,0,0,0,0,0,0,0,0,0,0,0,0,0,0,0,0,0,0,0,0,0,0,0,0,0,0,0,0)';
      OUTPUT_LOAD='(1.0,-1.0)';
    'MDB0_CS_L0':
      PIN_NUMBER='(0,0,0,BM58,0,0,0,0,0,0,0,0,0,0,0,0,0,0,0,0,0,0,0,0,0,0,0,0,0,0,0,0,0,0,0,0,0,0,0,0)';
      OUTPUT_LOAD='(1.0,-1.0)';
    'MDA_DQS_L0':
      PIN_NUMBER='(0,0,0,H60,0,0,0,0,0,0,0,0,0,0,0,0,0,0,0,0,0,0,0,0,0,0,0,0,0,0,0,0,0,0,0,0,0,0,0,0)';
      BIDIRECTIONAL='TRUE';
      INPUT_LOAD='(-0.01,0.01)';
      OUTPUT_LOAD='(1.0,-1.0)';
    'MDA_DATA24':
      PIN_NUMBER='(0,0,0,AC60,0,0,0,0,0,0,0,0,0,0,0,0,0,0,0,0,0,0,0,0,0,0,0,0,0,0,0,0,0,0,0,0,0,0,0,0)';
      BIDIRECTIONAL='TRUE';
      INPUT_LOAD='(-0.01,0.01)';
      OUTPUT_LOAD='(1.0,-1.0)';
    'MDA_DATA13':
      PIN_NUMBER='(0,0,0,T58,0,0,0,0,0,0,0,0,0,0,0,0,0,0,0,0,0,0,0,0,0,0,0,0,0,0,0,0,0,0,0,0,0,0,0,0)';
      BIDIRECTIONAL='TRUE';
      INPUT_LOAD='(-0.01,0.01)';
      OUTPUT_LOAD='(1.0,-1.0)';
    'MDA_CHECK4':
      PIN_NUMBER='(0,0,0,AN60,0,0,0,0,0,0,0,0,0,0,0,0,0,0,0,0,0,0,0,0,0,0,0,0,0,0,0,0,0,0,0,0,0,0,0,0)';
      BIDIRECTIONAL='TRUE';
      INPUT_LOAD='(-0.01,0.01)';
      OUTPUT_LOAD='(1.0,-1.0)';
    'MDA_CA6':
      PIN_NUMBER='(0,0,0,BB58,0,0,0,0,0,0,0,0,0,0,0,0,0,0,0,0,0,0,0,0,0,0,0,0,0,0,0,0,0,0,0,0,0,0,0,0)';
      OUTPUT_LOAD='(1.0,-1.0)';
    'MDB_DQS_H8':
      PIN_NUMBER='(0,0,0,DD58,0,0,0,0,0,0,0,0,0,0,0,0,0,0,0,0,0,0,0,0,0,0,0,0,0,0,0,0,0,0,0,0,0,0,0,0)';
      BIDIRECTIONAL='TRUE';
      INPUT_LOAD='(-0.01,0.01)';
      OUTPUT_LOAD='(1.0,-1.0)';
    'MDB_DATA30':
      PIN_NUMBER='(0,0,0,DE60,0,0,0,0,0,0,0,0,0,0,0,0,0,0,0,0,0,0,0,0,0,0,0,0,0,0,0,0,0,0,0,0,0,0,0,0)';
      BIDIRECTIONAL='TRUE';
      INPUT_LOAD='(-0.01,0.01)';
      OUTPUT_LOAD='(1.0,-1.0)';
    'MDB_CA6':
      PIN_NUMBER='(0,0,0,BK60,0,0,0,0,0,0,0,0,0,0,0,0,0,0,0,0,0,0,0,0,0,0,0,0,0,0,0,0,0,0,0,0,0,0,0,0)';
      OUTPUT_LOAD='(1.0,-1.0)';
    'MDB1_CS_L0':
      PIN_NUMBER='(0,0,0,BL59,0,0,0,0,0,0,0,0,0,0,0,0,0,0,0,0,0,0,0,0,0,0,0,0,0,0,0,0,0,0,0,0,0,0,0,0)';
      OUTPUT_LOAD='(1.0,-1.0)';
    'MDB0_CS_L1':
      PIN_NUMBER='(0,0,0,BN60,0,0,0,0,0,0,0,0,0,0,0,0,0,0,0,0,0,0,0,0,0,0,0,0,0,0,0,0,0,0,0,0,0,0,0,0)';
      OUTPUT_LOAD='(1.0,-1.0)';
    'MDA_DQS_L1':
      PIN_NUMBER='(0,0,0,P60,0,0,0,0,0,0,0,0,0,0,0,0,0,0,0,0,0,0,0,0,0,0,0,0,0,0,0,0,0,0,0,0,0,0,0,0)';
      BIDIRECTIONAL='TRUE';
      INPUT_LOAD='(-0.01,0.01)';
      OUTPUT_LOAD='(1.0,-1.0)';
    'MDA_DATA25':
      PIN_NUMBER='(0,0,0,AD58,0,0,0,0,0,0,0,0,0,0,0,0,0,0,0,0,0,0,0,0,0,0,0,0,0,0,0,0,0,0,0,0,0,0,0,0)';
      BIDIRECTIONAL='TRUE';
      INPUT_LOAD='(-0.01,0.01)';
      OUTPUT_LOAD='(1.0,-1.0)';
    'MDA_DATA14':
      PIN_NUMBER='(0,0,0,T60,0,0,0,0,0,0,0,0,0,0,0,0,0,0,0,0,0,0,0,0,0,0,0,0,0,0,0,0,0,0,0,0,0,0,0,0)';
      BIDIRECTIONAL='TRUE';
      INPUT_LOAD='(-0.01,0.01)';
      OUTPUT_LOAD='(1.0,-1.0)';
    'MDA_CHECK5':
      PIN_NUMBER='(0,0,0,AP58,0,0,0,0,0,0,0,0,0,0,0,0,0,0,0,0,0,0,0,0,0,0,0,0,0,0,0,0,0,0,0,0,0,0,0,0)';
      BIDIRECTIONAL='TRUE';
      INPUT_LOAD='(-0.01,0.01)';
      OUTPUT_LOAD='(1.0,-1.0)';
    'MDB_DATA31':
      PIN_NUMBER='(0,0,0,DF60,0,0,0,0,0,0,0,0,0,0,0,0,0,0,0,0,0,0,0,0,0,0,0,0,0,0,0,0,0,0,0,0,0,0,0,0)';
      BIDIRECTIONAL='TRUE';
      INPUT_LOAD='(-0.01,0.01)';
      OUTPUT_LOAD='(1.0,-1.0)';
    'MDB_DATA20':
      PIN_NUMBER='(0,0,0,CV60,0,0,0,0,0,0,0,0,0,0,0,0,0,0,0,0,0,0,0,0,0,0,0,0,0,0,0,0,0,0,0,0,0,0,0,0)';
      BIDIRECTIONAL='TRUE';
      INPUT_LOAD='(-0.01,0.01)';
      OUTPUT_LOAD='(1.0,-1.0)';
    'MDB_CHECK0':
      PIN_NUMBER='(0,0,0,BY60,0,0,0,0,0,0,0,0,0,0,0,0,0,0,0,0,0,0,0,0,0,0,0,0,0,0,0,0,0,0,0,0,0,0,0,0)';
      BIDIRECTIONAL='TRUE';
      INPUT_LOAD='(-0.01,0.01)';
      OUTPUT_LOAD='(1.0,-1.0)';
    'MDB1_CS_L1':
      PIN_NUMBER='(0,0,0,BM60,0,0,0,0,0,0,0,0,0,0,0,0,0,0,0,0,0,0,0,0,0,0,0,0,0,0,0,0,0,0,0,0,0,0,0,0)';
      OUTPUT_LOAD='(1.0,-1.0)';
    'MDA_DQS_L2':
      PIN_NUMBER='(0,0,0,Y60,0,0,0,0,0,0,0,0,0,0,0,0,0,0,0,0,0,0,0,0,0,0,0,0,0,0,0,0,0,0,0,0,0,0,0,0)';
      BIDIRECTIONAL='TRUE';
      INPUT_LOAD='(-0.01,0.01)';
      OUTPUT_LOAD='(1.0,-1.0)';
    'MDA_DATA26':
      PIN_NUMBER='(0,0,0,AD60,0,0,0,0,0,0,0,0,0,0,0,0,0,0,0,0,0,0,0,0,0,0,0,0,0,0,0,0,0,0,0,0,0,0,0,0)';
      BIDIRECTIONAL='TRUE';
      INPUT_LOAD='(-0.01,0.01)';
      OUTPUT_LOAD='(1.0,-1.0)';
    'MDA_DATA15':
      PIN_NUMBER='(0,0,0,U59,0,0,0,0,0,0,0,0,0,0,0,0,0,0,0,0,0,0,0,0,0,0,0,0,0,0,0,0,0,0,0,0,0,0,0,0)';
      BIDIRECTIONAL='TRUE';
      INPUT_LOAD='(-0.01,0.01)';
      OUTPUT_LOAD='(1.0,-1.0)';
    'MDA_DATA0':
      PIN_NUMBER='(0,0,0,E60,0,0,0,0,0,0,0,0,0,0,0,0,0,0,0,0,0,0,0,0,0,0,0,0,0,0,0,0,0,0,0,0,0,0,0,0)';
      BIDIRECTIONAL='TRUE';
      INPUT_LOAD='(-0.01,0.01)';
      OUTPUT_LOAD='(1.0,-1.0)';
    'MDA_CHECK6':
      PIN_NUMBER='(0,0,0,AP60,0,0,0,0,0,0,0,0,0,0,0,0,0,0,0,0,0,0,0,0,0,0,0,0,0,0,0,0,0,0,0,0,0,0,0,0)';
      BIDIRECTIONAL='TRUE';
      INPUT_LOAD='(-0.01,0.01)';
      OUTPUT_LOAD='(1.0,-1.0)';
    'MDB_DATA21':
      PIN_NUMBER='(0,0,0,CW59,0,0,0,0,0,0,0,0,0,0,0,0,0,0,0,0,0,0,0,0,0,0,0,0,0,0,0,0,0,0,0,0,0,0,0,0)';
      BIDIRECTIONAL='TRUE';
      INPUT_LOAD='(-0.01,0.01)';
      OUTPUT_LOAD='(1.0,-1.0)';
    'MDB_DATA10':
      PIN_NUMBER='(0,0,0,CJ60,0,0,0,0,0,0,0,0,0,0,0,0,0,0,0,0,0,0,0,0,0,0,0,0,0,0,0,0,0,0,0,0,0,0,0,0)';
      BIDIRECTIONAL='TRUE';
      INPUT_LOAD='(-0.01,0.01)';
      OUTPUT_LOAD='(1.0,-1.0)';
    'MDB_DATA0':
      PIN_NUMBER='(0,0,0,CB60,0,0,0,0,0,0,0,0,0,0,0,0,0,0,0,0,0,0,0,0,0,0,0,0,0,0,0,0,0,0,0,0,0,0,0,0)';
      BIDIRECTIONAL='TRUE';
      INPUT_LOAD='(-0.01,0.01)';
      OUTPUT_LOAD='(1.0,-1.0)';
    'MDB_CHECK1':
      PIN_NUMBER='(0,0,0,CA59,0,0,0,0,0,0,0,0,0,0,0,0,0,0,0,0,0,0,0,0,0,0,0,0,0,0,0,0,0,0,0,0,0,0,0,0)';
      BIDIRECTIONAL='TRUE';
      INPUT_LOAD='(-0.01,0.01)';
      OUTPUT_LOAD='(1.0,-1.0)';
    'MDA_DQS_L3':
      PIN_NUMBER='(0,0,0,AF60,0,0,0,0,0,0,0,0,0,0,0,0,0,0,0,0,0,0,0,0,0,0,0,0,0,0,0,0,0,0,0,0,0,0,0,0)';
      BIDIRECTIONAL='TRUE';
      INPUT_LOAD='(-0.01,0.01)';
      OUTPUT_LOAD='(1.0,-1.0)';
    'MDA_DATA27':
      PIN_NUMBER='(0,0,0,AE59,0,0,0,0,0,0,0,0,0,0,0,0,0,0,0,0,0,0,0,0,0,0,0,0,0,0,0,0,0,0,0,0,0,0,0,0)';
      BIDIRECTIONAL='TRUE';
      INPUT_LOAD='(-0.01,0.01)';
      OUTPUT_LOAD='(1.0,-1.0)';
    'MDA_DATA16':
      PIN_NUMBER='(0,0,0,U60,0,0,0,0,0,0,0,0,0,0,0,0,0,0,0,0,0,0,0,0,0,0,0,0,0,0,0,0,0,0,0,0,0,0,0,0)';
      BIDIRECTIONAL='TRUE';
      INPUT_LOAD='(-0.01,0.01)';
      OUTPUT_LOAD='(1.0,-1.0)';
    'MDA_DATA1':
      PIN_NUMBER='(0,0,0,F58,0,0,0,0,0,0,0,0,0,0,0,0,0,0,0,0,0,0,0,0,0,0,0,0,0,0,0,0,0,0,0,0,0,0,0,0)';
      BIDIRECTIONAL='TRUE';
      INPUT_LOAD='(-0.01,0.01)';
      OUTPUT_LOAD='(1.0,-1.0)';
    'MDA_CHECK7':
      PIN_NUMBER='(0,0,0,AR59,0,0,0,0,0,0,0,0,0,0,0,0,0,0,0,0,0,0,0,0,0,0,0,0,0,0,0,0,0,0,0,0,0,0,0,0)';
      BIDIRECTIONAL='TRUE';
      INPUT_LOAD='(-0.01,0.01)';
      OUTPUT_LOAD='(1.0,-1.0)';
    'MDA0_RSP_L':
      PIN_NUMBER='(0,0,0,BN59,0,0,0,0,0,0,0,0,0,0,0,0,0,0,0,0,0,0,0,0,0,0,0,0,0,0,0,0,0,0,0,0,0,0,0,0)';
      INPUT_LOAD='(-0.01,0.01)';
    'MDB_DATA22':
      PIN_NUMBER='(0,0,0,CW60,0,0,0,0,0,0,0,0,0,0,0,0,0,0,0,0,0,0,0,0,0,0,0,0,0,0,0,0,0,0,0,0,0,0,0,0)';
      BIDIRECTIONAL='TRUE';
      INPUT_LOAD='(-0.01,0.01)';
      OUTPUT_LOAD='(1.0,-1.0)';
    'MDB_DATA11':
      PIN_NUMBER='(0,0,0,CK58,0,0,0,0,0,0,0,0,0,0,0,0,0,0,0,0,0,0,0,0,0,0,0,0,0,0,0,0,0,0,0,0,0,0,0,0)';
      BIDIRECTIONAL='TRUE';
      INPUT_LOAD='(-0.01,0.01)';
      OUTPUT_LOAD='(1.0,-1.0)';
    'MDB_DATA1':
      PIN_NUMBER='(0,0,0,CC59,0,0,0,0,0,0,0,0,0,0,0,0,0,0,0,0,0,0,0,0,0,0,0,0,0,0,0,0,0,0,0,0,0,0,0,0)';
      BIDIRECTIONAL='TRUE';
      INPUT_LOAD='(-0.01,0.01)';
      OUTPUT_LOAD='(1.0,-1.0)';
    'MDB_CHECK2':
      PIN_NUMBER='(0,0,0,CA60,0,0,0,0,0,0,0,0,0,0,0,0,0,0,0,0,0,0,0,0,0,0,0,0,0,0,0,0,0,0,0,0,0,0,0,0)';
      BIDIRECTIONAL='TRUE';
      INPUT_LOAD='(-0.01,0.01)';
      OUTPUT_LOAD='(1.0,-1.0)';
    'MDA_DQS_L4':
      PIN_NUMBER='(0,0,0,AM60,0,0,0,0,0,0,0,0,0,0,0,0,0,0,0,0,0,0,0,0,0,0,0,0,0,0,0,0,0,0,0,0,0,0,0,0)';
      BIDIRECTIONAL='TRUE';
      INPUT_LOAD='(-0.01,0.01)';
      OUTPUT_LOAD='(1.0,-1.0)';
    'MDA_DQS_H0':
      PIN_NUMBER='(0,0,0,G60,0,0,0,0,0,0,0,0,0,0,0,0,0,0,0,0,0,0,0,0,0,0,0,0,0,0,0,0,0,0,0,0,0,0,0,0)';
      BIDIRECTIONAL='TRUE';
      INPUT_LOAD='(-0.01,0.01)';
      OUTPUT_LOAD='(1.0,-1.0)';
    'MDA_DATA28':
      PIN_NUMBER='(0,0,0,AG60,0,0,0,0,0,0,0,0,0,0,0,0,0,0,0,0,0,0,0,0,0,0,0,0,0,0,0,0,0,0,0,0,0,0,0,0)';
      BIDIRECTIONAL='TRUE';
      INPUT_LOAD='(-0.01,0.01)';
      OUTPUT_LOAD='(1.0,-1.0)';
    'MDA_DATA17':
      PIN_NUMBER='(0,0,0,V58,0,0,0,0,0,0,0,0,0,0,0,0,0,0,0,0,0,0,0,0,0,0,0,0,0,0,0,0,0,0,0,0,0,0,0,0)';
      BIDIRECTIONAL='TRUE';
      INPUT_LOAD='(-0.01,0.01)';
      OUTPUT_LOAD='(1.0,-1.0)';
    'MDA_DATA2':
      PIN_NUMBER='(0,0,0,F60,0,0,0,0,0,0,0,0,0,0,0,0,0,0,0,0,0,0,0,0,0,0,0,0,0,0,0,0,0,0,0,0,0,0,0,0)';
      BIDIRECTIONAL='TRUE';
      INPUT_LOAD='(-0.01,0.01)';
      OUTPUT_LOAD='(1.0,-1.0)';
    'MDA1_RSP_L':
      PIN_NUMBER='(0,0,0,BP58,0,0,0,0,0,0,0,0,0,0,0,0,0,0,0,0,0,0,0,0,0,0,0,0,0,0,0,0,0,0,0,0,0,0,0,0)';
      INPUT_LOAD='(-0.01,0.01)';
    'MDA_PAR':
      PIN_NUMBER='(0,0,0,BC59,0,0,0,0,0,0,0,0,0,0,0,0,0,0,0,0,0,0,0,0,0,0,0,0,0,0,0,0,0,0,0,0,0,0,0,0)';
      OUTPUT_LOAD='(1.0,-1.0)';
    'MDB_PAR':
      PIN_NUMBER='(0,0,0,BL60,0,0,0,0,0,0,0,0,0,0,0,0,0,0,0,0,0,0,0,0,0,0,0,0,0,0,0,0,0,0,0,0,0,0,0,0)';
      OUTPUT_LOAD='(1.0,-1.0)';
    'MDB_CA3':
      PIN_NUMBER='(0,0,0,BJ60,0,0,0,0,0,0,0,0,0,0,0,0,0,0,0,0,0,0,0,0,0,0,0,0,0,0,0,0,0,0,0,0,0,0,0,0)';
      OUTPUT_LOAD='(1.0,-1.0)';
    'MDB_DQS_H9':
      PIN_NUMBER='(0,0,0,BV60,0,0,0,0,0,0,0,0,0,0,0,0,0,0,0,0,0,0,0,0,0,0,0,0,0,0,0,0,0,0,0,0,0,0,0,0)';
      BIDIRECTIONAL='TRUE';
      INPUT_LOAD='(-0.01,0.01)';
      OUTPUT_LOAD='(1.0,-1.0)';
    'MD0_CLK_H':
      PIN_NUMBER='(0,0,0,BC60,0,0,0,0,0,0,0,0,0,0,0,0,0,0,0,0,0,0,0,0,0,0,0,0,0,0,0,0,0,0,0,0,0,0,0,0)';
      OUTPUT_LOAD='(1.0,-1.0)';
    'MD0_CLK_L':
      PIN_NUMBER='(0,0,0,BD60,0,0,0,0,0,0,0,0,0,0,0,0,0,0,0,0,0,0,0,0,0,0,0,0,0,0,0,0,0,0,0,0,0,0,0,0)';
      OUTPUT_LOAD='(1.0,-1.0)';
    'MD1_CLK_H':
      PIN_NUMBER='(0,0,0,BF60,0,0,0,0,0,0,0,0,0,0,0,0,0,0,0,0,0,0,0,0,0,0,0,0,0,0,0,0,0,0,0,0,0,0,0,0)';
      OUTPUT_LOAD='(1.0,-1.0)';
    'MD1_CLK_L':
      PIN_NUMBER='(0,0,0,BG60,0,0,0,0,0,0,0,0,0,0,0,0,0,0,0,0,0,0,0,0,0,0,0,0,0,0,0,0,0,0,0,0,0,0,0,0)';
      OUTPUT_LOAD='(1.0,-1.0)';
    'TEST39D':
      PIN_NUMBER='(0,0,0,BF58,0,0,0,0,0,0,0,0,0,0,0,0,0,0,0,0,0,0,0,0,0,0,0,0,0,0,0,0,0,0,0,0,0,0,0,0)';
      OUTPUT_LOAD='(1.0,-1.0)';
    'ME_ALERT_L':
      PIN_NUMBER='(0,0,0,0,AT69,0,0,0,0,0,0,0,0,0,0,0,0,0,0,0,0,0,0,0,0,0,0,0,0,0,0,0,0,0,0,0,0,0,0,0)';
      INPUT_LOAD='(-0.01,0.01)';
    'ME_RESET_L':
      PIN_NUMBER='(0,0,0,0,AU69,0,0,0,0,0,0,0,0,0,0,0,0,0,0,0,0,0,0,0,0,0,0,0,0,0,0,0,0,0,0,0,0,0,0,0)';
      OUTPUT_LOAD='(1.0,-1.0)';
    'MEB_DQS_L2':
      PIN_NUMBER='(0,0,0,0,CU71,0,0,0,0,0,0,0,0,0,0,0,0,0,0,0,0,0,0,0,0,0,0,0,0,0,0,0,0,0,0,0,0,0,0,0)';
      BIDIRECTIONAL='TRUE';
      INPUT_LOAD='(-0.01,0.01)';
      OUTPUT_LOAD='(1.0,-1.0)';
    'MEB_DATA26':
      PIN_NUMBER='(0,0,0,0,DA71,0,0,0,0,0,0,0,0,0,0,0,0,0,0,0,0,0,0,0,0,0,0,0,0,0,0,0,0,0,0,0,0,0,0,0)';
      BIDIRECTIONAL='TRUE';
      INPUT_LOAD='(-0.01,0.01)';
      OUTPUT_LOAD='(1.0,-1.0)';
    'MEB_DATA15':
      PIN_NUMBER='(0,0,0,0,CP69,0,0,0,0,0,0,0,0,0,0,0,0,0,0,0,0,0,0,0,0,0,0,0,0,0,0,0,0,0,0,0,0,0,0,0)';
      BIDIRECTIONAL='TRUE';
      INPUT_LOAD='(-0.01,0.01)';
      OUTPUT_LOAD='(1.0,-1.0)';
    'MEB_CHECK6':
      PIN_NUMBER='(0,0,0,0,BU71,0,0,0,0,0,0,0,0,0,0,0,0,0,0,0,0,0,0,0,0,0,0,0,0,0,0,0,0,0,0,0,0,0,0,0)';
      BIDIRECTIONAL='TRUE';
      INPUT_LOAD='(-0.01,0.01)';
      OUTPUT_LOAD='(1.0,-1.0)';
    'MEA_DQS_L8':
      PIN_NUMBER='(0,0,0,0,AF69,0,0,0,0,0,0,0,0,0,0,0,0,0,0,0,0,0,0,0,0,0,0,0,0,0,0,0,0,0,0,0,0,0,0,0)';
      BIDIRECTIONAL='TRUE';
      INPUT_LOAD='(-0.01,0.01)';
      OUTPUT_LOAD='(1.0,-1.0)';
    'MEA_DQS_H4':
      PIN_NUMBER='(0,0,0,0,AL71,0,0,0,0,0,0,0,0,0,0,0,0,0,0,0,0,0,0,0,0,0,0,0,0,0,0,0,0,0,0,0,0,0,0,0)';
      BIDIRECTIONAL='TRUE';
      INPUT_LOAD='(-0.01,0.01)';
      OUTPUT_LOAD='(1.0,-1.0)';
    'MEB_DQS_L3':
      PIN_NUMBER='(0,0,0,0,DC71,0,0,0,0,0,0,0,0,0,0,0,0,0,0,0,0,0,0,0,0,0,0,0,0,0,0,0,0,0,0,0,0,0,0,0)';
      BIDIRECTIONAL='TRUE';
      INPUT_LOAD='(-0.01,0.01)';
      OUTPUT_LOAD='(1.0,-1.0)';
    'MEB_DATA27':
      PIN_NUMBER='(0,0,0,0,DB69,0,0,0,0,0,0,0,0,0,0,0,0,0,0,0,0,0,0,0,0,0,0,0,0,0,0,0,0,0,0,0,0,0,0,0)';
      BIDIRECTIONAL='TRUE';
      INPUT_LOAD='(-0.01,0.01)';
      OUTPUT_LOAD='(1.0,-1.0)';
    'MEB_DATA16':
      PIN_NUMBER='(0,0,0,0,CP70,0,0,0,0,0,0,0,0,0,0,0,0,0,0,0,0,0,0,0,0,0,0,0,0,0,0,0,0,0,0,0,0,0,0,0)';
      BIDIRECTIONAL='TRUE';
      INPUT_LOAD='(-0.01,0.01)';
      OUTPUT_LOAD='(1.0,-1.0)';
    'MEB_CHECK7':
      PIN_NUMBER='(0,0,0,0,BV69,0,0,0,0,0,0,0,0,0,0,0,0,0,0,0,0,0,0,0,0,0,0,0,0,0,0,0,0,0,0,0,0,0,0,0)';
      BIDIRECTIONAL='TRUE';
      INPUT_LOAD='(-0.01,0.01)';
      OUTPUT_LOAD='(1.0,-1.0)';
    'MEB1_RSP_L':
      PIN_NUMBER='(0,0,0,0,BR71,0,0,0,0,0,0,0,0,0,0,0,0,0,0,0,0,0,0,0,0,0,0,0,0,0,0,0,0,0,0,0,0,0,0,0)';
      INPUT_LOAD='(-0.01,0.01)';
    'MEB0_RSP_L':
      PIN_NUMBER='(0,0,0,0,BP70,0,0,0,0,0,0,0,0,0,0,0,0,0,0,0,0,0,0,0,0,0,0,0,0,0,0,0,0,0,0,0,0,0,0,0)';
      INPUT_LOAD='(-0.01,0.01)';
    'MEA_DQS_L9':
      PIN_NUMBER='(0,0,0,0,AM69,0,0,0,0,0,0,0,0,0,0,0,0,0,0,0,0,0,0,0,0,0,0,0,0,0,0,0,0,0,0,0,0,0,0,0)';
      BIDIRECTIONAL='TRUE';
      INPUT_LOAD='(-0.01,0.01)';
      OUTPUT_LOAD='(1.0,-1.0)';
    'MEA_DQS_H5':
      PIN_NUMBER='(0,0,0,0,J69,0,0,0,0,0,0,0,0,0,0,0,0,0,0,0,0,0,0,0,0,0,0,0,0,0,0,0,0,0,0,0,0,0,0,0)';
      BIDIRECTIONAL='TRUE';
      INPUT_LOAD='(-0.01,0.01)';
      OUTPUT_LOAD='(1.0,-1.0)';
    'MEB_DQS_L4':
      PIN_NUMBER='(0,0,0,0,BW69,0,0,0,0,0,0,0,0,0,0,0,0,0,0,0,0,0,0,0,0,0,0,0,0,0,0,0,0,0,0,0,0,0,0,0)';
      BIDIRECTIONAL='TRUE';
      INPUT_LOAD='(-0.01,0.01)';
      OUTPUT_LOAD='(1.0,-1.0)';
    'MEB_DQS_H0':
      PIN_NUMBER='(0,0,0,0,CD70,0,0,0,0,0,0,0,0,0,0,0,0,0,0,0,0,0,0,0,0,0,0,0,0,0,0,0,0,0,0,0,0,0,0,0)';
      BIDIRECTIONAL='TRUE';
      INPUT_LOAD='(-0.01,0.01)';
      OUTPUT_LOAD='(1.0,-1.0)';
    'MEB_DATA28':
      PIN_NUMBER='(0,0,0,0,DD70,0,0,0,0,0,0,0,0,0,0,0,0,0,0,0,0,0,0,0,0,0,0,0,0,0,0,0,0,0,0,0,0,0,0,0)';
      BIDIRECTIONAL='TRUE';
      INPUT_LOAD='(-0.01,0.01)';
      OUTPUT_LOAD='(1.0,-1.0)';
    'MEB_DATA17':
      PIN_NUMBER='(0,0,0,0,CR69,0,0,0,0,0,0,0,0,0,0,0,0,0,0,0,0,0,0,0,0,0,0,0,0,0,0,0,0,0,0,0,0,0,0,0)';
      BIDIRECTIONAL='TRUE';
      INPUT_LOAD='(-0.01,0.01)';
      OUTPUT_LOAD='(1.0,-1.0)';
    'MEA_DQS_H6':
      PIN_NUMBER='(0,0,0,0,R69,0,0,0,0,0,0,0,0,0,0,0,0,0,0,0,0,0,0,0,0,0,0,0,0,0,0,0,0,0,0,0,0,0,0,0)';
      BIDIRECTIONAL='TRUE';
      INPUT_LOAD='(-0.01,0.01)';
      OUTPUT_LOAD='(1.0,-1.0)';
    'MEB_DQS_L5':
      PIN_NUMBER='(0,0,0,0,CE69,0,0,0,0,0,0,0,0,0,0,0,0,0,0,0,0,0,0,0,0,0,0,0,0,0,0,0,0,0,0,0,0,0,0,0)';
      BIDIRECTIONAL='TRUE';
      INPUT_LOAD='(-0.01,0.01)';
      OUTPUT_LOAD='(1.0,-1.0)';
    'MEB_DQS_H1':
      PIN_NUMBER='(0,0,0,0,CK70,0,0,0,0,0,0,0,0,0,0,0,0,0,0,0,0,0,0,0,0,0,0,0,0,0,0,0,0,0,0,0,0,0,0,0)';
      BIDIRECTIONAL='TRUE';
      INPUT_LOAD='(-0.01,0.01)';
      OUTPUT_LOAD='(1.0,-1.0)';
    'MEB_DATA29':
      PIN_NUMBER='(0,0,0,0,DE69,0,0,0,0,0,0,0,0,0,0,0,0,0,0,0,0,0,0,0,0,0,0,0,0,0,0,0,0,0,0,0,0,0,0,0)';
      BIDIRECTIONAL='TRUE';
      INPUT_LOAD='(-0.01,0.01)';
      OUTPUT_LOAD='(1.0,-1.0)';
    'MEB_DATA18':
      PIN_NUMBER='(0,0,0,0,CR71,0,0,0,0,0,0,0,0,0,0,0,0,0,0,0,0,0,0,0,0,0,0,0,0,0,0,0,0,0,0,0,0,0,0,0)';
      BIDIRECTIONAL='TRUE';
      INPUT_LOAD='(-0.01,0.01)';
      OUTPUT_LOAD='(1.0,-1.0)';
    'MEA_DQS_H7':
      PIN_NUMBER='(0,0,0,0,AA69,0,0,0,0,0,0,0,0,0,0,0,0,0,0,0,0,0,0,0,0,0,0,0,0,0,0,0,0,0,0,0,0,0,0,0)';
      BIDIRECTIONAL='TRUE';
      INPUT_LOAD='(-0.01,0.01)';
      OUTPUT_LOAD='(1.0,-1.0)';
    'MEA_DATA0':
      PIN_NUMBER='(0,0,0,0,E71,0,0,0,0,0,0,0,0,0,0,0,0,0,0,0,0,0,0,0,0,0,0,0,0,0,0,0,0,0,0,0,0,0,0,0)';
      BIDIRECTIONAL='TRUE';
      INPUT_LOAD='(-0.01,0.01)';
      OUTPUT_LOAD='(1.0,-1.0)';
    'MEA1_CS_L0':
      PIN_NUMBER='(0,0,0,0,AU71,0,0,0,0,0,0,0,0,0,0,0,0,0,0,0,0,0,0,0,0,0,0,0,0,0,0,0,0,0,0,0,0,0,0,0)';
      OUTPUT_LOAD='(1.0,-1.0)';
    'MEA0_CS_L0':
      PIN_NUMBER='(0,0,0,0,AV70,0,0,0,0,0,0,0,0,0,0,0,0,0,0,0,0,0,0,0,0,0,0,0,0,0,0,0,0,0,0,0,0,0,0,0)';
      OUTPUT_LOAD='(1.0,-1.0)';
    'MEB_DQS_L6':
      PIN_NUMBER='(0,0,0,0,CL69,0,0,0,0,0,0,0,0,0,0,0,0,0,0,0,0,0,0,0,0,0,0,0,0,0,0,0,0,0,0,0,0,0,0,0)';
      BIDIRECTIONAL='TRUE';
      INPUT_LOAD='(-0.01,0.01)';
      OUTPUT_LOAD='(1.0,-1.0)';
    'MEB_DQS_H2':
      PIN_NUMBER='(0,0,0,0,CT70,0,0,0,0,0,0,0,0,0,0,0,0,0,0,0,0,0,0,0,0,0,0,0,0,0,0,0,0,0,0,0,0,0,0,0)';
      BIDIRECTIONAL='TRUE';
      INPUT_LOAD='(-0.01,0.01)';
      OUTPUT_LOAD='(1.0,-1.0)';
    'MEB_DATA19':
      PIN_NUMBER='(0,0,0,0,CT69,0,0,0,0,0,0,0,0,0,0,0,0,0,0,0,0,0,0,0,0,0,0,0,0,0,0,0,0,0,0,0,0,0,0,0)';
      BIDIRECTIONAL='TRUE';
      INPUT_LOAD='(-0.01,0.01)';
      OUTPUT_LOAD='(1.0,-1.0)';
    'MEB_DATA0':
      PIN_NUMBER='(0,0,0,0,CB70,0,0,0,0,0,0,0,0,0,0,0,0,0,0,0,0,0,0,0,0,0,0,0,0,0,0,0,0,0,0,0,0,0,0,0)';
      BIDIRECTIONAL='TRUE';
      INPUT_LOAD='(-0.01,0.01)';
      OUTPUT_LOAD='(1.0,-1.0)';
    'MEA_DQS_H8':
      PIN_NUMBER='(0,0,0,0,AG69,0,0,0,0,0,0,0,0,0,0,0,0,0,0,0,0,0,0,0,0,0,0,0,0,0,0,0,0,0,0,0,0,0,0,0)';
      BIDIRECTIONAL='TRUE';
      INPUT_LOAD='(-0.01,0.01)';
      OUTPUT_LOAD='(1.0,-1.0)';
    'MEA_DATA30':
      PIN_NUMBER='(0,0,0,0,AH70,0,0,0,0,0,0,0,0,0,0,0,0,0,0,0,0,0,0,0,0,0,0,0,0,0,0,0,0,0,0,0,0,0,0,0)';
      BIDIRECTIONAL='TRUE';
      INPUT_LOAD='(-0.01,0.01)';
      OUTPUT_LOAD='(1.0,-1.0)';
    'MEA_DATA1':
      PIN_NUMBER='(0,0,0,0,F69,0,0,0,0,0,0,0,0,0,0,0,0,0,0,0,0,0,0,0,0,0,0,0,0,0,0,0,0,0,0,0,0,0,0,0)';
      BIDIRECTIONAL='TRUE';
      INPUT_LOAD='(-0.01,0.01)';
      OUTPUT_LOAD='(1.0,-1.0)';
    'MEA1_CS_L1':
      PIN_NUMBER='(0,0,0,0,AV69,0,0,0,0,0,0,0,0,0,0,0,0,0,0,0,0,0,0,0,0,0,0,0,0,0,0,0,0,0,0,0,0,0,0,0)';
      OUTPUT_LOAD='(1.0,-1.0)';
    'MEA0_CS_L1':
      PIN_NUMBER='(0,0,0,0,AW69,0,0,0,0,0,0,0,0,0,0,0,0,0,0,0,0,0,0,0,0,0,0,0,0,0,0,0,0,0,0,0,0,0,0,0)';
      OUTPUT_LOAD='(1.0,-1.0)';
    'MEB_DQS_L7':
      PIN_NUMBER='(0,0,0,0,CU69,0,0,0,0,0,0,0,0,0,0,0,0,0,0,0,0,0,0,0,0,0,0,0,0,0,0,0,0,0,0,0,0,0,0,0)';
      BIDIRECTIONAL='TRUE';
      INPUT_LOAD='(-0.01,0.01)';
      OUTPUT_LOAD='(1.0,-1.0)';
    'MEB_DQS_H3':
      PIN_NUMBER='(0,0,0,0,DB70,0,0,0,0,0,0,0,0,0,0,0,0,0,0,0,0,0,0,0,0,0,0,0,0,0,0,0,0,0,0,0,0,0,0,0)';
      BIDIRECTIONAL='TRUE';
      INPUT_LOAD='(-0.01,0.01)';
      OUTPUT_LOAD='(1.0,-1.0)';
    'MEB_DATA1':
      PIN_NUMBER='(0,0,0,0,CC69,0,0,0,0,0,0,0,0,0,0,0,0,0,0,0,0,0,0,0,0,0,0,0,0,0,0,0,0,0,0,0,0,0,0,0)';
      BIDIRECTIONAL='TRUE';
      INPUT_LOAD='(-0.01,0.01)';
      OUTPUT_LOAD='(1.0,-1.0)';
    'MEA_DQS_H9':
      PIN_NUMBER='(0,0,0,0,AN69,0,0,0,0,0,0,0,0,0,0,0,0,0,0,0,0,0,0,0,0,0,0,0,0,0,0,0,0,0,0,0,0,0,0,0)';
      BIDIRECTIONAL='TRUE';
      INPUT_LOAD='(-0.01,0.01)';
      OUTPUT_LOAD='(1.0,-1.0)';
    'MEA_DATA31':
      PIN_NUMBER='(0,0,0,0,AJ69,0,0,0,0,0,0,0,0,0,0,0,0,0,0,0,0,0,0,0,0,0,0,0,0,0,0,0,0,0,0,0,0,0,0,0)';
      BIDIRECTIONAL='TRUE';
      INPUT_LOAD='(-0.01,0.01)';
      OUTPUT_LOAD='(1.0,-1.0)';
    'MEA_DATA20':
      PIN_NUMBER='(0,0,0,0,AA71,0,0,0,0,0,0,0,0,0,0,0,0,0,0,0,0,0,0,0,0,0,0,0,0,0,0,0,0,0,0,0,0,0,0,0)';
      BIDIRECTIONAL='TRUE';
      INPUT_LOAD='(-0.01,0.01)';
      OUTPUT_LOAD='(1.0,-1.0)';
    'MEA_DATA2':
      PIN_NUMBER='(0,0,0,0,F70,0,0,0,0,0,0,0,0,0,0,0,0,0,0,0,0,0,0,0,0,0,0,0,0,0,0,0,0,0,0,0,0,0,0,0)';
      BIDIRECTIONAL='TRUE';
      INPUT_LOAD='(-0.01,0.01)';
      OUTPUT_LOAD='(1.0,-1.0)';
    'MEA_CHECK0':
      PIN_NUMBER='(0,0,0,0,AJ71,0,0,0,0,0,0,0,0,0,0,0,0,0,0,0,0,0,0,0,0,0,0,0,0,0,0,0,0,0,0,0,0,0,0,0)';
      BIDIRECTIONAL='TRUE';
      INPUT_LOAD='(-0.01,0.01)';
      OUTPUT_LOAD='(1.0,-1.0)';
    'MEA_CA0':
      PIN_NUMBER='(0,0,0,0,AW71,0,0,0,0,0,0,0,0,0,0,0,0,0,0,0,0,0,0,0,0,0,0,0,0,0,0,0,0,0,0,0,0,0,0,0)';
      OUTPUT_LOAD='(1.0,-1.0)';
    'MEB_DQS_L8':
      PIN_NUMBER='(0,0,0,0,DC69,0,0,0,0,0,0,0,0,0,0,0,0,0,0,0,0,0,0,0,0,0,0,0,0,0,0,0,0,0,0,0,0,0,0,0)';
      BIDIRECTIONAL='TRUE';
      INPUT_LOAD='(-0.01,0.01)';
      OUTPUT_LOAD='(1.0,-1.0)';
    'MEB_DQS_H4':
      PIN_NUMBER='(0,0,0,0,BY69,0,0,0,0,0,0,0,0,0,0,0,0,0,0,0,0,0,0,0,0,0,0,0,0,0,0,0,0,0,0,0,0,0,0,0)';
      BIDIRECTIONAL='TRUE';
      INPUT_LOAD='(-0.01,0.01)';
      OUTPUT_LOAD='(1.0,-1.0)';
    'MEB_DATA2':
      PIN_NUMBER='(0,0,0,0,CC71,0,0,0,0,0,0,0,0,0,0,0,0,0,0,0,0,0,0,0,0,0,0,0,0,0,0,0,0,0,0,0,0,0,0,0)';
      BIDIRECTIONAL='TRUE';
      INPUT_LOAD='(-0.01,0.01)';
      OUTPUT_LOAD='(1.0,-1.0)';
    'MEB_CA0':
      PIN_NUMBER='(0,0,0,0,BG69,0,0,0,0,0,0,0,0,0,0,0,0,0,0,0,0,0,0,0,0,0,0,0,0,0,0,0,0,0,0,0,0,0,0,0)';
      OUTPUT_LOAD='(1.0,-1.0)';
    'MEA_DATA21':
      PIN_NUMBER='(0,0,0,0,AB69,0,0,0,0,0,0,0,0,0,0,0,0,0,0,0,0,0,0,0,0,0,0,0,0,0,0,0,0,0,0,0,0,0,0,0)';
      BIDIRECTIONAL='TRUE';
      INPUT_LOAD='(-0.01,0.01)';
      OUTPUT_LOAD='(1.0,-1.0)';
    'MEA_DATA10':
      PIN_NUMBER='(0,0,0,0,M70,0,0,0,0,0,0,0,0,0,0,0,0,0,0,0,0,0,0,0,0,0,0,0,0,0,0,0,0,0,0,0,0,0,0,0)';
      BIDIRECTIONAL='TRUE';
      INPUT_LOAD='(-0.01,0.01)';
      OUTPUT_LOAD='(1.0,-1.0)';
    'MEA_DATA3':
      PIN_NUMBER='(0,0,0,0,G69,0,0,0,0,0,0,0,0,0,0,0,0,0,0,0,0,0,0,0,0,0,0,0,0,0,0,0,0,0,0,0,0,0,0,0)';
      BIDIRECTIONAL='TRUE';
      INPUT_LOAD='(-0.01,0.01)';
      OUTPUT_LOAD='(1.0,-1.0)';
    'MEA_CHECK1':
      PIN_NUMBER='(0,0,0,0,AK69,0,0,0,0,0,0,0,0,0,0,0,0,0,0,0,0,0,0,0,0,0,0,0,0,0,0,0,0,0,0,0,0,0,0,0)';
      BIDIRECTIONAL='TRUE';
      INPUT_LOAD='(-0.01,0.01)';
      OUTPUT_LOAD='(1.0,-1.0)';
    'MEA_CA1':
      PIN_NUMBER='(0,0,0,0,AY70,0,0,0,0,0,0,0,0,0,0,0,0,0,0,0,0,0,0,0,0,0,0,0,0,0,0,0,0,0,0,0,0,0,0,0)';
      OUTPUT_LOAD='(1.0,-1.0)';
    'MEB_DQS_L9':
      PIN_NUMBER='(0,0,0,0,BW71,0,0,0,0,0,0,0,0,0,0,0,0,0,0,0,0,0,0,0,0,0,0,0,0,0,0,0,0,0,0,0,0,0,0,0)';
      BIDIRECTIONAL='TRUE';
      INPUT_LOAD='(-0.01,0.01)';
      OUTPUT_LOAD='(1.0,-1.0)';
    'MEB_DQS_H5':
      PIN_NUMBER='(0,0,0,0,CF69,0,0,0,0,0,0,0,0,0,0,0,0,0,0,0,0,0,0,0,0,0,0,0,0,0,0,0,0,0,0,0,0,0,0,0)';
      BIDIRECTIONAL='TRUE';
      INPUT_LOAD='(-0.01,0.01)';
      OUTPUT_LOAD='(1.0,-1.0)';
    'MEB_DATA3':
      PIN_NUMBER='(0,0,0,0,CD69,0,0,0,0,0,0,0,0,0,0,0,0,0,0,0,0,0,0,0,0,0,0,0,0,0,0,0,0,0,0,0,0,0,0,0)';
      BIDIRECTIONAL='TRUE';
      INPUT_LOAD='(-0.01,0.01)';
      OUTPUT_LOAD='(1.0,-1.0)';
    'MEB_CA1':
      PIN_NUMBER='(0,0,0,0,BH69,0,0,0,0,0,0,0,0,0,0,0,0,0,0,0,0,0,0,0,0,0,0,0,0,0,0,0,0,0,0,0,0,0,0,0)';
      OUTPUT_LOAD='(1.0,-1.0)';
    'MEA_DATA22':
      PIN_NUMBER='(0,0,0,0,AB70,0,0,0,0,0,0,0,0,0,0,0,0,0,0,0,0,0,0,0,0,0,0,0,0,0,0,0,0,0,0,0,0,0,0,0)';
      BIDIRECTIONAL='TRUE';
      INPUT_LOAD='(-0.01,0.01)';
      OUTPUT_LOAD='(1.0,-1.0)';
    'MEA_DATA11':
      PIN_NUMBER='(0,0,0,0,N69,0,0,0,0,0,0,0,0,0,0,0,0,0,0,0,0,0,0,0,0,0,0,0,0,0,0,0,0,0,0,0,0,0,0,0)';
      BIDIRECTIONAL='TRUE';
      INPUT_LOAD='(-0.01,0.01)';
      OUTPUT_LOAD='(1.0,-1.0)';
    'MEA_DATA4':
      PIN_NUMBER='(0,0,0,0,J71,0,0,0,0,0,0,0,0,0,0,0,0,0,0,0,0,0,0,0,0,0,0,0,0,0,0,0,0,0,0,0,0,0,0,0)';
      BIDIRECTIONAL='TRUE';
      INPUT_LOAD='(-0.01,0.01)';
      OUTPUT_LOAD='(1.0,-1.0)';
    'MEA_CHECK2':
      PIN_NUMBER='(0,0,0,0,AK70,0,0,0,0,0,0,0,0,0,0,0,0,0,0,0,0,0,0,0,0,0,0,0,0,0,0,0,0,0,0,0,0,0,0,0)';
      BIDIRECTIONAL='TRUE';
      INPUT_LOAD='(-0.01,0.01)';
      OUTPUT_LOAD='(1.0,-1.0)';
    'MEA_CA2':
      PIN_NUMBER='(0,0,0,0,AY69,0,0,0,0,0,0,0,0,0,0,0,0,0,0,0,0,0,0,0,0,0,0,0,0,0,0,0,0,0,0,0,0,0,0,0)';
      OUTPUT_LOAD='(1.0,-1.0)';
    'MEB_DQS_H6':
      PIN_NUMBER='(0,0,0,0,CM69,0,0,0,0,0,0,0,0,0,0,0,0,0,0,0,0,0,0,0,0,0,0,0,0,0,0,0,0,0,0,0,0,0,0,0)';
      BIDIRECTIONAL='TRUE';
      INPUT_LOAD='(-0.01,0.01)';
      OUTPUT_LOAD='(1.0,-1.0)';
    'MEB_DATA4':
      PIN_NUMBER='(0,0,0,0,CF70,0,0,0,0,0,0,0,0,0,0,0,0,0,0,0,0,0,0,0,0,0,0,0,0,0,0,0,0,0,0,0,0,0,0,0)';
      BIDIRECTIONAL='TRUE';
      INPUT_LOAD='(-0.01,0.01)';
      OUTPUT_LOAD='(1.0,-1.0)';
    'MEB_CA2':
      PIN_NUMBER='(0,0,0,0,BH70,0,0,0,0,0,0,0,0,0,0,0,0,0,0,0,0,0,0,0,0,0,0,0,0,0,0,0,0,0,0,0,0,0,0,0)';
      OUTPUT_LOAD='(1.0,-1.0)';
    'MEA_DATA23':
      PIN_NUMBER='(0,0,0,0,AC69,0,0,0,0,0,0,0,0,0,0,0,0,0,0,0,0,0,0,0,0,0,0,0,0,0,0,0,0,0,0,0,0,0,0,0)';
      BIDIRECTIONAL='TRUE';
      INPUT_LOAD='(-0.01,0.01)';
      OUTPUT_LOAD='(1.0,-1.0)';
    'MEA_DATA12':
      PIN_NUMBER='(0,0,0,0,R71,0,0,0,0,0,0,0,0,0,0,0,0,0,0,0,0,0,0,0,0,0,0,0,0,0,0,0,0,0,0,0,0,0,0,0)';
      BIDIRECTIONAL='TRUE';
      INPUT_LOAD='(-0.01,0.01)';
      OUTPUT_LOAD='(1.0,-1.0)';
    'MEA_DATA5':
      PIN_NUMBER='(0,0,0,0,K69,0,0,0,0,0,0,0,0,0,0,0,0,0,0,0,0,0,0,0,0,0,0,0,0,0,0,0,0,0,0,0,0,0,0,0)';
      BIDIRECTIONAL='TRUE';
      INPUT_LOAD='(-0.01,0.01)';
      OUTPUT_LOAD='(1.0,-1.0)';
    'MEA_CHECK3':
      PIN_NUMBER='(0,0,0,0,AL69,0,0,0,0,0,0,0,0,0,0,0,0,0,0,0,0,0,0,0,0,0,0,0,0,0,0,0,0,0,0,0,0,0,0,0)';
      BIDIRECTIONAL='TRUE';
      INPUT_LOAD='(-0.01,0.01)';
      OUTPUT_LOAD='(1.0,-1.0)';
    'MEA_CA3':
      PIN_NUMBER='(0,0,0,0,BA69,0,0,0,0,0,0,0,0,0,0,0,0,0,0,0,0,0,0,0,0,0,0,0,0,0,0,0,0,0,0,0,0,0,0,0)';
      OUTPUT_LOAD='(1.0,-1.0)';
    'MEB_DQS_H7':
      PIN_NUMBER='(0,0,0,0,CV69,0,0,0,0,0,0,0,0,0,0,0,0,0,0,0,0,0,0,0,0,0,0,0,0,0,0,0,0,0,0,0,0,0,0,0)';
      BIDIRECTIONAL='TRUE';
      INPUT_LOAD='(-0.01,0.01)';
      OUTPUT_LOAD='(1.0,-1.0)';
    'MEB_DATA5':
      PIN_NUMBER='(0,0,0,0,CG69,0,0,0,0,0,0,0,0,0,0,0,0,0,0,0,0,0,0,0,0,0,0,0,0,0,0,0,0,0,0,0,0,0,0,0)';
      BIDIRECTIONAL='TRUE';
      INPUT_LOAD='(-0.01,0.01)';
      OUTPUT_LOAD='(1.0,-1.0)';
    'MEB_CA3':
      PIN_NUMBER='(0,0,0,0,BJ71,0,0,0,0,0,0,0,0,0,0,0,0,0,0,0,0,0,0,0,0,0,0,0,0,0,0,0,0,0,0,0,0,0,0,0)';
      OUTPUT_LOAD='(1.0,-1.0)';
    'MEB1_CS_L0':
      PIN_NUMBER='(0,0,0,0,BL69,0,0,0,0,0,0,0,0,0,0,0,0,0,0,0,0,0,0,0,0,0,0,0,0,0,0,0,0,0,0,0,0,0,0,0)';
      OUTPUT_LOAD='(1.0,-1.0)';
    'MEB0_CS_L0':
      PIN_NUMBER='(0,0,0,0,BM69,0,0,0,0,0,0,0,0,0,0,0,0,0,0,0,0,0,0,0,0,0,0,0,0,0,0,0,0,0,0,0,0,0,0,0)';
      OUTPUT_LOAD='(1.0,-1.0)';
    'MEA_DQS_L0':
      PIN_NUMBER='(0,0,0,0,H70,0,0,0,0,0,0,0,0,0,0,0,0,0,0,0,0,0,0,0,0,0,0,0,0,0,0,0,0,0,0,0,0,0,0,0)';
      BIDIRECTIONAL='TRUE';
      INPUT_LOAD='(-0.01,0.01)';
      OUTPUT_LOAD='(1.0,-1.0)';
    'MEA_DATA24':
      PIN_NUMBER='(0,0,0,0,AC71,0,0,0,0,0,0,0,0,0,0,0,0,0,0,0,0,0,0,0,0,0,0,0,0,0,0,0,0,0,0,0,0,0,0,0)';
      BIDIRECTIONAL='TRUE';
      INPUT_LOAD='(-0.01,0.01)';
      OUTPUT_LOAD='(1.0,-1.0)';
    'MEA_DATA13':
      PIN_NUMBER='(0,0,0,0,T69,0,0,0,0,0,0,0,0,0,0,0,0,0,0,0,0,0,0,0,0,0,0,0,0,0,0,0,0,0,0,0,0,0,0,0)';
      BIDIRECTIONAL='TRUE';
      INPUT_LOAD='(-0.01,0.01)';
      OUTPUT_LOAD='(1.0,-1.0)';
    'MEA_DATA6':
      PIN_NUMBER='(0,0,0,0,K70,0,0,0,0,0,0,0,0,0,0,0,0,0,0,0,0,0,0,0,0,0,0,0,0,0,0,0,0,0,0,0,0,0,0,0)';
      BIDIRECTIONAL='TRUE';
      INPUT_LOAD='(-0.01,0.01)';
      OUTPUT_LOAD='(1.0,-1.0)';
    'MEA_CHECK4':
      PIN_NUMBER='(0,0,0,0,AN71,0,0,0,0,0,0,0,0,0,0,0,0,0,0,0,0,0,0,0,0,0,0,0,0,0,0,0,0,0,0,0,0,0,0,0)';
      BIDIRECTIONAL='TRUE';
      INPUT_LOAD='(-0.01,0.01)';
      OUTPUT_LOAD='(1.0,-1.0)';
    'MEA_CA4':
      PIN_NUMBER='(0,0,0,0,BA71,0,0,0,0,0,0,0,0,0,0,0,0,0,0,0,0,0,0,0,0,0,0,0,0,0,0,0,0,0,0,0,0,0,0,0)';
      OUTPUT_LOAD='(1.0,-1.0)';
    'MEB_DQS_H8':
      PIN_NUMBER='(0,0,0,0,DD69,0,0,0,0,0,0,0,0,0,0,0,0,0,0,0,0,0,0,0,0,0,0,0,0,0,0,0,0,0,0,0,0,0,0,0)';
      BIDIRECTIONAL='TRUE';
      INPUT_LOAD='(-0.01,0.01)';
      OUTPUT_LOAD='(1.0,-1.0)';
    'MEB_DATA30':
      PIN_NUMBER='(0,0,0,0,DE71,0,0,0,0,0,0,0,0,0,0,0,0,0,0,0,0,0,0,0,0,0,0,0,0,0,0,0,0,0,0,0,0,0,0,0)';
      BIDIRECTIONAL='TRUE';
      INPUT_LOAD='(-0.01,0.01)';
      OUTPUT_LOAD='(1.0,-1.0)';
    'MEB_DATA6':
      PIN_NUMBER='(0,0,0,0,CG71,0,0,0,0,0,0,0,0,0,0,0,0,0,0,0,0,0,0,0,0,0,0,0,0,0,0,0,0,0,0,0,0,0,0,0)';
      BIDIRECTIONAL='TRUE';
      INPUT_LOAD='(-0.01,0.01)';
      OUTPUT_LOAD='(1.0,-1.0)';
    'MEB_CA4':
      PIN_NUMBER='(0,0,0,0,BJ69,0,0,0,0,0,0,0,0,0,0,0,0,0,0,0,0,0,0,0,0,0,0,0,0,0,0,0,0,0,0,0,0,0,0,0)';
      OUTPUT_LOAD='(1.0,-1.0)';
    'MEB1_CS_L1':
      PIN_NUMBER='(0,0,0,0,BM70,0,0,0,0,0,0,0,0,0,0,0,0,0,0,0,0,0,0,0,0,0,0,0,0,0,0,0,0,0,0,0,0,0,0,0)';
      OUTPUT_LOAD='(1.0,-1.0)';
    'MEB0_CS_L1':
      PIN_NUMBER='(0,0,0,0,BN71,0,0,0,0,0,0,0,0,0,0,0,0,0,0,0,0,0,0,0,0,0,0,0,0,0,0,0,0,0,0,0,0,0,0,0)';
      OUTPUT_LOAD='(1.0,-1.0)';
    'MEA_DQS_L1':
      PIN_NUMBER='(0,0,0,0,P70,0,0,0,0,0,0,0,0,0,0,0,0,0,0,0,0,0,0,0,0,0,0,0,0,0,0,0,0,0,0,0,0,0,0,0)';
      BIDIRECTIONAL='TRUE';
      INPUT_LOAD='(-0.01,0.01)';
      OUTPUT_LOAD='(1.0,-1.0)';
    'MEA_DATA25':
      PIN_NUMBER='(0,0,0,0,AD69,0,0,0,0,0,0,0,0,0,0,0,0,0,0,0,0,0,0,0,0,0,0,0,0,0,0,0,0,0,0,0,0,0,0,0)';
      BIDIRECTIONAL='TRUE';
      INPUT_LOAD='(-0.01,0.01)';
      OUTPUT_LOAD='(1.0,-1.0)';
    'MEA_DATA14':
      PIN_NUMBER='(0,0,0,0,T70,0,0,0,0,0,0,0,0,0,0,0,0,0,0,0,0,0,0,0,0,0,0,0,0,0,0,0,0,0,0,0,0,0,0,0)';
      BIDIRECTIONAL='TRUE';
      INPUT_LOAD='(-0.01,0.01)';
      OUTPUT_LOAD='(1.0,-1.0)';
    'MEA_DATA7':
      PIN_NUMBER='(0,0,0,0,L69,0,0,0,0,0,0,0,0,0,0,0,0,0,0,0,0,0,0,0,0,0,0,0,0,0,0,0,0,0,0,0,0,0,0,0)';
      BIDIRECTIONAL='TRUE';
      INPUT_LOAD='(-0.01,0.01)';
      OUTPUT_LOAD='(1.0,-1.0)';
    'MEA_CHECK5':
      PIN_NUMBER='(0,0,0,0,AP69,0,0,0,0,0,0,0,0,0,0,0,0,0,0,0,0,0,0,0,0,0,0,0,0,0,0,0,0,0,0,0,0,0,0,0)';
      BIDIRECTIONAL='TRUE';
      INPUT_LOAD='(-0.01,0.01)';
      OUTPUT_LOAD='(1.0,-1.0)';
    'MEA_CA5':
      PIN_NUMBER='(0,0,0,0,BB70,0,0,0,0,0,0,0,0,0,0,0,0,0,0,0,0,0,0,0,0,0,0,0,0,0,0,0,0,0,0,0,0,0,0,0)';
      OUTPUT_LOAD='(1.0,-1.0)';
    'MEB_DATA31':
      PIN_NUMBER='(0,0,0,0,DF69,0,0,0,0,0,0,0,0,0,0,0,0,0,0,0,0,0,0,0,0,0,0,0,0,0,0,0,0,0,0,0,0,0,0,0)';
      BIDIRECTIONAL='TRUE';
      INPUT_LOAD='(-0.01,0.01)';
      OUTPUT_LOAD='(1.0,-1.0)';
    'MEB_DATA20':
      PIN_NUMBER='(0,0,0,0,CV70,0,0,0,0,0,0,0,0,0,0,0,0,0,0,0,0,0,0,0,0,0,0,0,0,0,0,0,0,0,0,0,0,0,0,0)';
      BIDIRECTIONAL='TRUE';
      INPUT_LOAD='(-0.01,0.01)';
      OUTPUT_LOAD='(1.0,-1.0)';
    'MEB_DATA7':
      PIN_NUMBER='(0,0,0,0,CH69,0,0,0,0,0,0,0,0,0,0,0,0,0,0,0,0,0,0,0,0,0,0,0,0,0,0,0,0,0,0,0,0,0,0,0)';
      BIDIRECTIONAL='TRUE';
      INPUT_LOAD='(-0.01,0.01)';
      OUTPUT_LOAD='(1.0,-1.0)';
    'MEB_CHECK0':
      PIN_NUMBER='(0,0,0,0,BY70,0,0,0,0,0,0,0,0,0,0,0,0,0,0,0,0,0,0,0,0,0,0,0,0,0,0,0,0,0,0,0,0,0,0,0)';
      BIDIRECTIONAL='TRUE';
      INPUT_LOAD='(-0.01,0.01)';
      OUTPUT_LOAD='(1.0,-1.0)';
    'MEB_CA5':
      PIN_NUMBER='(0,0,0,0,BK69,0,0,0,0,0,0,0,0,0,0,0,0,0,0,0,0,0,0,0,0,0,0,0,0,0,0,0,0,0,0,0,0,0,0,0)';
      OUTPUT_LOAD='(1.0,-1.0)';
    'MEA_DQS_L2':
      PIN_NUMBER='(0,0,0,0,Y70,0,0,0,0,0,0,0,0,0,0,0,0,0,0,0,0,0,0,0,0,0,0,0,0,0,0,0,0,0,0,0,0,0,0,0)';
      BIDIRECTIONAL='TRUE';
      INPUT_LOAD='(-0.01,0.01)';
      OUTPUT_LOAD='(1.0,-1.0)';
    'MEA_DATA26':
      PIN_NUMBER='(0,0,0,0,AD70,0,0,0,0,0,0,0,0,0,0,0,0,0,0,0,0,0,0,0,0,0,0,0,0,0,0,0,0,0,0,0,0,0,0,0)';
      BIDIRECTIONAL='TRUE';
      INPUT_LOAD='(-0.01,0.01)';
      OUTPUT_LOAD='(1.0,-1.0)';
    'MEA_DATA15':
      PIN_NUMBER='(0,0,0,0,U69,0,0,0,0,0,0,0,0,0,0,0,0,0,0,0,0,0,0,0,0,0,0,0,0,0,0,0,0,0,0,0,0,0,0,0)';
      BIDIRECTIONAL='TRUE';
      INPUT_LOAD='(-0.01,0.01)';
      OUTPUT_LOAD='(1.0,-1.0)';
    'MEA_DATA8':
      PIN_NUMBER='(0,0,0,0,L71,0,0,0,0,0,0,0,0,0,0,0,0,0,0,0,0,0,0,0,0,0,0,0,0,0,0,0,0,0,0,0,0,0,0,0)';
      BIDIRECTIONAL='TRUE';
      INPUT_LOAD='(-0.01,0.01)';
      OUTPUT_LOAD='(1.0,-1.0)';
    'MEA_CHECK6':
      PIN_NUMBER='(0,0,0,0,AP70,0,0,0,0,0,0,0,0,0,0,0,0,0,0,0,0,0,0,0,0,0,0,0,0,0,0,0,0,0,0,0,0,0,0,0)';
      BIDIRECTIONAL='TRUE';
      INPUT_LOAD='(-0.01,0.01)';
      OUTPUT_LOAD='(1.0,-1.0)';
    'MEA_CA6':
      PIN_NUMBER='(0,0,0,0,BB69,0,0,0,0,0,0,0,0,0,0,0,0,0,0,0,0,0,0,0,0,0,0,0,0,0,0,0,0,0,0,0,0,0,0,0)';
      OUTPUT_LOAD='(1.0,-1.0)';
    'MEB_DATA21':
      PIN_NUMBER='(0,0,0,0,CW69,0,0,0,0,0,0,0,0,0,0,0,0,0,0,0,0,0,0,0,0,0,0,0,0,0,0,0,0,0,0,0,0,0,0,0)';
      BIDIRECTIONAL='TRUE';
      INPUT_LOAD='(-0.01,0.01)';
      OUTPUT_LOAD='(1.0,-1.0)';
    'MEB_DATA10':
      PIN_NUMBER='(0,0,0,0,CJ71,0,0,0,0,0,0,0,0,0,0,0,0,0,0,0,0,0,0,0,0,0,0,0,0,0,0,0,0,0,0,0,0,0,0,0)';
      BIDIRECTIONAL='TRUE';
      INPUT_LOAD='(-0.01,0.01)';
      OUTPUT_LOAD='(1.0,-1.0)';
    'MEB_DATA8':
      PIN_NUMBER='(0,0,0,0,CH70,0,0,0,0,0,0,0,0,0,0,0,0,0,0,0,0,0,0,0,0,0,0,0,0,0,0,0,0,0,0,0,0,0,0,0)';
      BIDIRECTIONAL='TRUE';
      INPUT_LOAD='(-0.01,0.01)';
      OUTPUT_LOAD='(1.0,-1.0)';
    'MEB_CHECK1':
      PIN_NUMBER='(0,0,0,0,CA69,0,0,0,0,0,0,0,0,0,0,0,0,0,0,0,0,0,0,0,0,0,0,0,0,0,0,0,0,0,0,0,0,0,0,0)';
      BIDIRECTIONAL='TRUE';
      INPUT_LOAD='(-0.01,0.01)';
      OUTPUT_LOAD='(1.0,-1.0)';
    'MEB_CA6':
      PIN_NUMBER='(0,0,0,0,BK70,0,0,0,0,0,0,0,0,0,0,0,0,0,0,0,0,0,0,0,0,0,0,0,0,0,0,0,0,0,0,0,0,0,0,0)';
      OUTPUT_LOAD='(1.0,-1.0)';
    'MEA_DQS_L3':
      PIN_NUMBER='(0,0,0,0,AF70,0,0,0,0,0,0,0,0,0,0,0,0,0,0,0,0,0,0,0,0,0,0,0,0,0,0,0,0,0,0,0,0,0,0,0)';
      BIDIRECTIONAL='TRUE';
      INPUT_LOAD='(-0.01,0.01)';
      OUTPUT_LOAD='(1.0,-1.0)';
    'MEA_DATA27':
      PIN_NUMBER='(0,0,0,0,AE69,0,0,0,0,0,0,0,0,0,0,0,0,0,0,0,0,0,0,0,0,0,0,0,0,0,0,0,0,0,0,0,0,0,0,0)';
      BIDIRECTIONAL='TRUE';
      INPUT_LOAD='(-0.01,0.01)';
      OUTPUT_LOAD='(1.0,-1.0)';
    'MEA_DATA16':
      PIN_NUMBER='(0,0,0,0,U71,0,0,0,0,0,0,0,0,0,0,0,0,0,0,0,0,0,0,0,0,0,0,0,0,0,0,0,0,0,0,0,0,0,0,0)';
      BIDIRECTIONAL='TRUE';
      INPUT_LOAD='(-0.01,0.01)';
      OUTPUT_LOAD='(1.0,-1.0)';
    'MEA_DATA9':
      PIN_NUMBER='(0,0,0,0,M69,0,0,0,0,0,0,0,0,0,0,0,0,0,0,0,0,0,0,0,0,0,0,0,0,0,0,0,0,0,0,0,0,0,0,0)';
      BIDIRECTIONAL='TRUE';
      INPUT_LOAD='(-0.01,0.01)';
      OUTPUT_LOAD='(1.0,-1.0)';
    'MEA_CHECK7':
      PIN_NUMBER='(0,0,0,0,AR69,0,0,0,0,0,0,0,0,0,0,0,0,0,0,0,0,0,0,0,0,0,0,0,0,0,0,0,0,0,0,0,0,0,0,0)';
      BIDIRECTIONAL='TRUE';
      INPUT_LOAD='(-0.01,0.01)';
      OUTPUT_LOAD='(1.0,-1.0)';
    'MEA1_RSP_L':
      PIN_NUMBER='(0,0,0,0,BP69,0,0,0,0,0,0,0,0,0,0,0,0,0,0,0,0,0,0,0,0,0,0,0,0,0,0,0,0,0,0,0,0,0,0,0)';
      INPUT_LOAD='(-0.01,0.01)';
    'MEA0_RSP_L':
      PIN_NUMBER='(0,0,0,0,BN69,0,0,0,0,0,0,0,0,0,0,0,0,0,0,0,0,0,0,0,0,0,0,0,0,0,0,0,0,0,0,0,0,0,0,0)';
      INPUT_LOAD='(-0.01,0.01)';
    'MEB_DATA22':
      PIN_NUMBER='(0,0,0,0,CW71,0,0,0,0,0,0,0,0,0,0,0,0,0,0,0,0,0,0,0,0,0,0,0,0,0,0,0,0,0,0,0,0,0,0,0)';
      BIDIRECTIONAL='TRUE';
      INPUT_LOAD='(-0.01,0.01)';
      OUTPUT_LOAD='(1.0,-1.0)';
    'MEB_DATA11':
      PIN_NUMBER='(0,0,0,0,CK69,0,0,0,0,0,0,0,0,0,0,0,0,0,0,0,0,0,0,0,0,0,0,0,0,0,0,0,0,0,0,0,0,0,0,0)';
      BIDIRECTIONAL='TRUE';
      INPUT_LOAD='(-0.01,0.01)';
      OUTPUT_LOAD='(1.0,-1.0)';
    'MEB_DATA9':
      PIN_NUMBER='(0,0,0,0,CJ69,0,0,0,0,0,0,0,0,0,0,0,0,0,0,0,0,0,0,0,0,0,0,0,0,0,0,0,0,0,0,0,0,0,0,0)';
      BIDIRECTIONAL='TRUE';
      INPUT_LOAD='(-0.01,0.01)';
      OUTPUT_LOAD='(1.0,-1.0)';
    'MEB_CHECK2':
      PIN_NUMBER='(0,0,0,0,CA71,0,0,0,0,0,0,0,0,0,0,0,0,0,0,0,0,0,0,0,0,0,0,0,0,0,0,0,0,0,0,0,0,0,0,0)';
      BIDIRECTIONAL='TRUE';
      INPUT_LOAD='(-0.01,0.01)';
      OUTPUT_LOAD='(1.0,-1.0)';
    'MEA_DQS_L4':
      PIN_NUMBER='(0,0,0,0,AM70,0,0,0,0,0,0,0,0,0,0,0,0,0,0,0,0,0,0,0,0,0,0,0,0,0,0,0,0,0,0,0,0,0,0,0)';
      BIDIRECTIONAL='TRUE';
      INPUT_LOAD='(-0.01,0.01)';
      OUTPUT_LOAD='(1.0,-1.0)';
    'MEA_DQS_H0':
      PIN_NUMBER='(0,0,0,0,G71,0,0,0,0,0,0,0,0,0,0,0,0,0,0,0,0,0,0,0,0,0,0,0,0,0,0,0,0,0,0,0,0,0,0,0)';
      BIDIRECTIONAL='TRUE';
      INPUT_LOAD='(-0.01,0.01)';
      OUTPUT_LOAD='(1.0,-1.0)';
    'MEA_DATA28':
      PIN_NUMBER='(0,0,0,0,AG71,0,0,0,0,0,0,0,0,0,0,0,0,0,0,0,0,0,0,0,0,0,0,0,0,0,0,0,0,0,0,0,0,0,0,0)';
      BIDIRECTIONAL='TRUE';
      INPUT_LOAD='(-0.01,0.01)';
      OUTPUT_LOAD='(1.0,-1.0)';
    'MEA_DATA17':
      PIN_NUMBER='(0,0,0,0,V69,0,0,0,0,0,0,0,0,0,0,0,0,0,0,0,0,0,0,0,0,0,0,0,0,0,0,0,0,0,0,0,0,0,0,0)';
      BIDIRECTIONAL='TRUE';
      INPUT_LOAD='(-0.01,0.01)';
      OUTPUT_LOAD='(1.0,-1.0)';
    'MEB_DATA23':
      PIN_NUMBER='(0,0,0,0,CY69,0,0,0,0,0,0,0,0,0,0,0,0,0,0,0,0,0,0,0,0,0,0,0,0,0,0,0,0,0,0,0,0,0,0,0)';
      BIDIRECTIONAL='TRUE';
      INPUT_LOAD='(-0.01,0.01)';
      OUTPUT_LOAD='(1.0,-1.0)';
    'MEB_DATA12':
      PIN_NUMBER='(0,0,0,0,CM70,0,0,0,0,0,0,0,0,0,0,0,0,0,0,0,0,0,0,0,0,0,0,0,0,0,0,0,0,0,0,0,0,0,0,0)';
      BIDIRECTIONAL='TRUE';
      INPUT_LOAD='(-0.01,0.01)';
      OUTPUT_LOAD='(1.0,-1.0)';
    'MEB_CHECK3':
      PIN_NUMBER='(0,0,0,0,CB69,0,0,0,0,0,0,0,0,0,0,0,0,0,0,0,0,0,0,0,0,0,0,0,0,0,0,0,0,0,0,0,0,0,0,0)';
      BIDIRECTIONAL='TRUE';
      INPUT_LOAD='(-0.01,0.01)';
      OUTPUT_LOAD='(1.0,-1.0)';
    'MEA_DQS_L5':
      PIN_NUMBER='(0,0,0,0,H69,0,0,0,0,0,0,0,0,0,0,0,0,0,0,0,0,0,0,0,0,0,0,0,0,0,0,0,0,0,0,0,0,0,0,0)';
      BIDIRECTIONAL='TRUE';
      INPUT_LOAD='(-0.01,0.01)';
      OUTPUT_LOAD='(1.0,-1.0)';
    'MEA_DQS_H1':
      PIN_NUMBER='(0,0,0,0,N71,0,0,0,0,0,0,0,0,0,0,0,0,0,0,0,0,0,0,0,0,0,0,0,0,0,0,0,0,0,0,0,0,0,0,0)';
      BIDIRECTIONAL='TRUE';
      INPUT_LOAD='(-0.01,0.01)';
      OUTPUT_LOAD='(1.0,-1.0)';
    'MEA_DATA29':
      PIN_NUMBER='(0,0,0,0,AH69,0,0,0,0,0,0,0,0,0,0,0,0,0,0,0,0,0,0,0,0,0,0,0,0,0,0,0,0,0,0,0,0,0,0,0)';
      BIDIRECTIONAL='TRUE';
      INPUT_LOAD='(-0.01,0.01)';
      OUTPUT_LOAD='(1.0,-1.0)';
    'MEA_DATA18':
      PIN_NUMBER='(0,0,0,0,V70,0,0,0,0,0,0,0,0,0,0,0,0,0,0,0,0,0,0,0,0,0,0,0,0,0,0,0,0,0,0,0,0,0,0,0)';
      BIDIRECTIONAL='TRUE';
      INPUT_LOAD='(-0.01,0.01)';
      OUTPUT_LOAD='(1.0,-1.0)';
    'MEB_DQS_L0':
      PIN_NUMBER='(0,0,0,0,CE71,0,0,0,0,0,0,0,0,0,0,0,0,0,0,0,0,0,0,0,0,0,0,0,0,0,0,0,0,0,0,0,0,0,0,0)';
      BIDIRECTIONAL='TRUE';
      INPUT_LOAD='(-0.01,0.01)';
      OUTPUT_LOAD='(1.0,-1.0)';
    'MEB_DATA24':
      PIN_NUMBER='(0,0,0,0,CY70,0,0,0,0,0,0,0,0,0,0,0,0,0,0,0,0,0,0,0,0,0,0,0,0,0,0,0,0,0,0,0,0,0,0,0)';
      BIDIRECTIONAL='TRUE';
      INPUT_LOAD='(-0.01,0.01)';
      OUTPUT_LOAD='(1.0,-1.0)';
    'MEB_DATA13':
      PIN_NUMBER='(0,0,0,0,CN69,0,0,0,0,0,0,0,0,0,0,0,0,0,0,0,0,0,0,0,0,0,0,0,0,0,0,0,0,0,0,0,0,0,0,0)';
      BIDIRECTIONAL='TRUE';
      INPUT_LOAD='(-0.01,0.01)';
      OUTPUT_LOAD='(1.0,-1.0)';
    'MEB_CHECK4':
      PIN_NUMBER='(0,0,0,0,BT70,0,0,0,0,0,0,0,0,0,0,0,0,0,0,0,0,0,0,0,0,0,0,0,0,0,0,0,0,0,0,0,0,0,0,0)';
      BIDIRECTIONAL='TRUE';
      INPUT_LOAD='(-0.01,0.01)';
      OUTPUT_LOAD='(1.0,-1.0)';
    'MEA_DQS_L6':
      PIN_NUMBER='(0,0,0,0,P69,0,0,0,0,0,0,0,0,0,0,0,0,0,0,0,0,0,0,0,0,0,0,0,0,0,0,0,0,0,0,0,0,0,0,0)';
      BIDIRECTIONAL='TRUE';
      INPUT_LOAD='(-0.01,0.01)';
      OUTPUT_LOAD='(1.0,-1.0)';
    'MEA_DQS_H2':
      PIN_NUMBER='(0,0,0,0,W71,0,0,0,0,0,0,0,0,0,0,0,0,0,0,0,0,0,0,0,0,0,0,0,0,0,0,0,0,0,0,0,0,0,0,0)';
      BIDIRECTIONAL='TRUE';
      INPUT_LOAD='(-0.01,0.01)';
      OUTPUT_LOAD='(1.0,-1.0)';
    'MEA_DATA19':
      PIN_NUMBER='(0,0,0,0,W69,0,0,0,0,0,0,0,0,0,0,0,0,0,0,0,0,0,0,0,0,0,0,0,0,0,0,0,0,0,0,0,0,0,0,0)';
      BIDIRECTIONAL='TRUE';
      INPUT_LOAD='(-0.01,0.01)';
      OUTPUT_LOAD='(1.0,-1.0)';
    'MEB_DQS_L1':
      PIN_NUMBER='(0,0,0,0,CL71,0,0,0,0,0,0,0,0,0,0,0,0,0,0,0,0,0,0,0,0,0,0,0,0,0,0,0,0,0,0,0,0,0,0,0)';
      BIDIRECTIONAL='TRUE';
      INPUT_LOAD='(-0.01,0.01)';
      OUTPUT_LOAD='(1.0,-1.0)';
    'MEB_DATA25':
      PIN_NUMBER='(0,0,0,0,DA69,0,0,0,0,0,0,0,0,0,0,0,0,0,0,0,0,0,0,0,0,0,0,0,0,0,0,0,0,0,0,0,0,0,0,0)';
      BIDIRECTIONAL='TRUE';
      INPUT_LOAD='(-0.01,0.01)';
      OUTPUT_LOAD='(1.0,-1.0)';
    'MEB_DATA14':
      PIN_NUMBER='(0,0,0,0,CN71,0,0,0,0,0,0,0,0,0,0,0,0,0,0,0,0,0,0,0,0,0,0,0,0,0,0,0,0,0,0,0,0,0,0,0)';
      BIDIRECTIONAL='TRUE';
      INPUT_LOAD='(-0.01,0.01)';
      OUTPUT_LOAD='(1.0,-1.0)';
    'MEB_CHECK5':
      PIN_NUMBER='(0,0,0,0,BU69,0,0,0,0,0,0,0,0,0,0,0,0,0,0,0,0,0,0,0,0,0,0,0,0,0,0,0,0,0,0,0,0,0,0,0)';
      BIDIRECTIONAL='TRUE';
      INPUT_LOAD='(-0.01,0.01)';
      OUTPUT_LOAD='(1.0,-1.0)';
    'MEA_DQS_L7':
      PIN_NUMBER='(0,0,0,0,Y69,0,0,0,0,0,0,0,0,0,0,0,0,0,0,0,0,0,0,0,0,0,0,0,0,0,0,0,0,0,0,0,0,0,0,0)';
      BIDIRECTIONAL='TRUE';
      INPUT_LOAD='(-0.01,0.01)';
      OUTPUT_LOAD='(1.0,-1.0)';
    'MEA_DQS_H3':
      PIN_NUMBER='(0,0,0,0,AE71,0,0,0,0,0,0,0,0,0,0,0,0,0,0,0,0,0,0,0,0,0,0,0,0,0,0,0,0,0,0,0,0,0,0,0)';
      BIDIRECTIONAL='TRUE';
      INPUT_LOAD='(-0.01,0.01)';
      OUTPUT_LOAD='(1.0,-1.0)';
    'MEA_PAR':
      PIN_NUMBER='(0,0,0,0,BC69,0,0,0,0,0,0,0,0,0,0,0,0,0,0,0,0,0,0,0,0,0,0,0,0,0,0,0,0,0,0,0,0,0,0,0)';
      OUTPUT_LOAD='(1.0,-1.0)';
    'MEB_PAR':
      PIN_NUMBER='(0,0,0,0,BL71,0,0,0,0,0,0,0,0,0,0,0,0,0,0,0,0,0,0,0,0,0,0,0,0,0,0,0,0,0,0,0,0,0,0,0)';
      OUTPUT_LOAD='(1.0,-1.0)';
    'MEB_DQS_H9':
      PIN_NUMBER='(0,0,0,0,BV70,0,0,0,0,0,0,0,0,0,0,0,0,0,0,0,0,0,0,0,0,0,0,0,0,0,0,0,0,0,0,0,0,0,0,0)';
      BIDIRECTIONAL='TRUE';
      INPUT_LOAD='(-0.01,0.01)';
      OUTPUT_LOAD='(1.0,-1.0)';
    'ME0_CLK_H':
      PIN_NUMBER='(0,0,0,0,BC71,0,0,0,0,0,0,0,0,0,0,0,0,0,0,0,0,0,0,0,0,0,0,0,0,0,0,0,0,0,0,0,0,0,0,0)';
      OUTPUT_LOAD='(1.0,-1.0)';
    'ME0_CLK_L':
      PIN_NUMBER='(0,0,0,0,BD70,0,0,0,0,0,0,0,0,0,0,0,0,0,0,0,0,0,0,0,0,0,0,0,0,0,0,0,0,0,0,0,0,0,0,0)';
      OUTPUT_LOAD='(1.0,-1.0)';
    'ME1_CLK_H':
      PIN_NUMBER='(0,0,0,0,BF70,0,0,0,0,0,0,0,0,0,0,0,0,0,0,0,0,0,0,0,0,0,0,0,0,0,0,0,0,0,0,0,0,0,0,0)';
      OUTPUT_LOAD='(1.0,-1.0)';
    'ME1_CLK_L':
      PIN_NUMBER='(0,0,0,0,BG71,0,0,0,0,0,0,0,0,0,0,0,0,0,0,0,0,0,0,0,0,0,0,0,0,0,0,0,0,0,0,0,0,0,0,0)';
      OUTPUT_LOAD='(1.0,-1.0)';
    'TEST39E':
      PIN_NUMBER='(0,0,0,0,BF69,0,0,0,0,0,0,0,0,0,0,0,0,0,0,0,0,0,0,0,0,0,0,0,0,0,0,0,0,0,0,0,0,0,0,0)';
      OUTPUT_LOAD='(1.0,-1.0)';
    'MF_ALERT_L':
      PIN_NUMBER='(0,0,0,0,0,AT65,0,0,0,0,0,0,0,0,0,0,0,0,0,0,0,0,0,0,0,0,0,0,0,0,0,0,0,0,0,0,0,0,0,0)';
      INPUT_LOAD='(-0.01,0.01)';
    'MF_RESET_L':
      PIN_NUMBER='(0,0,0,0,0,AU66,0,0,0,0,0,0,0,0,0,0,0,0,0,0,0,0,0,0,0,0,0,0,0,0,0,0,0,0,0,0,0,0,0,0)';
      OUTPUT_LOAD='(1.0,-1.0)';
    'MFB_DQS_L6':
      PIN_NUMBER='(0,0,0,0,0,CL66,0,0,0,0,0,0,0,0,0,0,0,0,0,0,0,0,0,0,0,0,0,0,0,0,0,0,0,0,0,0,0,0,0,0)';
      BIDIRECTIONAL='TRUE';
      INPUT_LOAD='(-0.01,0.01)';
      OUTPUT_LOAD='(1.0,-1.0)';
    'MFB_DQS_H2':
      PIN_NUMBER='(0,0,0,0,0,CT67,0,0,0,0,0,0,0,0,0,0,0,0,0,0,0,0,0,0,0,0,0,0,0,0,0,0,0,0,0,0,0,0,0,0)';
      BIDIRECTIONAL='TRUE';
      INPUT_LOAD='(-0.01,0.01)';
      OUTPUT_LOAD='(1.0,-1.0)';
    'MFB_DATA19':
      PIN_NUMBER='(0,0,0,0,0,CT65,0,0,0,0,0,0,0,0,0,0,0,0,0,0,0,0,0,0,0,0,0,0,0,0,0,0,0,0,0,0,0,0,0,0)';
      BIDIRECTIONAL='TRUE';
      INPUT_LOAD='(-0.01,0.01)';
      OUTPUT_LOAD='(1.0,-1.0)';
    'MFB_DATA7':
      PIN_NUMBER='(0,0,0,0,0,CH65,0,0,0,0,0,0,0,0,0,0,0,0,0,0,0,0,0,0,0,0,0,0,0,0,0,0,0,0,0,0,0,0,0,0)';
      BIDIRECTIONAL='TRUE';
      INPUT_LOAD='(-0.01,0.01)';
      OUTPUT_LOAD='(1.0,-1.0)';
    'MFA_DQS_H8':
      PIN_NUMBER='(0,0,0,0,0,AG66,0,0,0,0,0,0,0,0,0,0,0,0,0,0,0,0,0,0,0,0,0,0,0,0,0,0,0,0,0,0,0,0,0,0)';
      BIDIRECTIONAL='TRUE';
      INPUT_LOAD='(-0.01,0.01)';
      OUTPUT_LOAD='(1.0,-1.0)';
    'MFA_DATA30':
      PIN_NUMBER='(0,0,0,0,0,AH67,0,0,0,0,0,0,0,0,0,0,0,0,0,0,0,0,0,0,0,0,0,0,0,0,0,0,0,0,0,0,0,0,0,0)';
      BIDIRECTIONAL='TRUE';
      INPUT_LOAD='(-0.01,0.01)';
      OUTPUT_LOAD='(1.0,-1.0)';
    'MFA_DATA8':
      PIN_NUMBER='(0,0,0,0,0,L67,0,0,0,0,0,0,0,0,0,0,0,0,0,0,0,0,0,0,0,0,0,0,0,0,0,0,0,0,0,0,0,0,0,0)';
      BIDIRECTIONAL='TRUE';
      INPUT_LOAD='(-0.01,0.01)';
      OUTPUT_LOAD='(1.0,-1.0)';
    'MFA1_CS_L0':
      PIN_NUMBER='(0,0,0,0,0,AU67,0,0,0,0,0,0,0,0,0,0,0,0,0,0,0,0,0,0,0,0,0,0,0,0,0,0,0,0,0,0,0,0,0,0)';
      OUTPUT_LOAD='(1.0,-1.0)';
    'MFA0_CS_L1':
      PIN_NUMBER='(0,0,0,0,0,AW66,0,0,0,0,0,0,0,0,0,0,0,0,0,0,0,0,0,0,0,0,0,0,0,0,0,0,0,0,0,0,0,0,0,0)';
      OUTPUT_LOAD='(1.0,-1.0)';
    'MFB_DQS_L7':
      PIN_NUMBER='(0,0,0,0,0,CU66,0,0,0,0,0,0,0,0,0,0,0,0,0,0,0,0,0,0,0,0,0,0,0,0,0,0,0,0,0,0,0,0,0,0)';
      BIDIRECTIONAL='TRUE';
      INPUT_LOAD='(-0.01,0.01)';
      OUTPUT_LOAD='(1.0,-1.0)';
    'MFB_DQS_H3':
      PIN_NUMBER='(0,0,0,0,0,DB67,0,0,0,0,0,0,0,0,0,0,0,0,0,0,0,0,0,0,0,0,0,0,0,0,0,0,0,0,0,0,0,0,0,0)';
      BIDIRECTIONAL='TRUE';
      INPUT_LOAD='(-0.01,0.01)';
      OUTPUT_LOAD='(1.0,-1.0)';
    'MFB_DATA8':
      PIN_NUMBER='(0,0,0,0,0,CH67,0,0,0,0,0,0,0,0,0,0,0,0,0,0,0,0,0,0,0,0,0,0,0,0,0,0,0,0,0,0,0,0,0,0)';
      BIDIRECTIONAL='TRUE';
      INPUT_LOAD='(-0.01,0.01)';
      OUTPUT_LOAD='(1.0,-1.0)';
    'MFA_DQS_H9':
      PIN_NUMBER='(0,0,0,0,0,AN66,0,0,0,0,0,0,0,0,0,0,0,0,0,0,0,0,0,0,0,0,0,0,0,0,0,0,0,0,0,0,0,0,0,0)';
      BIDIRECTIONAL='TRUE';
      INPUT_LOAD='(-0.01,0.01)';
      OUTPUT_LOAD='(1.0,-1.0)';
    'MFA_DATA31':
      PIN_NUMBER='(0,0,0,0,0,AJ66,0,0,0,0,0,0,0,0,0,0,0,0,0,0,0,0,0,0,0,0,0,0,0,0,0,0,0,0,0,0,0,0,0,0)';
      BIDIRECTIONAL='TRUE';
      INPUT_LOAD='(-0.01,0.01)';
      OUTPUT_LOAD='(1.0,-1.0)';
    'MFA_DATA20':
      PIN_NUMBER='(0,0,0,0,0,AA67,0,0,0,0,0,0,0,0,0,0,0,0,0,0,0,0,0,0,0,0,0,0,0,0,0,0,0,0,0,0,0,0,0,0)';
      BIDIRECTIONAL='TRUE';
      INPUT_LOAD='(-0.01,0.01)';
      OUTPUT_LOAD='(1.0,-1.0)';
    'MFA_DATA9':
      PIN_NUMBER='(0,0,0,0,0,M65,0,0,0,0,0,0,0,0,0,0,0,0,0,0,0,0,0,0,0,0,0,0,0,0,0,0,0,0,0,0,0,0,0,0)';
      BIDIRECTIONAL='TRUE';
      INPUT_LOAD='(-0.01,0.01)';
      OUTPUT_LOAD='(1.0,-1.0)';
    'MFA_CHECK0':
      PIN_NUMBER='(0,0,0,0,0,AJ67,0,0,0,0,0,0,0,0,0,0,0,0,0,0,0,0,0,0,0,0,0,0,0,0,0,0,0,0,0,0,0,0,0,0)';
      BIDIRECTIONAL='TRUE';
      INPUT_LOAD='(-0.01,0.01)';
      OUTPUT_LOAD='(1.0,-1.0)';
    'MFA1_CS_L1':
      PIN_NUMBER='(0,0,0,0,0,AV65,0,0,0,0,0,0,0,0,0,0,0,0,0,0,0,0,0,0,0,0,0,0,0,0,0,0,0,0,0,0,0,0,0,0)';
      OUTPUT_LOAD='(1.0,-1.0)';
    'MFB_DQS_L8':
      PIN_NUMBER='(0,0,0,0,0,DC66,0,0,0,0,0,0,0,0,0,0,0,0,0,0,0,0,0,0,0,0,0,0,0,0,0,0,0,0,0,0,0,0,0,0)';
      BIDIRECTIONAL='TRUE';
      INPUT_LOAD='(-0.01,0.01)';
      OUTPUT_LOAD='(1.0,-1.0)';
    'MFB_DQS_H4':
      PIN_NUMBER='(0,0,0,0,0,BY65,0,0,0,0,0,0,0,0,0,0,0,0,0,0,0,0,0,0,0,0,0,0,0,0,0,0,0,0,0,0,0,0,0,0)';
      BIDIRECTIONAL='TRUE';
      INPUT_LOAD='(-0.01,0.01)';
      OUTPUT_LOAD='(1.0,-1.0)';
    'MFB_DATA9':
      PIN_NUMBER='(0,0,0,0,0,CJ66,0,0,0,0,0,0,0,0,0,0,0,0,0,0,0,0,0,0,0,0,0,0,0,0,0,0,0,0,0,0,0,0,0,0)';
      BIDIRECTIONAL='TRUE';
      INPUT_LOAD='(-0.01,0.01)';
      OUTPUT_LOAD='(1.0,-1.0)';
    'MFA_DATA21':
      PIN_NUMBER='(0,0,0,0,0,AB65,0,0,0,0,0,0,0,0,0,0,0,0,0,0,0,0,0,0,0,0,0,0,0,0,0,0,0,0,0,0,0,0,0,0)';
      BIDIRECTIONAL='TRUE';
      INPUT_LOAD='(-0.01,0.01)';
      OUTPUT_LOAD='(1.0,-1.0)';
    'MFA_DATA10':
      PIN_NUMBER='(0,0,0,0,0,M67,0,0,0,0,0,0,0,0,0,0,0,0,0,0,0,0,0,0,0,0,0,0,0,0,0,0,0,0,0,0,0,0,0,0)';
      BIDIRECTIONAL='TRUE';
      INPUT_LOAD='(-0.01,0.01)';
      OUTPUT_LOAD='(1.0,-1.0)';
    'MFA_CHECK1':
      PIN_NUMBER='(0,0,0,0,0,AK65,0,0,0,0,0,0,0,0,0,0,0,0,0,0,0,0,0,0,0,0,0,0,0,0,0,0,0,0,0,0,0,0,0,0)';
      BIDIRECTIONAL='TRUE';
      INPUT_LOAD='(-0.01,0.01)';
      OUTPUT_LOAD='(1.0,-1.0)';
    'MFB_DQS_L9':
      PIN_NUMBER='(0,0,0,0,0,BW67,0,0,0,0,0,0,0,0,0,0,0,0,0,0,0,0,0,0,0,0,0,0,0,0,0,0,0,0,0,0,0,0,0,0)';
      BIDIRECTIONAL='TRUE';
      INPUT_LOAD='(-0.01,0.01)';
      OUTPUT_LOAD='(1.0,-1.0)';
    'MFB_DQS_H5':
      PIN_NUMBER='(0,0,0,0,0,CF65,0,0,0,0,0,0,0,0,0,0,0,0,0,0,0,0,0,0,0,0,0,0,0,0,0,0,0,0,0,0,0,0,0,0)';
      BIDIRECTIONAL='TRUE';
      INPUT_LOAD='(-0.01,0.01)';
      OUTPUT_LOAD='(1.0,-1.0)';
    'MFA_DATA22':
      PIN_NUMBER='(0,0,0,0,0,AB67,0,0,0,0,0,0,0,0,0,0,0,0,0,0,0,0,0,0,0,0,0,0,0,0,0,0,0,0,0,0,0,0,0,0)';
      BIDIRECTIONAL='TRUE';
      INPUT_LOAD='(-0.01,0.01)';
      OUTPUT_LOAD='(1.0,-1.0)';
    'MFA_DATA11':
      PIN_NUMBER='(0,0,0,0,0,N66,0,0,0,0,0,0,0,0,0,0,0,0,0,0,0,0,0,0,0,0,0,0,0,0,0,0,0,0,0,0,0,0,0,0)';
      BIDIRECTIONAL='TRUE';
      INPUT_LOAD='(-0.01,0.01)';
      OUTPUT_LOAD='(1.0,-1.0)';
    'MFA_CHECK2':
      PIN_NUMBER='(0,0,0,0,0,AK67,0,0,0,0,0,0,0,0,0,0,0,0,0,0,0,0,0,0,0,0,0,0,0,0,0,0,0,0,0,0,0,0,0,0)';
      BIDIRECTIONAL='TRUE';
      INPUT_LOAD='(-0.01,0.01)';
      OUTPUT_LOAD='(1.0,-1.0)';
    'MFB_DQS_H6':
      PIN_NUMBER='(0,0,0,0,0,CM65,0,0,0,0,0,0,0,0,0,0,0,0,0,0,0,0,0,0,0,0,0,0,0,0,0,0,0,0,0,0,0,0,0,0)';
      BIDIRECTIONAL='TRUE';
      INPUT_LOAD='(-0.01,0.01)';
      OUTPUT_LOAD='(1.0,-1.0)';
    'MFA_DATA23':
      PIN_NUMBER='(0,0,0,0,0,AC66,0,0,0,0,0,0,0,0,0,0,0,0,0,0,0,0,0,0,0,0,0,0,0,0,0,0,0,0,0,0,0,0,0,0)';
      BIDIRECTIONAL='TRUE';
      INPUT_LOAD='(-0.01,0.01)';
      OUTPUT_LOAD='(1.0,-1.0)';
    'MFA_DATA12':
      PIN_NUMBER='(0,0,0,0,0,R67,0,0,0,0,0,0,0,0,0,0,0,0,0,0,0,0,0,0,0,0,0,0,0,0,0,0,0,0,0,0,0,0,0,0)';
      BIDIRECTIONAL='TRUE';
      INPUT_LOAD='(-0.01,0.01)';
      OUTPUT_LOAD='(1.0,-1.0)';
    'MFA_CHECK3':
      PIN_NUMBER='(0,0,0,0,0,AL66,0,0,0,0,0,0,0,0,0,0,0,0,0,0,0,0,0,0,0,0,0,0,0,0,0,0,0,0,0,0,0,0,0,0)';
      BIDIRECTIONAL='TRUE';
      INPUT_LOAD='(-0.01,0.01)';
      OUTPUT_LOAD='(1.0,-1.0)';
    'MFA_CA0':
      PIN_NUMBER='(0,0,0,0,0,AW67,0,0,0,0,0,0,0,0,0,0,0,0,0,0,0,0,0,0,0,0,0,0,0,0,0,0,0,0,0,0,0,0,0,0)';
      OUTPUT_LOAD='(1.0,-1.0)';
    'MFB_DQS_H7':
      PIN_NUMBER='(0,0,0,0,0,CV65,0,0,0,0,0,0,0,0,0,0,0,0,0,0,0,0,0,0,0,0,0,0,0,0,0,0,0,0,0,0,0,0,0,0)';
      BIDIRECTIONAL='TRUE';
      INPUT_LOAD='(-0.01,0.01)';
      OUTPUT_LOAD='(1.0,-1.0)';
    'MFB_CA0':
      PIN_NUMBER='(0,0,0,0,0,BG66,0,0,0,0,0,0,0,0,0,0,0,0,0,0,0,0,0,0,0,0,0,0,0,0,0,0,0,0,0,0,0,0,0,0)';
      OUTPUT_LOAD='(1.0,-1.0)';
    'MFB0_CS_L0':
      PIN_NUMBER='(0,0,0,0,0,BM65,0,0,0,0,0,0,0,0,0,0,0,0,0,0,0,0,0,0,0,0,0,0,0,0,0,0,0,0,0,0,0,0,0,0)';
      OUTPUT_LOAD='(1.0,-1.0)';
    'MFA_DQS_L0':
      PIN_NUMBER='(0,0,0,0,0,H67,0,0,0,0,0,0,0,0,0,0,0,0,0,0,0,0,0,0,0,0,0,0,0,0,0,0,0,0,0,0,0,0,0,0)';
      BIDIRECTIONAL='TRUE';
      INPUT_LOAD='(-0.01,0.01)';
      OUTPUT_LOAD='(1.0,-1.0)';
    'MFA_DATA24':
      PIN_NUMBER='(0,0,0,0,0,AC67,0,0,0,0,0,0,0,0,0,0,0,0,0,0,0,0,0,0,0,0,0,0,0,0,0,0,0,0,0,0,0,0,0,0)';
      BIDIRECTIONAL='TRUE';
      INPUT_LOAD='(-0.01,0.01)';
      OUTPUT_LOAD='(1.0,-1.0)';
    'MFA_DATA13':
      PIN_NUMBER='(0,0,0,0,0,T65,0,0,0,0,0,0,0,0,0,0,0,0,0,0,0,0,0,0,0,0,0,0,0,0,0,0,0,0,0,0,0,0,0,0)';
      BIDIRECTIONAL='TRUE';
      INPUT_LOAD='(-0.01,0.01)';
      OUTPUT_LOAD='(1.0,-1.0)';
    'MFA_CHECK4':
      PIN_NUMBER='(0,0,0,0,0,AN67,0,0,0,0,0,0,0,0,0,0,0,0,0,0,0,0,0,0,0,0,0,0,0,0,0,0,0,0,0,0,0,0,0,0)';
      BIDIRECTIONAL='TRUE';
      INPUT_LOAD='(-0.01,0.01)';
      OUTPUT_LOAD='(1.0,-1.0)';
    'MFA_CA1':
      PIN_NUMBER='(0,0,0,0,0,AY67,0,0,0,0,0,0,0,0,0,0,0,0,0,0,0,0,0,0,0,0,0,0,0,0,0,0,0,0,0,0,0,0,0,0)';
      OUTPUT_LOAD='(1.0,-1.0)';
    'MFB_DQS_H8':
      PIN_NUMBER='(0,0,0,0,0,DD65,0,0,0,0,0,0,0,0,0,0,0,0,0,0,0,0,0,0,0,0,0,0,0,0,0,0,0,0,0,0,0,0,0,0)';
      BIDIRECTIONAL='TRUE';
      INPUT_LOAD='(-0.01,0.01)';
      OUTPUT_LOAD='(1.0,-1.0)';
    'MFB_DATA30':
      PIN_NUMBER='(0,0,0,0,0,DE67,0,0,0,0,0,0,0,0,0,0,0,0,0,0,0,0,0,0,0,0,0,0,0,0,0,0,0,0,0,0,0,0,0,0)';
      BIDIRECTIONAL='TRUE';
      INPUT_LOAD='(-0.01,0.01)';
      OUTPUT_LOAD='(1.0,-1.0)';
    'MFB_CA1':
      PIN_NUMBER='(0,0,0,0,0,BH65,0,0,0,0,0,0,0,0,0,0,0,0,0,0,0,0,0,0,0,0,0,0,0,0,0,0,0,0,0,0,0,0,0,0)';
      OUTPUT_LOAD='(1.0,-1.0)';
    'MFB1_CS_L0':
      PIN_NUMBER='(0,0,0,0,0,BL66,0,0,0,0,0,0,0,0,0,0,0,0,0,0,0,0,0,0,0,0,0,0,0,0,0,0,0,0,0,0,0,0,0,0)';
      OUTPUT_LOAD='(1.0,-1.0)';
    'MFB0_CS_L1':
      PIN_NUMBER='(0,0,0,0,0,BN67,0,0,0,0,0,0,0,0,0,0,0,0,0,0,0,0,0,0,0,0,0,0,0,0,0,0,0,0,0,0,0,0,0,0)';
      OUTPUT_LOAD='(1.0,-1.0)';
    'MFA_DQS_L1':
      PIN_NUMBER='(0,0,0,0,0,P67,0,0,0,0,0,0,0,0,0,0,0,0,0,0,0,0,0,0,0,0,0,0,0,0,0,0,0,0,0,0,0,0,0,0)';
      BIDIRECTIONAL='TRUE';
      INPUT_LOAD='(-0.01,0.01)';
      OUTPUT_LOAD='(1.0,-1.0)';
    'MFA_DATA25':
      PIN_NUMBER='(0,0,0,0,0,AD65,0,0,0,0,0,0,0,0,0,0,0,0,0,0,0,0,0,0,0,0,0,0,0,0,0,0,0,0,0,0,0,0,0,0)';
      BIDIRECTIONAL='TRUE';
      INPUT_LOAD='(-0.01,0.01)';
      OUTPUT_LOAD='(1.0,-1.0)';
    'MFA_DATA14':
      PIN_NUMBER='(0,0,0,0,0,T67,0,0,0,0,0,0,0,0,0,0,0,0,0,0,0,0,0,0,0,0,0,0,0,0,0,0,0,0,0,0,0,0,0,0)';
      BIDIRECTIONAL='TRUE';
      INPUT_LOAD='(-0.01,0.01)';
      OUTPUT_LOAD='(1.0,-1.0)';
    'MFA_CHECK5':
      PIN_NUMBER='(0,0,0,0,0,AP65,0,0,0,0,0,0,0,0,0,0,0,0,0,0,0,0,0,0,0,0,0,0,0,0,0,0,0,0,0,0,0,0,0,0)';
      BIDIRECTIONAL='TRUE';
      INPUT_LOAD='(-0.01,0.01)';
      OUTPUT_LOAD='(1.0,-1.0)';
    'MFA_CA2':
      PIN_NUMBER='(0,0,0,0,0,AY65,0,0,0,0,0,0,0,0,0,0,0,0,0,0,0,0,0,0,0,0,0,0,0,0,0,0,0,0,0,0,0,0,0,0)';
      OUTPUT_LOAD='(1.0,-1.0)';
    'MFB_DATA31':
      PIN_NUMBER='(0,0,0,0,0,DF67,0,0,0,0,0,0,0,0,0,0,0,0,0,0,0,0,0,0,0,0,0,0,0,0,0,0,0,0,0,0,0,0,0,0)';
      BIDIRECTIONAL='TRUE';
      INPUT_LOAD='(-0.01,0.01)';
      OUTPUT_LOAD='(1.0,-1.0)';
    'MFB_DATA20':
      PIN_NUMBER='(0,0,0,0,0,CV67,0,0,0,0,0,0,0,0,0,0,0,0,0,0,0,0,0,0,0,0,0,0,0,0,0,0,0,0,0,0,0,0,0,0)';
      BIDIRECTIONAL='TRUE';
      INPUT_LOAD='(-0.01,0.01)';
      OUTPUT_LOAD='(1.0,-1.0)';
    'MFB_CHECK0':
      PIN_NUMBER='(0,0,0,0,0,BY67,0,0,0,0,0,0,0,0,0,0,0,0,0,0,0,0,0,0,0,0,0,0,0,0,0,0,0,0,0,0,0,0,0,0)';
      BIDIRECTIONAL='TRUE';
      INPUT_LOAD='(-0.01,0.01)';
      OUTPUT_LOAD='(1.0,-1.0)';
    'MFB_CA2':
      PIN_NUMBER='(0,0,0,0,0,BH67,0,0,0,0,0,0,0,0,0,0,0,0,0,0,0,0,0,0,0,0,0,0,0,0,0,0,0,0,0,0,0,0,0,0)';
      OUTPUT_LOAD='(1.0,-1.0)';
    'MFB1_CS_L1':
      PIN_NUMBER='(0,0,0,0,0,BM67,0,0,0,0,0,0,0,0,0,0,0,0,0,0,0,0,0,0,0,0,0,0,0,0,0,0,0,0,0,0,0,0,0,0)';
      OUTPUT_LOAD='(1.0,-1.0)';
    'MFA_DQS_L2':
      PIN_NUMBER='(0,0,0,0,0,Y67,0,0,0,0,0,0,0,0,0,0,0,0,0,0,0,0,0,0,0,0,0,0,0,0,0,0,0,0,0,0,0,0,0,0)';
      BIDIRECTIONAL='TRUE';
      INPUT_LOAD='(-0.01,0.01)';
      OUTPUT_LOAD='(1.0,-1.0)';
    'MFA_DATA26':
      PIN_NUMBER='(0,0,0,0,0,AD67,0,0,0,0,0,0,0,0,0,0,0,0,0,0,0,0,0,0,0,0,0,0,0,0,0,0,0,0,0,0,0,0,0,0)';
      BIDIRECTIONAL='TRUE';
      INPUT_LOAD='(-0.01,0.01)';
      OUTPUT_LOAD='(1.0,-1.0)';
    'MFA_DATA15':
      PIN_NUMBER='(0,0,0,0,0,U66,0,0,0,0,0,0,0,0,0,0,0,0,0,0,0,0,0,0,0,0,0,0,0,0,0,0,0,0,0,0,0,0,0,0)';
      BIDIRECTIONAL='TRUE';
      INPUT_LOAD='(-0.01,0.01)';
      OUTPUT_LOAD='(1.0,-1.0)';
    'MFA_CHECK6':
      PIN_NUMBER='(0,0,0,0,0,AP67,0,0,0,0,0,0,0,0,0,0,0,0,0,0,0,0,0,0,0,0,0,0,0,0,0,0,0,0,0,0,0,0,0,0)';
      BIDIRECTIONAL='TRUE';
      INPUT_LOAD='(-0.01,0.01)';
      OUTPUT_LOAD='(1.0,-1.0)';
    'MFA_CA3':
      PIN_NUMBER='(0,0,0,0,0,BA66,0,0,0,0,0,0,0,0,0,0,0,0,0,0,0,0,0,0,0,0,0,0,0,0,0,0,0,0,0,0,0,0,0,0)';
      OUTPUT_LOAD='(1.0,-1.0)';
    'MFB_DATA21':
      PIN_NUMBER='(0,0,0,0,0,CW66,0,0,0,0,0,0,0,0,0,0,0,0,0,0,0,0,0,0,0,0,0,0,0,0,0,0,0,0,0,0,0,0,0,0)';
      BIDIRECTIONAL='TRUE';
      INPUT_LOAD='(-0.01,0.01)';
      OUTPUT_LOAD='(1.0,-1.0)';
    'MFB_DATA10':
      PIN_NUMBER='(0,0,0,0,0,CJ67,0,0,0,0,0,0,0,0,0,0,0,0,0,0,0,0,0,0,0,0,0,0,0,0,0,0,0,0,0,0,0,0,0,0)';
      BIDIRECTIONAL='TRUE';
      INPUT_LOAD='(-0.01,0.01)';
      OUTPUT_LOAD='(1.0,-1.0)';
    'MFB_CHECK1':
      PIN_NUMBER='(0,0,0,0,0,CA66,0,0,0,0,0,0,0,0,0,0,0,0,0,0,0,0,0,0,0,0,0,0,0,0,0,0,0,0,0,0,0,0,0,0)';
      BIDIRECTIONAL='TRUE';
      INPUT_LOAD='(-0.01,0.01)';
      OUTPUT_LOAD='(1.0,-1.0)';
    'MFB_CA3':
      PIN_NUMBER='(0,0,0,0,0,BJ67,0,0,0,0,0,0,0,0,0,0,0,0,0,0,0,0,0,0,0,0,0,0,0,0,0,0,0,0,0,0,0,0,0,0)';
      OUTPUT_LOAD='(1.0,-1.0)';
    'MFA_DQS_L3':
      PIN_NUMBER='(0,0,0,0,0,AF67,0,0,0,0,0,0,0,0,0,0,0,0,0,0,0,0,0,0,0,0,0,0,0,0,0,0,0,0,0,0,0,0,0,0)';
      BIDIRECTIONAL='TRUE';
      INPUT_LOAD='(-0.01,0.01)';
      OUTPUT_LOAD='(1.0,-1.0)';
    'MFA_DATA27':
      PIN_NUMBER='(0,0,0,0,0,AE66,0,0,0,0,0,0,0,0,0,0,0,0,0,0,0,0,0,0,0,0,0,0,0,0,0,0,0,0,0,0,0,0,0,0)';
      BIDIRECTIONAL='TRUE';
      INPUT_LOAD='(-0.01,0.01)';
      OUTPUT_LOAD='(1.0,-1.0)';
    'MFA_DATA16':
      PIN_NUMBER='(0,0,0,0,0,U67,0,0,0,0,0,0,0,0,0,0,0,0,0,0,0,0,0,0,0,0,0,0,0,0,0,0,0,0,0,0,0,0,0,0)';
      BIDIRECTIONAL='TRUE';
      INPUT_LOAD='(-0.01,0.01)';
      OUTPUT_LOAD='(1.0,-1.0)';
    'MFA_CHECK7':
      PIN_NUMBER='(0,0,0,0,0,AR66,0,0,0,0,0,0,0,0,0,0,0,0,0,0,0,0,0,0,0,0,0,0,0,0,0,0,0,0,0,0,0,0,0,0)';
      BIDIRECTIONAL='TRUE';
      INPUT_LOAD='(-0.01,0.01)';
      OUTPUT_LOAD='(1.0,-1.0)';
    'MFA_CA4':
      PIN_NUMBER='(0,0,0,0,0,BA67,0,0,0,0,0,0,0,0,0,0,0,0,0,0,0,0,0,0,0,0,0,0,0,0,0,0,0,0,0,0,0,0,0,0)';
      OUTPUT_LOAD='(1.0,-1.0)';
    'MFA0_RSP_L':
      PIN_NUMBER='(0,0,0,0,0,BN66,0,0,0,0,0,0,0,0,0,0,0,0,0,0,0,0,0,0,0,0,0,0,0,0,0,0,0,0,0,0,0,0,0,0)';
      INPUT_LOAD='(-0.01,0.01)';
    'MFB_DATA22':
      PIN_NUMBER='(0,0,0,0,0,CW67,0,0,0,0,0,0,0,0,0,0,0,0,0,0,0,0,0,0,0,0,0,0,0,0,0,0,0,0,0,0,0,0,0,0)';
      BIDIRECTIONAL='TRUE';
      INPUT_LOAD='(-0.01,0.01)';
      OUTPUT_LOAD='(1.0,-1.0)';
    'MFB_DATA11':
      PIN_NUMBER='(0,0,0,0,0,CK65,0,0,0,0,0,0,0,0,0,0,0,0,0,0,0,0,0,0,0,0,0,0,0,0,0,0,0,0,0,0,0,0,0,0)';
      BIDIRECTIONAL='TRUE';
      INPUT_LOAD='(-0.01,0.01)';
      OUTPUT_LOAD='(1.0,-1.0)';
    'MFB_CHECK2':
      PIN_NUMBER='(0,0,0,0,0,CA67,0,0,0,0,0,0,0,0,0,0,0,0,0,0,0,0,0,0,0,0,0,0,0,0,0,0,0,0,0,0,0,0,0,0)';
      BIDIRECTIONAL='TRUE';
      INPUT_LOAD='(-0.01,0.01)';
      OUTPUT_LOAD='(1.0,-1.0)';
    'MFB_CA4':
      PIN_NUMBER='(0,0,0,0,0,BJ66,0,0,0,0,0,0,0,0,0,0,0,0,0,0,0,0,0,0,0,0,0,0,0,0,0,0,0,0,0,0,0,0,0,0)';
      OUTPUT_LOAD='(1.0,-1.0)';
    'MFA_DQS_L4':
      PIN_NUMBER='(0,0,0,0,0,AM67,0,0,0,0,0,0,0,0,0,0,0,0,0,0,0,0,0,0,0,0,0,0,0,0,0,0,0,0,0,0,0,0,0,0)';
      BIDIRECTIONAL='TRUE';
      INPUT_LOAD='(-0.01,0.01)';
      OUTPUT_LOAD='(1.0,-1.0)';
    'MFA_DQS_H0':
      PIN_NUMBER='(0,0,0,0,0,G67,0,0,0,0,0,0,0,0,0,0,0,0,0,0,0,0,0,0,0,0,0,0,0,0,0,0,0,0,0,0,0,0,0,0)';
      BIDIRECTIONAL='TRUE';
      INPUT_LOAD='(-0.01,0.01)';
      OUTPUT_LOAD='(1.0,-1.0)';
    'MFA_DATA28':
      PIN_NUMBER='(0,0,0,0,0,AG67,0,0,0,0,0,0,0,0,0,0,0,0,0,0,0,0,0,0,0,0,0,0,0,0,0,0,0,0,0,0,0,0,0,0)';
      BIDIRECTIONAL='TRUE';
      INPUT_LOAD='(-0.01,0.01)';
      OUTPUT_LOAD='(1.0,-1.0)';
    'MFA_DATA17':
      PIN_NUMBER='(0,0,0,0,0,V65,0,0,0,0,0,0,0,0,0,0,0,0,0,0,0,0,0,0,0,0,0,0,0,0,0,0,0,0,0,0,0,0,0,0)';
      BIDIRECTIONAL='TRUE';
      INPUT_LOAD='(-0.01,0.01)';
      OUTPUT_LOAD='(1.0,-1.0)';
    'MFA_DATA0':
      PIN_NUMBER='(0,0,0,0,0,E67,0,0,0,0,0,0,0,0,0,0,0,0,0,0,0,0,0,0,0,0,0,0,0,0,0,0,0,0,0,0,0,0,0,0)';
      BIDIRECTIONAL='TRUE';
      INPUT_LOAD='(-0.01,0.01)';
      OUTPUT_LOAD='(1.0,-1.0)';
    'MFA_CA5':
      PIN_NUMBER='(0,0,0,0,0,BB67,0,0,0,0,0,0,0,0,0,0,0,0,0,0,0,0,0,0,0,0,0,0,0,0,0,0,0,0,0,0,0,0,0,0)';
      OUTPUT_LOAD='(1.0,-1.0)';
    'MFA1_RSP_L':
      PIN_NUMBER='(0,0,0,0,0,BP65,0,0,0,0,0,0,0,0,0,0,0,0,0,0,0,0,0,0,0,0,0,0,0,0,0,0,0,0,0,0,0,0,0,0)';
      INPUT_LOAD='(-0.01,0.01)';
    'MFB_DATA23':
      PIN_NUMBER='(0,0,0,0,0,CY65,0,0,0,0,0,0,0,0,0,0,0,0,0,0,0,0,0,0,0,0,0,0,0,0,0,0,0,0,0,0,0,0,0,0)';
      BIDIRECTIONAL='TRUE';
      INPUT_LOAD='(-0.01,0.01)';
      OUTPUT_LOAD='(1.0,-1.0)';
    'MFB_DATA12':
      PIN_NUMBER='(0,0,0,0,0,CM67,0,0,0,0,0,0,0,0,0,0,0,0,0,0,0,0,0,0,0,0,0,0,0,0,0,0,0,0,0,0,0,0,0,0)';
      BIDIRECTIONAL='TRUE';
      INPUT_LOAD='(-0.01,0.01)';
      OUTPUT_LOAD='(1.0,-1.0)';
    'MFB_DATA0':
      PIN_NUMBER='(0,0,0,0,0,CB67,0,0,0,0,0,0,0,0,0,0,0,0,0,0,0,0,0,0,0,0,0,0,0,0,0,0,0,0,0,0,0,0,0,0)';
      BIDIRECTIONAL='TRUE';
      INPUT_LOAD='(-0.01,0.01)';
      OUTPUT_LOAD='(1.0,-1.0)';
    'MFB_CHECK3':
      PIN_NUMBER='(0,0,0,0,0,CB65,0,0,0,0,0,0,0,0,0,0,0,0,0,0,0,0,0,0,0,0,0,0,0,0,0,0,0,0,0,0,0,0,0,0)';
      BIDIRECTIONAL='TRUE';
      INPUT_LOAD='(-0.01,0.01)';
      OUTPUT_LOAD='(1.0,-1.0)';
    'MFB_CA5':
      PIN_NUMBER='(0,0,0,0,0,BK65,0,0,0,0,0,0,0,0,0,0,0,0,0,0,0,0,0,0,0,0,0,0,0,0,0,0,0,0,0,0,0,0,0,0)';
      OUTPUT_LOAD='(1.0,-1.0)';
    'MFA_DQS_L5':
      PIN_NUMBER='(0,0,0,0,0,H65,0,0,0,0,0,0,0,0,0,0,0,0,0,0,0,0,0,0,0,0,0,0,0,0,0,0,0,0,0,0,0,0,0,0)';
      BIDIRECTIONAL='TRUE';
      INPUT_LOAD='(-0.01,0.01)';
      OUTPUT_LOAD='(1.0,-1.0)';
    'MFA_DQS_H1':
      PIN_NUMBER='(0,0,0,0,0,N67,0,0,0,0,0,0,0,0,0,0,0,0,0,0,0,0,0,0,0,0,0,0,0,0,0,0,0,0,0,0,0,0,0,0)';
      BIDIRECTIONAL='TRUE';
      INPUT_LOAD='(-0.01,0.01)';
      OUTPUT_LOAD='(1.0,-1.0)';
    'MFA_DATA29':
      PIN_NUMBER='(0,0,0,0,0,AH65,0,0,0,0,0,0,0,0,0,0,0,0,0,0,0,0,0,0,0,0,0,0,0,0,0,0,0,0,0,0,0,0,0,0)';
      BIDIRECTIONAL='TRUE';
      INPUT_LOAD='(-0.01,0.01)';
      OUTPUT_LOAD='(1.0,-1.0)';
    'MFA_DATA18':
      PIN_NUMBER='(0,0,0,0,0,V67,0,0,0,0,0,0,0,0,0,0,0,0,0,0,0,0,0,0,0,0,0,0,0,0,0,0,0,0,0,0,0,0,0,0)';
      BIDIRECTIONAL='TRUE';
      INPUT_LOAD='(-0.01,0.01)';
      OUTPUT_LOAD='(1.0,-1.0)';
    'MFA_DATA1':
      PIN_NUMBER='(0,0,0,0,0,F65,0,0,0,0,0,0,0,0,0,0,0,0,0,0,0,0,0,0,0,0,0,0,0,0,0,0,0,0,0,0,0,0,0,0)';
      BIDIRECTIONAL='TRUE';
      INPUT_LOAD='(-0.01,0.01)';
      OUTPUT_LOAD='(1.0,-1.0)';
    'MFA_CA6':
      PIN_NUMBER='(0,0,0,0,0,BB65,0,0,0,0,0,0,0,0,0,0,0,0,0,0,0,0,0,0,0,0,0,0,0,0,0,0,0,0,0,0,0,0,0,0)';
      OUTPUT_LOAD='(1.0,-1.0)';
    'MFB_DQS_L0':
      PIN_NUMBER='(0,0,0,0,0,CE67,0,0,0,0,0,0,0,0,0,0,0,0,0,0,0,0,0,0,0,0,0,0,0,0,0,0,0,0,0,0,0,0,0,0)';
      BIDIRECTIONAL='TRUE';
      INPUT_LOAD='(-0.01,0.01)';
      OUTPUT_LOAD='(1.0,-1.0)';
    'MFB_DATA24':
      PIN_NUMBER='(0,0,0,0,0,CY67,0,0,0,0,0,0,0,0,0,0,0,0,0,0,0,0,0,0,0,0,0,0,0,0,0,0,0,0,0,0,0,0,0,0)';
      BIDIRECTIONAL='TRUE';
      INPUT_LOAD='(-0.01,0.01)';
      OUTPUT_LOAD='(1.0,-1.0)';
    'MFB_DATA13':
      PIN_NUMBER='(0,0,0,0,0,CN66,0,0,0,0,0,0,0,0,0,0,0,0,0,0,0,0,0,0,0,0,0,0,0,0,0,0,0,0,0,0,0,0,0,0)';
      BIDIRECTIONAL='TRUE';
      INPUT_LOAD='(-0.01,0.01)';
      OUTPUT_LOAD='(1.0,-1.0)';
    'MFB_DATA1':
      PIN_NUMBER='(0,0,0,0,0,CC66,0,0,0,0,0,0,0,0,0,0,0,0,0,0,0,0,0,0,0,0,0,0,0,0,0,0,0,0,0,0,0,0,0,0)';
      BIDIRECTIONAL='TRUE';
      INPUT_LOAD='(-0.01,0.01)';
      OUTPUT_LOAD='(1.0,-1.0)';
    'MFB_CHECK4':
      PIN_NUMBER='(0,0,0,0,0,BT67,0,0,0,0,0,0,0,0,0,0,0,0,0,0,0,0,0,0,0,0,0,0,0,0,0,0,0,0,0,0,0,0,0,0)';
      BIDIRECTIONAL='TRUE';
      INPUT_LOAD='(-0.01,0.01)';
      OUTPUT_LOAD='(1.0,-1.0)';
    'MFB_CA6':
      PIN_NUMBER='(0,0,0,0,0,BK67,0,0,0,0,0,0,0,0,0,0,0,0,0,0,0,0,0,0,0,0,0,0,0,0,0,0,0,0,0,0,0,0,0,0)';
      OUTPUT_LOAD='(1.0,-1.0)';
    'MFA_DQS_L6':
      PIN_NUMBER='(0,0,0,0,0,P65,0,0,0,0,0,0,0,0,0,0,0,0,0,0,0,0,0,0,0,0,0,0,0,0,0,0,0,0,0,0,0,0,0,0)';
      BIDIRECTIONAL='TRUE';
      INPUT_LOAD='(-0.01,0.01)';
      OUTPUT_LOAD='(1.0,-1.0)';
    'MFA_DQS_H2':
      PIN_NUMBER='(0,0,0,0,0,W67,0,0,0,0,0,0,0,0,0,0,0,0,0,0,0,0,0,0,0,0,0,0,0,0,0,0,0,0,0,0,0,0,0,0)';
      BIDIRECTIONAL='TRUE';
      INPUT_LOAD='(-0.01,0.01)';
      OUTPUT_LOAD='(1.0,-1.0)';
    'MFA_DATA19':
      PIN_NUMBER='(0,0,0,0,0,W66,0,0,0,0,0,0,0,0,0,0,0,0,0,0,0,0,0,0,0,0,0,0,0,0,0,0,0,0,0,0,0,0,0,0)';
      BIDIRECTIONAL='TRUE';
      INPUT_LOAD='(-0.01,0.01)';
      OUTPUT_LOAD='(1.0,-1.0)';
    'MFA_DATA2':
      PIN_NUMBER='(0,0,0,0,0,F67,0,0,0,0,0,0,0,0,0,0,0,0,0,0,0,0,0,0,0,0,0,0,0,0,0,0,0,0,0,0,0,0,0,0)';
      BIDIRECTIONAL='TRUE';
      INPUT_LOAD='(-0.01,0.01)';
      OUTPUT_LOAD='(1.0,-1.0)';
    'MFB_DQS_L1':
      PIN_NUMBER='(0,0,0,0,0,CL67,0,0,0,0,0,0,0,0,0,0,0,0,0,0,0,0,0,0,0,0,0,0,0,0,0,0,0,0,0,0,0,0,0,0)';
      BIDIRECTIONAL='TRUE';
      INPUT_LOAD='(-0.01,0.01)';
      OUTPUT_LOAD='(1.0,-1.0)';
    'MFB_DATA25':
      PIN_NUMBER='(0,0,0,0,0,DA66,0,0,0,0,0,0,0,0,0,0,0,0,0,0,0,0,0,0,0,0,0,0,0,0,0,0,0,0,0,0,0,0,0,0)';
      BIDIRECTIONAL='TRUE';
      INPUT_LOAD='(-0.01,0.01)';
      OUTPUT_LOAD='(1.0,-1.0)';
    'MFB_DATA14':
      PIN_NUMBER='(0,0,0,0,0,CN67,0,0,0,0,0,0,0,0,0,0,0,0,0,0,0,0,0,0,0,0,0,0,0,0,0,0,0,0,0,0,0,0,0,0)';
      BIDIRECTIONAL='TRUE';
      INPUT_LOAD='(-0.01,0.01)';
      OUTPUT_LOAD='(1.0,-1.0)';
    'MFB_DATA2':
      PIN_NUMBER='(0,0,0,0,0,CC67,0,0,0,0,0,0,0,0,0,0,0,0,0,0,0,0,0,0,0,0,0,0,0,0,0,0,0,0,0,0,0,0,0,0)';
      BIDIRECTIONAL='TRUE';
      INPUT_LOAD='(-0.01,0.01)';
      OUTPUT_LOAD='(1.0,-1.0)';
    'MFB_CHECK5':
      PIN_NUMBER='(0,0,0,0,0,BU66,0,0,0,0,0,0,0,0,0,0,0,0,0,0,0,0,0,0,0,0,0,0,0,0,0,0,0,0,0,0,0,0,0,0)';
      BIDIRECTIONAL='TRUE';
      INPUT_LOAD='(-0.01,0.01)';
      OUTPUT_LOAD='(1.0,-1.0)';
    'MFA_DQS_L7':
      PIN_NUMBER='(0,0,0,0,0,Y65,0,0,0,0,0,0,0,0,0,0,0,0,0,0,0,0,0,0,0,0,0,0,0,0,0,0,0,0,0,0,0,0,0,0)';
      BIDIRECTIONAL='TRUE';
      INPUT_LOAD='(-0.01,0.01)';
      OUTPUT_LOAD='(1.0,-1.0)';
    'MFA_DQS_H3':
      PIN_NUMBER='(0,0,0,0,0,AE67,0,0,0,0,0,0,0,0,0,0,0,0,0,0,0,0,0,0,0,0,0,0,0,0,0,0,0,0,0,0,0,0,0,0)';
      BIDIRECTIONAL='TRUE';
      INPUT_LOAD='(-0.01,0.01)';
      OUTPUT_LOAD='(1.0,-1.0)';
    'MFA_DATA3':
      PIN_NUMBER='(0,0,0,0,0,G66,0,0,0,0,0,0,0,0,0,0,0,0,0,0,0,0,0,0,0,0,0,0,0,0,0,0,0,0,0,0,0,0,0,0)';
      BIDIRECTIONAL='TRUE';
      INPUT_LOAD='(-0.01,0.01)';
      OUTPUT_LOAD='(1.0,-1.0)';
    'MFB_DQS_L2':
      PIN_NUMBER='(0,0,0,0,0,CU67,0,0,0,0,0,0,0,0,0,0,0,0,0,0,0,0,0,0,0,0,0,0,0,0,0,0,0,0,0,0,0,0,0,0)';
      BIDIRECTIONAL='TRUE';
      INPUT_LOAD='(-0.01,0.01)';
      OUTPUT_LOAD='(1.0,-1.0)';
    'MFB_DATA26':
      PIN_NUMBER='(0,0,0,0,0,DA67,0,0,0,0,0,0,0,0,0,0,0,0,0,0,0,0,0,0,0,0,0,0,0,0,0,0,0,0,0,0,0,0,0,0)';
      BIDIRECTIONAL='TRUE';
      INPUT_LOAD='(-0.01,0.01)';
      OUTPUT_LOAD='(1.0,-1.0)';
    'MFB_DATA15':
      PIN_NUMBER='(0,0,0,0,0,CP65,0,0,0,0,0,0,0,0,0,0,0,0,0,0,0,0,0,0,0,0,0,0,0,0,0,0,0,0,0,0,0,0,0,0)';
      BIDIRECTIONAL='TRUE';
      INPUT_LOAD='(-0.01,0.01)';
      OUTPUT_LOAD='(1.0,-1.0)';
    'MFB_DATA3':
      PIN_NUMBER='(0,0,0,0,0,CD65,0,0,0,0,0,0,0,0,0,0,0,0,0,0,0,0,0,0,0,0,0,0,0,0,0,0,0,0,0,0,0,0,0,0)';
      BIDIRECTIONAL='TRUE';
      INPUT_LOAD='(-0.01,0.01)';
      OUTPUT_LOAD='(1.0,-1.0)';
    'MFB_CHECK6':
      PIN_NUMBER='(0,0,0,0,0,BU67,0,0,0,0,0,0,0,0,0,0,0,0,0,0,0,0,0,0,0,0,0,0,0,0,0,0,0,0,0,0,0,0,0,0)';
      BIDIRECTIONAL='TRUE';
      INPUT_LOAD='(-0.01,0.01)';
      OUTPUT_LOAD='(1.0,-1.0)';
    'MFA_DQS_L8':
      PIN_NUMBER='(0,0,0,0,0,AF65,0,0,0,0,0,0,0,0,0,0,0,0,0,0,0,0,0,0,0,0,0,0,0,0,0,0,0,0,0,0,0,0,0,0)';
      BIDIRECTIONAL='TRUE';
      INPUT_LOAD='(-0.01,0.01)';
      OUTPUT_LOAD='(1.0,-1.0)';
    'MFA_DQS_H4':
      PIN_NUMBER='(0,0,0,0,0,AL67,0,0,0,0,0,0,0,0,0,0,0,0,0,0,0,0,0,0,0,0,0,0,0,0,0,0,0,0,0,0,0,0,0,0)';
      BIDIRECTIONAL='TRUE';
      INPUT_LOAD='(-0.01,0.01)';
      OUTPUT_LOAD='(1.0,-1.0)';
    'MFA_DATA4':
      PIN_NUMBER='(0,0,0,0,0,J67,0,0,0,0,0,0,0,0,0,0,0,0,0,0,0,0,0,0,0,0,0,0,0,0,0,0,0,0,0,0,0,0,0,0)';
      BIDIRECTIONAL='TRUE';
      INPUT_LOAD='(-0.01,0.01)';
      OUTPUT_LOAD='(1.0,-1.0)';
    'MFB_DQS_L3':
      PIN_NUMBER='(0,0,0,0,0,DC67,0,0,0,0,0,0,0,0,0,0,0,0,0,0,0,0,0,0,0,0,0,0,0,0,0,0,0,0,0,0,0,0,0,0)';
      BIDIRECTIONAL='TRUE';
      INPUT_LOAD='(-0.01,0.01)';
      OUTPUT_LOAD='(1.0,-1.0)';
    'MFB_DATA27':
      PIN_NUMBER='(0,0,0,0,0,DB65,0,0,0,0,0,0,0,0,0,0,0,0,0,0,0,0,0,0,0,0,0,0,0,0,0,0,0,0,0,0,0,0,0,0)';
      BIDIRECTIONAL='TRUE';
      INPUT_LOAD='(-0.01,0.01)';
      OUTPUT_LOAD='(1.0,-1.0)';
    'MFB_DATA16':
      PIN_NUMBER='(0,0,0,0,0,CP67,0,0,0,0,0,0,0,0,0,0,0,0,0,0,0,0,0,0,0,0,0,0,0,0,0,0,0,0,0,0,0,0,0,0)';
      BIDIRECTIONAL='TRUE';
      INPUT_LOAD='(-0.01,0.01)';
      OUTPUT_LOAD='(1.0,-1.0)';
    'MFB_DATA4':
      PIN_NUMBER='(0,0,0,0,0,CF67,0,0,0,0,0,0,0,0,0,0,0,0,0,0,0,0,0,0,0,0,0,0,0,0,0,0,0,0,0,0,0,0,0,0)';
      BIDIRECTIONAL='TRUE';
      INPUT_LOAD='(-0.01,0.01)';
      OUTPUT_LOAD='(1.0,-1.0)';
    'MFB_CHECK7':
      PIN_NUMBER='(0,0,0,0,0,BV65,0,0,0,0,0,0,0,0,0,0,0,0,0,0,0,0,0,0,0,0,0,0,0,0,0,0,0,0,0,0,0,0,0,0)';
      BIDIRECTIONAL='TRUE';
      INPUT_LOAD='(-0.01,0.01)';
      OUTPUT_LOAD='(1.0,-1.0)';
    'MFB0_RSP_L':
      PIN_NUMBER='(0,0,0,0,0,BP67,0,0,0,0,0,0,0,0,0,0,0,0,0,0,0,0,0,0,0,0,0,0,0,0,0,0,0,0,0,0,0,0,0,0)';
      INPUT_LOAD='(-0.01,0.01)';
    'MFA_DQS_L9':
      PIN_NUMBER='(0,0,0,0,0,AM65,0,0,0,0,0,0,0,0,0,0,0,0,0,0,0,0,0,0,0,0,0,0,0,0,0,0,0,0,0,0,0,0,0,0)';
      BIDIRECTIONAL='TRUE';
      INPUT_LOAD='(-0.01,0.01)';
      OUTPUT_LOAD='(1.0,-1.0)';
    'MFA_DQS_H5':
      PIN_NUMBER='(0,0,0,0,0,J66,0,0,0,0,0,0,0,0,0,0,0,0,0,0,0,0,0,0,0,0,0,0,0,0,0,0,0,0,0,0,0,0,0,0)';
      BIDIRECTIONAL='TRUE';
      INPUT_LOAD='(-0.01,0.01)';
      OUTPUT_LOAD='(1.0,-1.0)';
    'MFA_DATA5':
      PIN_NUMBER='(0,0,0,0,0,K65,0,0,0,0,0,0,0,0,0,0,0,0,0,0,0,0,0,0,0,0,0,0,0,0,0,0,0,0,0,0,0,0,0,0)';
      BIDIRECTIONAL='TRUE';
      INPUT_LOAD='(-0.01,0.01)';
      OUTPUT_LOAD='(1.0,-1.0)';
    'MFB_DQS_L4':
      PIN_NUMBER='(0,0,0,0,0,BW66,0,0,0,0,0,0,0,0,0,0,0,0,0,0,0,0,0,0,0,0,0,0,0,0,0,0,0,0,0,0,0,0,0,0)';
      BIDIRECTIONAL='TRUE';
      INPUT_LOAD='(-0.01,0.01)';
      OUTPUT_LOAD='(1.0,-1.0)';
    'MFB_DQS_H0':
      PIN_NUMBER='(0,0,0,0,0,CD67,0,0,0,0,0,0,0,0,0,0,0,0,0,0,0,0,0,0,0,0,0,0,0,0,0,0,0,0,0,0,0,0,0,0)';
      BIDIRECTIONAL='TRUE';
      INPUT_LOAD='(-0.01,0.01)';
      OUTPUT_LOAD='(1.0,-1.0)';
    'MFB_DATA28':
      PIN_NUMBER='(0,0,0,0,0,DD67,0,0,0,0,0,0,0,0,0,0,0,0,0,0,0,0,0,0,0,0,0,0,0,0,0,0,0,0,0,0,0,0,0,0)';
      BIDIRECTIONAL='TRUE';
      INPUT_LOAD='(-0.01,0.01)';
      OUTPUT_LOAD='(1.0,-1.0)';
    'MFB_DATA17':
      PIN_NUMBER='(0,0,0,0,0,CR66,0,0,0,0,0,0,0,0,0,0,0,0,0,0,0,0,0,0,0,0,0,0,0,0,0,0,0,0,0,0,0,0,0,0)';
      BIDIRECTIONAL='TRUE';
      INPUT_LOAD='(-0.01,0.01)';
      OUTPUT_LOAD='(1.0,-1.0)';
    'MFB_DATA5':
      PIN_NUMBER='(0,0,0,0,0,CG66,0,0,0,0,0,0,0,0,0,0,0,0,0,0,0,0,0,0,0,0,0,0,0,0,0,0,0,0,0,0,0,0,0,0)';
      BIDIRECTIONAL='TRUE';
      INPUT_LOAD='(-0.01,0.01)';
      OUTPUT_LOAD='(1.0,-1.0)';
    'MFB1_RSP_L':
      PIN_NUMBER='(0,0,0,0,0,BR67,0,0,0,0,0,0,0,0,0,0,0,0,0,0,0,0,0,0,0,0,0,0,0,0,0,0,0,0,0,0,0,0,0,0)';
      INPUT_LOAD='(-0.01,0.01)';
    'MFA_DQS_H6':
      PIN_NUMBER='(0,0,0,0,0,R66,0,0,0,0,0,0,0,0,0,0,0,0,0,0,0,0,0,0,0,0,0,0,0,0,0,0,0,0,0,0,0,0,0,0)';
      BIDIRECTIONAL='TRUE';
      INPUT_LOAD='(-0.01,0.01)';
      OUTPUT_LOAD='(1.0,-1.0)';
    'MFA_DATA6':
      PIN_NUMBER='(0,0,0,0,0,K67,0,0,0,0,0,0,0,0,0,0,0,0,0,0,0,0,0,0,0,0,0,0,0,0,0,0,0,0,0,0,0,0,0,0)';
      BIDIRECTIONAL='TRUE';
      INPUT_LOAD='(-0.01,0.01)';
      OUTPUT_LOAD='(1.0,-1.0)';
    'MFB_DQS_L5':
      PIN_NUMBER='(0,0,0,0,0,CE66,0,0,0,0,0,0,0,0,0,0,0,0,0,0,0,0,0,0,0,0,0,0,0,0,0,0,0,0,0,0,0,0,0,0)';
      BIDIRECTIONAL='TRUE';
      INPUT_LOAD='(-0.01,0.01)';
      OUTPUT_LOAD='(1.0,-1.0)';
    'MFB_DQS_H1':
      PIN_NUMBER='(0,0,0,0,0,CK67,0,0,0,0,0,0,0,0,0,0,0,0,0,0,0,0,0,0,0,0,0,0,0,0,0,0,0,0,0,0,0,0,0,0)';
      BIDIRECTIONAL='TRUE';
      INPUT_LOAD='(-0.01,0.01)';
      OUTPUT_LOAD='(1.0,-1.0)';
    'MFB_DATA29':
      PIN_NUMBER='(0,0,0,0,0,DE66,0,0,0,0,0,0,0,0,0,0,0,0,0,0,0,0,0,0,0,0,0,0,0,0,0,0,0,0,0,0,0,0,0,0)';
      BIDIRECTIONAL='TRUE';
      INPUT_LOAD='(-0.01,0.01)';
      OUTPUT_LOAD='(1.0,-1.0)';
    'MFB_DATA18':
      PIN_NUMBER='(0,0,0,0,0,CR67,0,0,0,0,0,0,0,0,0,0,0,0,0,0,0,0,0,0,0,0,0,0,0,0,0,0,0,0,0,0,0,0,0,0)';
      BIDIRECTIONAL='TRUE';
      INPUT_LOAD='(-0.01,0.01)';
      OUTPUT_LOAD='(1.0,-1.0)';
    'MFB_DATA6':
      PIN_NUMBER='(0,0,0,0,0,CG67,0,0,0,0,0,0,0,0,0,0,0,0,0,0,0,0,0,0,0,0,0,0,0,0,0,0,0,0,0,0,0,0,0,0)';
      BIDIRECTIONAL='TRUE';
      INPUT_LOAD='(-0.01,0.01)';
      OUTPUT_LOAD='(1.0,-1.0)';
    'MFA_DQS_H7':
      PIN_NUMBER='(0,0,0,0,0,AA66,0,0,0,0,0,0,0,0,0,0,0,0,0,0,0,0,0,0,0,0,0,0,0,0,0,0,0,0,0,0,0,0,0,0)';
      BIDIRECTIONAL='TRUE';
      INPUT_LOAD='(-0.01,0.01)';
      OUTPUT_LOAD='(1.0,-1.0)';
    'MFA_DATA7':
      PIN_NUMBER='(0,0,0,0,0,L66,0,0,0,0,0,0,0,0,0,0,0,0,0,0,0,0,0,0,0,0,0,0,0,0,0,0,0,0,0,0,0,0,0,0)';
      BIDIRECTIONAL='TRUE';
      INPUT_LOAD='(-0.01,0.01)';
      OUTPUT_LOAD='(1.0,-1.0)';
    'MFA0_CS_L0':
      PIN_NUMBER='(0,0,0,0,0,AV67,0,0,0,0,0,0,0,0,0,0,0,0,0,0,0,0,0,0,0,0,0,0,0,0,0,0,0,0,0,0,0,0,0,0)';
      OUTPUT_LOAD='(1.0,-1.0)';
    'MFA_PAR':
      PIN_NUMBER='(0,0,0,0,0,BC66,0,0,0,0,0,0,0,0,0,0,0,0,0,0,0,0,0,0,0,0,0,0,0,0,0,0,0,0,0,0,0,0,0,0)';
      OUTPUT_LOAD='(1.0,-1.0)';
    'MFB_PAR':
      PIN_NUMBER='(0,0,0,0,0,BL67,0,0,0,0,0,0,0,0,0,0,0,0,0,0,0,0,0,0,0,0,0,0,0,0,0,0,0,0,0,0,0,0,0,0)';
      OUTPUT_LOAD='(1.0,-1.0)';
    'MFB_DQS_H9':
      PIN_NUMBER='(0,0,0,0,0,BV67,0,0,0,0,0,0,0,0,0,0,0,0,0,0,0,0,0,0,0,0,0,0,0,0,0,0,0,0,0,0,0,0,0,0)';
      BIDIRECTIONAL='TRUE';
      INPUT_LOAD='(-0.01,0.01)';
      OUTPUT_LOAD='(1.0,-1.0)';
    'MF0_CLK_H':
      PIN_NUMBER='(0,0,0,0,0,BC67,0,0,0,0,0,0,0,0,0,0,0,0,0,0,0,0,0,0,0,0,0,0,0,0,0,0,0,0,0,0,0,0,0,0)';
      OUTPUT_LOAD='(1.0,-1.0)';
    'MF0_CLK_L':
      PIN_NUMBER='(0,0,0,0,0,BD67,0,0,0,0,0,0,0,0,0,0,0,0,0,0,0,0,0,0,0,0,0,0,0,0,0,0,0,0,0,0,0,0,0,0)';
      OUTPUT_LOAD='(1.0,-1.0)';
    'MF1_CLK_H':
      PIN_NUMBER='(0,0,0,0,0,BF67,0,0,0,0,0,0,0,0,0,0,0,0,0,0,0,0,0,0,0,0,0,0,0,0,0,0,0,0,0,0,0,0,0,0)';
      OUTPUT_LOAD='(1.0,-1.0)';
    'MF1_CLK_L':
      PIN_NUMBER='(0,0,0,0,0,BG67,0,0,0,0,0,0,0,0,0,0,0,0,0,0,0,0,0,0,0,0,0,0,0,0,0,0,0,0,0,0,0,0,0,0)';
      OUTPUT_LOAD='(1.0,-1.0)';
    'TEST39F':
      PIN_NUMBER='(0,0,0,0,0,BF65,0,0,0,0,0,0,0,0,0,0,0,0,0,0,0,0,0,0,0,0,0,0,0,0,0,0,0,0,0,0,0,0,0,0)';
      OUTPUT_LOAD='(1.0,-1.0)';
    'MG_ALERT_L':
      PIN_NUMBER='(0,0,0,0,0,0,AR2,0,0,0,0,0,0,0,0,0,0,0,0,0,0,0,0,0,0,0,0,0,0,0,0,0,0,0,0,0,0,0,0,0)';
      INPUT_LOAD='(-0.01,0.01)';
    'MG_RESET_L':
      PIN_NUMBER='(0,0,0,0,0,0,AT2,0,0,0,0,0,0,0,0,0,0,0,0,0,0,0,0,0,0,0,0,0,0,0,0,0,0,0,0,0,0,0,0,0)';
      OUTPUT_LOAD='(1.0,-1.0)';
    'MGB_DQS_L9':
      PIN_NUMBER='(0,0,0,0,0,0,BW2,0,0,0,0,0,0,0,0,0,0,0,0,0,0,0,0,0,0,0,0,0,0,0,0,0,0,0,0,0,0,0,0,0)';
      BIDIRECTIONAL='TRUE';
      INPUT_LOAD='(-0.01,0.01)';
      OUTPUT_LOAD='(1.0,-1.0)';
    'MGB_DQS_H5':
      PIN_NUMBER='(0,0,0,0,0,0,CF4,0,0,0,0,0,0,0,0,0,0,0,0,0,0,0,0,0,0,0,0,0,0,0,0,0,0,0,0,0,0,0,0,0)';
      BIDIRECTIONAL='TRUE';
      INPUT_LOAD='(-0.01,0.01)';
      OUTPUT_LOAD='(1.0,-1.0)';
    'MGB_DATA1':
      PIN_NUMBER='(0,0,0,0,0,0,CC3,0,0,0,0,0,0,0,0,0,0,0,0,0,0,0,0,0,0,0,0,0,0,0,0,0,0,0,0,0,0,0,0,0)';
      BIDIRECTIONAL='TRUE';
      INPUT_LOAD='(-0.01,0.01)';
      OUTPUT_LOAD='(1.0,-1.0)';
    'MGA_DATA22':
      PIN_NUMBER='(0,0,0,0,0,0,AB2,0,0,0,0,0,0,0,0,0,0,0,0,0,0,0,0,0,0,0,0,0,0,0,0,0,0,0,0,0,0,0,0,0)';
      BIDIRECTIONAL='TRUE';
      INPUT_LOAD='(-0.01,0.01)';
      OUTPUT_LOAD='(1.0,-1.0)';
    'MGA_DATA11':
      PIN_NUMBER='(0,0,0,0,0,0,N3,0,0,0,0,0,0,0,0,0,0,0,0,0,0,0,0,0,0,0,0,0,0,0,0,0,0,0,0,0,0,0,0,0)';
      BIDIRECTIONAL='TRUE';
      INPUT_LOAD='(-0.01,0.01)';
      OUTPUT_LOAD='(1.0,-1.0)';
    'MGA_DATA1':
      PIN_NUMBER='(0,0,0,0,0,0,F4,0,0,0,0,0,0,0,0,0,0,0,0,0,0,0,0,0,0,0,0,0,0,0,0,0,0,0,0,0,0,0,0,0)';
      BIDIRECTIONAL='TRUE';
      INPUT_LOAD='(-0.01,0.01)';
      OUTPUT_LOAD='(1.0,-1.0)';
    'MGA_CHECK2':
      PIN_NUMBER='(0,0,0,0,0,0,AK2,0,0,0,0,0,0,0,0,0,0,0,0,0,0,0,0,0,0,0,0,0,0,0,0,0,0,0,0,0,0,0,0,0)';
      BIDIRECTIONAL='TRUE';
      INPUT_LOAD='(-0.01,0.01)';
      OUTPUT_LOAD='(1.0,-1.0)';
    'MGB_DQS_H6':
      PIN_NUMBER='(0,0,0,0,0,0,CM4,0,0,0,0,0,0,0,0,0,0,0,0,0,0,0,0,0,0,0,0,0,0,0,0,0,0,0,0,0,0,0,0,0)';
      BIDIRECTIONAL='TRUE';
      INPUT_LOAD='(-0.01,0.01)';
      OUTPUT_LOAD='(1.0,-1.0)';
    'MGB_DATA2':
      PIN_NUMBER='(0,0,0,0,0,0,CC2,0,0,0,0,0,0,0,0,0,0,0,0,0,0,0,0,0,0,0,0,0,0,0,0,0,0,0,0,0,0,0,0,0)';
      BIDIRECTIONAL='TRUE';
      INPUT_LOAD='(-0.01,0.01)';
      OUTPUT_LOAD='(1.0,-1.0)';
    'MGA_DATA23':
      PIN_NUMBER='(0,0,0,0,0,0,AC3,0,0,0,0,0,0,0,0,0,0,0,0,0,0,0,0,0,0,0,0,0,0,0,0,0,0,0,0,0,0,0,0,0)';
      BIDIRECTIONAL='TRUE';
      INPUT_LOAD='(-0.01,0.01)';
      OUTPUT_LOAD='(1.0,-1.0)';
    'MGA_DATA12':
      PIN_NUMBER='(0,0,0,0,0,0,R2,0,0,0,0,0,0,0,0,0,0,0,0,0,0,0,0,0,0,0,0,0,0,0,0,0,0,0,0,0,0,0,0,0)';
      BIDIRECTIONAL='TRUE';
      INPUT_LOAD='(-0.01,0.01)';
      OUTPUT_LOAD='(1.0,-1.0)';
    'MGA_DATA2':
      PIN_NUMBER='(0,0,0,0,0,0,F2,0,0,0,0,0,0,0,0,0,0,0,0,0,0,0,0,0,0,0,0,0,0,0,0,0,0,0,0,0,0,0,0,0)';
      BIDIRECTIONAL='TRUE';
      INPUT_LOAD='(-0.01,0.01)';
      OUTPUT_LOAD='(1.0,-1.0)';
    'MGA_CHECK3':
      PIN_NUMBER='(0,0,0,0,0,0,AL3,0,0,0,0,0,0,0,0,0,0,0,0,0,0,0,0,0,0,0,0,0,0,0,0,0,0,0,0,0,0,0,0,0)';
      BIDIRECTIONAL='TRUE';
      INPUT_LOAD='(-0.01,0.01)';
      OUTPUT_LOAD='(1.0,-1.0)';
    'MGB_DQS_H7':
      PIN_NUMBER='(0,0,0,0,0,0,CV4,0,0,0,0,0,0,0,0,0,0,0,0,0,0,0,0,0,0,0,0,0,0,0,0,0,0,0,0,0,0,0,0,0)';
      BIDIRECTIONAL='TRUE';
      INPUT_LOAD='(-0.01,0.01)';
      OUTPUT_LOAD='(1.0,-1.0)';
    'MGB_DATA3':
      PIN_NUMBER='(0,0,0,0,0,0,CD4,0,0,0,0,0,0,0,0,0,0,0,0,0,0,0,0,0,0,0,0,0,0,0,0,0,0,0,0,0,0,0,0,0)';
      BIDIRECTIONAL='TRUE';
      INPUT_LOAD='(-0.01,0.01)';
      OUTPUT_LOAD='(1.0,-1.0)';
    'MGB1_CS_L0':
      PIN_NUMBER='(0,0,0,0,0,0,BL2,0,0,0,0,0,0,0,0,0,0,0,0,0,0,0,0,0,0,0,0,0,0,0,0,0,0,0,0,0,0,0,0,0)';
      OUTPUT_LOAD='(1.0,-1.0)';
    'MGB0_CS_L0':
      PIN_NUMBER='(0,0,0,0,0,0,BM4,0,0,0,0,0,0,0,0,0,0,0,0,0,0,0,0,0,0,0,0,0,0,0,0,0,0,0,0,0,0,0,0,0)';
      OUTPUT_LOAD='(1.0,-1.0)';
    'MGA_DQS_L0':
      PIN_NUMBER='(0,0,0,0,0,0,H2,0,0,0,0,0,0,0,0,0,0,0,0,0,0,0,0,0,0,0,0,0,0,0,0,0,0,0,0,0,0,0,0,0)';
      BIDIRECTIONAL='TRUE';
      INPUT_LOAD='(-0.01,0.01)';
      OUTPUT_LOAD='(1.0,-1.0)';
    'MGA_DATA24':
      PIN_NUMBER='(0,0,0,0,0,0,AC2,0,0,0,0,0,0,0,0,0,0,0,0,0,0,0,0,0,0,0,0,0,0,0,0,0,0,0,0,0,0,0,0,0)';
      BIDIRECTIONAL='TRUE';
      INPUT_LOAD='(-0.01,0.01)';
      OUTPUT_LOAD='(1.0,-1.0)';
    'MGA_DATA13':
      PIN_NUMBER='(0,0,0,0,0,0,T4,0,0,0,0,0,0,0,0,0,0,0,0,0,0,0,0,0,0,0,0,0,0,0,0,0,0,0,0,0,0,0,0,0)';
      BIDIRECTIONAL='TRUE';
      INPUT_LOAD='(-0.01,0.01)';
      OUTPUT_LOAD='(1.0,-1.0)';
    'MGA_DATA3':
      PIN_NUMBER='(0,0,0,0,0,0,G3,0,0,0,0,0,0,0,0,0,0,0,0,0,0,0,0,0,0,0,0,0,0,0,0,0,0,0,0,0,0,0,0,0)';
      BIDIRECTIONAL='TRUE';
      INPUT_LOAD='(-0.01,0.01)';
      OUTPUT_LOAD='(1.0,-1.0)';
    'MGA_CHECK4':
      PIN_NUMBER='(0,0,0,0,0,0,AN2,0,0,0,0,0,0,0,0,0,0,0,0,0,0,0,0,0,0,0,0,0,0,0,0,0,0,0,0,0,0,0,0,0)';
      BIDIRECTIONAL='TRUE';
      INPUT_LOAD='(-0.01,0.01)';
      OUTPUT_LOAD='(1.0,-1.0)';
    'MGB_DQS_H8':
      PIN_NUMBER='(0,0,0,0,0,0,DD4,0,0,0,0,0,0,0,0,0,0,0,0,0,0,0,0,0,0,0,0,0,0,0,0,0,0,0,0,0,0,0,0,0)';
      BIDIRECTIONAL='TRUE';
      INPUT_LOAD='(-0.01,0.01)';
      OUTPUT_LOAD='(1.0,-1.0)';
    'MGB_DATA30':
      PIN_NUMBER='(0,0,0,0,0,0,DE2,0,0,0,0,0,0,0,0,0,0,0,0,0,0,0,0,0,0,0,0,0,0,0,0,0,0,0,0,0,0,0,0,0)';
      BIDIRECTIONAL='TRUE';
      INPUT_LOAD='(-0.01,0.01)';
      OUTPUT_LOAD='(1.0,-1.0)';
    'MGB_DATA4':
      PIN_NUMBER='(0,0,0,0,0,0,CF2,0,0,0,0,0,0,0,0,0,0,0,0,0,0,0,0,0,0,0,0,0,0,0,0,0,0,0,0,0,0,0,0,0)';
      BIDIRECTIONAL='TRUE';
      INPUT_LOAD='(-0.01,0.01)';
      OUTPUT_LOAD='(1.0,-1.0)';
    'MGB1_CS_L1':
      PIN_NUMBER='(0,0,0,0,0,0,BM2,0,0,0,0,0,0,0,0,0,0,0,0,0,0,0,0,0,0,0,0,0,0,0,0,0,0,0,0,0,0,0,0,0)';
      OUTPUT_LOAD='(1.0,-1.0)';
    'MGB0_CS_L1':
      PIN_NUMBER='(0,0,0,0,0,0,BN2,0,0,0,0,0,0,0,0,0,0,0,0,0,0,0,0,0,0,0,0,0,0,0,0,0,0,0,0,0,0,0,0,0)';
      OUTPUT_LOAD='(1.0,-1.0)';
    'MGA_DQS_L1':
      PIN_NUMBER='(0,0,0,0,0,0,P2,0,0,0,0,0,0,0,0,0,0,0,0,0,0,0,0,0,0,0,0,0,0,0,0,0,0,0,0,0,0,0,0,0)';
      BIDIRECTIONAL='TRUE';
      INPUT_LOAD='(-0.01,0.01)';
      OUTPUT_LOAD='(1.0,-1.0)';
    'MGA_DATA25':
      PIN_NUMBER='(0,0,0,0,0,0,AD4,0,0,0,0,0,0,0,0,0,0,0,0,0,0,0,0,0,0,0,0,0,0,0,0,0,0,0,0,0,0,0,0,0)';
      BIDIRECTIONAL='TRUE';
      INPUT_LOAD='(-0.01,0.01)';
      OUTPUT_LOAD='(1.0,-1.0)';
    'MGA_DATA14':
      PIN_NUMBER='(0,0,0,0,0,0,T2,0,0,0,0,0,0,0,0,0,0,0,0,0,0,0,0,0,0,0,0,0,0,0,0,0,0,0,0,0,0,0,0,0)';
      BIDIRECTIONAL='TRUE';
      INPUT_LOAD='(-0.01,0.01)';
      OUTPUT_LOAD='(1.0,-1.0)';
    'MGA_DATA4':
      PIN_NUMBER='(0,0,0,0,0,0,J2,0,0,0,0,0,0,0,0,0,0,0,0,0,0,0,0,0,0,0,0,0,0,0,0,0,0,0,0,0,0,0,0,0)';
      BIDIRECTIONAL='TRUE';
      INPUT_LOAD='(-0.01,0.01)';
      OUTPUT_LOAD='(1.0,-1.0)';
    'MGA_CHECK5':
      PIN_NUMBER='(0,0,0,0,0,0,AP4,0,0,0,0,0,0,0,0,0,0,0,0,0,0,0,0,0,0,0,0,0,0,0,0,0,0,0,0,0,0,0,0,0)';
      BIDIRECTIONAL='TRUE';
      INPUT_LOAD='(-0.01,0.01)';
      OUTPUT_LOAD='(1.0,-1.0)';
    'MGA_CA0':
      PIN_NUMBER='(0,0,0,0,0,0,AW2,0,0,0,0,0,0,0,0,0,0,0,0,0,0,0,0,0,0,0,0,0,0,0,0,0,0,0,0,0,0,0,0,0)';
      OUTPUT_LOAD='(1.0,-1.0)';
    'MGB_DATA31':
      PIN_NUMBER='(0,0,0,0,0,0,DF2,0,0,0,0,0,0,0,0,0,0,0,0,0,0,0,0,0,0,0,0,0,0,0,0,0,0,0,0,0,0,0,0,0)';
      BIDIRECTIONAL='TRUE';
      INPUT_LOAD='(-0.01,0.01)';
      OUTPUT_LOAD='(1.0,-1.0)';
    'MGB_DATA20':
      PIN_NUMBER='(0,0,0,0,0,0,CV2,0,0,0,0,0,0,0,0,0,0,0,0,0,0,0,0,0,0,0,0,0,0,0,0,0,0,0,0,0,0,0,0,0)';
      BIDIRECTIONAL='TRUE';
      INPUT_LOAD='(-0.01,0.01)';
      OUTPUT_LOAD='(1.0,-1.0)';
    'MGB_DATA5':
      PIN_NUMBER='(0,0,0,0,0,0,CG3,0,0,0,0,0,0,0,0,0,0,0,0,0,0,0,0,0,0,0,0,0,0,0,0,0,0,0,0,0,0,0,0,0)';
      BIDIRECTIONAL='TRUE';
      INPUT_LOAD='(-0.01,0.01)';
      OUTPUT_LOAD='(1.0,-1.0)';
    'MGB_CHECK0':
      PIN_NUMBER='(0,0,0,0,0,0,BY2,0,0,0,0,0,0,0,0,0,0,0,0,0,0,0,0,0,0,0,0,0,0,0,0,0,0,0,0,0,0,0,0,0)';
      BIDIRECTIONAL='TRUE';
      INPUT_LOAD='(-0.01,0.01)';
      OUTPUT_LOAD='(1.0,-1.0)';
    'MGB_CA0':
      PIN_NUMBER='(0,0,0,0,0,0,BG3,0,0,0,0,0,0,0,0,0,0,0,0,0,0,0,0,0,0,0,0,0,0,0,0,0,0,0,0,0,0,0,0,0)';
      OUTPUT_LOAD='(1.0,-1.0)';
    'MGA_DQS_L2':
      PIN_NUMBER='(0,0,0,0,0,0,Y2,0,0,0,0,0,0,0,0,0,0,0,0,0,0,0,0,0,0,0,0,0,0,0,0,0,0,0,0,0,0,0,0,0)';
      BIDIRECTIONAL='TRUE';
      INPUT_LOAD='(-0.01,0.01)';
      OUTPUT_LOAD='(1.0,-1.0)';
    'MGA_DATA26':
      PIN_NUMBER='(0,0,0,0,0,0,AD2,0,0,0,0,0,0,0,0,0,0,0,0,0,0,0,0,0,0,0,0,0,0,0,0,0,0,0,0,0,0,0,0,0)';
      BIDIRECTIONAL='TRUE';
      INPUT_LOAD='(-0.01,0.01)';
      OUTPUT_LOAD='(1.0,-1.0)';
    'MGA_DATA15':
      PIN_NUMBER='(0,0,0,0,0,0,U3,0,0,0,0,0,0,0,0,0,0,0,0,0,0,0,0,0,0,0,0,0,0,0,0,0,0,0,0,0,0,0,0,0)';
      BIDIRECTIONAL='TRUE';
      INPUT_LOAD='(-0.01,0.01)';
      OUTPUT_LOAD='(1.0,-1.0)';
    'MGA_DATA5':
      PIN_NUMBER='(0,0,0,0,0,0,K4,0,0,0,0,0,0,0,0,0,0,0,0,0,0,0,0,0,0,0,0,0,0,0,0,0,0,0,0,0,0,0,0,0)';
      BIDIRECTIONAL='TRUE';
      INPUT_LOAD='(-0.01,0.01)';
      OUTPUT_LOAD='(1.0,-1.0)';
    'MGA_CHECK6':
      PIN_NUMBER='(0,0,0,0,0,0,AP2,0,0,0,0,0,0,0,0,0,0,0,0,0,0,0,0,0,0,0,0,0,0,0,0,0,0,0,0,0,0,0,0,0)';
      BIDIRECTIONAL='TRUE';
      INPUT_LOAD='(-0.01,0.01)';
      OUTPUT_LOAD='(1.0,-1.0)';
    'MGA_CA1':
      PIN_NUMBER='(0,0,0,0,0,0,AY2,0,0,0,0,0,0,0,0,0,0,0,0,0,0,0,0,0,0,0,0,0,0,0,0,0,0,0,0,0,0,0,0,0)';
      OUTPUT_LOAD='(1.0,-1.0)';
    'MGB_DATA21':
      PIN_NUMBER='(0,0,0,0,0,0,CW3,0,0,0,0,0,0,0,0,0,0,0,0,0,0,0,0,0,0,0,0,0,0,0,0,0,0,0,0,0,0,0,0,0)';
      BIDIRECTIONAL='TRUE';
      INPUT_LOAD='(-0.01,0.01)';
      OUTPUT_LOAD='(1.0,-1.0)';
    'MGB_DATA10':
      PIN_NUMBER='(0,0,0,0,0,0,CJ2,0,0,0,0,0,0,0,0,0,0,0,0,0,0,0,0,0,0,0,0,0,0,0,0,0,0,0,0,0,0,0,0,0)';
      BIDIRECTIONAL='TRUE';
      INPUT_LOAD='(-0.01,0.01)';
      OUTPUT_LOAD='(1.0,-1.0)';
    'MGB_DATA6':
      PIN_NUMBER='(0,0,0,0,0,0,CG2,0,0,0,0,0,0,0,0,0,0,0,0,0,0,0,0,0,0,0,0,0,0,0,0,0,0,0,0,0,0,0,0,0)';
      BIDIRECTIONAL='TRUE';
      INPUT_LOAD='(-0.01,0.01)';
      OUTPUT_LOAD='(1.0,-1.0)';
    'MGB_CHECK1':
      PIN_NUMBER='(0,0,0,0,0,0,CA3,0,0,0,0,0,0,0,0,0,0,0,0,0,0,0,0,0,0,0,0,0,0,0,0,0,0,0,0,0,0,0,0,0)';
      BIDIRECTIONAL='TRUE';
      INPUT_LOAD='(-0.01,0.01)';
      OUTPUT_LOAD='(1.0,-1.0)';
    'MGB_CA1':
      PIN_NUMBER='(0,0,0,0,0,0,BH4,0,0,0,0,0,0,0,0,0,0,0,0,0,0,0,0,0,0,0,0,0,0,0,0,0,0,0,0,0,0,0,0,0)';
      OUTPUT_LOAD='(1.0,-1.0)';
    'MGA_DQS_L3':
      PIN_NUMBER='(0,0,0,0,0,0,AF2,0,0,0,0,0,0,0,0,0,0,0,0,0,0,0,0,0,0,0,0,0,0,0,0,0,0,0,0,0,0,0,0,0)';
      BIDIRECTIONAL='TRUE';
      INPUT_LOAD='(-0.01,0.01)';
      OUTPUT_LOAD='(1.0,-1.0)';
    'MGA_DATA27':
      PIN_NUMBER='(0,0,0,0,0,0,AE3,0,0,0,0,0,0,0,0,0,0,0,0,0,0,0,0,0,0,0,0,0,0,0,0,0,0,0,0,0,0,0,0,0)';
      BIDIRECTIONAL='TRUE';
      INPUT_LOAD='(-0.01,0.01)';
      OUTPUT_LOAD='(1.0,-1.0)';
    'MGA_DATA16':
      PIN_NUMBER='(0,0,0,0,0,0,U2,0,0,0,0,0,0,0,0,0,0,0,0,0,0,0,0,0,0,0,0,0,0,0,0,0,0,0,0,0,0,0,0,0)';
      BIDIRECTIONAL='TRUE';
      INPUT_LOAD='(-0.01,0.01)';
      OUTPUT_LOAD='(1.0,-1.0)';
    'MGA_DATA6':
      PIN_NUMBER='(0,0,0,0,0,0,K2,0,0,0,0,0,0,0,0,0,0,0,0,0,0,0,0,0,0,0,0,0,0,0,0,0,0,0,0,0,0,0,0,0)';
      BIDIRECTIONAL='TRUE';
      INPUT_LOAD='(-0.01,0.01)';
      OUTPUT_LOAD='(1.0,-1.0)';
    'MGA_CHECK7':
      PIN_NUMBER='(0,0,0,0,0,0,AR3,0,0,0,0,0,0,0,0,0,0,0,0,0,0,0,0,0,0,0,0,0,0,0,0,0,0,0,0,0,0,0,0,0)';
      BIDIRECTIONAL='TRUE';
      INPUT_LOAD='(-0.01,0.01)';
      OUTPUT_LOAD='(1.0,-1.0)';
    'MGA_CA2':
      PIN_NUMBER='(0,0,0,0,0,0,AY4,0,0,0,0,0,0,0,0,0,0,0,0,0,0,0,0,0,0,0,0,0,0,0,0,0,0,0,0,0,0,0,0,0)';
      OUTPUT_LOAD='(1.0,-1.0)';
    'MGA1_RSP_L':
      PIN_NUMBER='(0,0,0,0,0,0,BP4,0,0,0,0,0,0,0,0,0,0,0,0,0,0,0,0,0,0,0,0,0,0,0,0,0,0,0,0,0,0,0,0,0)';
      INPUT_LOAD='(-0.01,0.01)';
    'MGA0_RSP_L':
      PIN_NUMBER='(0,0,0,0,0,0,BN3,0,0,0,0,0,0,0,0,0,0,0,0,0,0,0,0,0,0,0,0,0,0,0,0,0,0,0,0,0,0,0,0,0)';
      INPUT_LOAD='(-0.01,0.01)';
    'MGB_DATA22':
      PIN_NUMBER='(0,0,0,0,0,0,CW2,0,0,0,0,0,0,0,0,0,0,0,0,0,0,0,0,0,0,0,0,0,0,0,0,0,0,0,0,0,0,0,0,0)';
      BIDIRECTIONAL='TRUE';
      INPUT_LOAD='(-0.01,0.01)';
      OUTPUT_LOAD='(1.0,-1.0)';
    'MGB_DATA11':
      PIN_NUMBER='(0,0,0,0,0,0,CK4,0,0,0,0,0,0,0,0,0,0,0,0,0,0,0,0,0,0,0,0,0,0,0,0,0,0,0,0,0,0,0,0,0)';
      BIDIRECTIONAL='TRUE';
      INPUT_LOAD='(-0.01,0.01)';
      OUTPUT_LOAD='(1.0,-1.0)';
    'MGB_DATA7':
      PIN_NUMBER='(0,0,0,0,0,0,CH4,0,0,0,0,0,0,0,0,0,0,0,0,0,0,0,0,0,0,0,0,0,0,0,0,0,0,0,0,0,0,0,0,0)';
      BIDIRECTIONAL='TRUE';
      INPUT_LOAD='(-0.01,0.01)';
      OUTPUT_LOAD='(1.0,-1.0)';
    'MGB_CHECK2':
      PIN_NUMBER='(0,0,0,0,0,0,CA2,0,0,0,0,0,0,0,0,0,0,0,0,0,0,0,0,0,0,0,0,0,0,0,0,0,0,0,0,0,0,0,0,0)';
      BIDIRECTIONAL='TRUE';
      INPUT_LOAD='(-0.01,0.01)';
      OUTPUT_LOAD='(1.0,-1.0)';
    'MGB_CA2':
      PIN_NUMBER='(0,0,0,0,0,0,BH2,0,0,0,0,0,0,0,0,0,0,0,0,0,0,0,0,0,0,0,0,0,0,0,0,0,0,0,0,0,0,0,0,0)';
      OUTPUT_LOAD='(1.0,-1.0)';
    'MGA_DQS_L4':
      PIN_NUMBER='(0,0,0,0,0,0,AM2,0,0,0,0,0,0,0,0,0,0,0,0,0,0,0,0,0,0,0,0,0,0,0,0,0,0,0,0,0,0,0,0,0)';
      BIDIRECTIONAL='TRUE';
      INPUT_LOAD='(-0.01,0.01)';
      OUTPUT_LOAD='(1.0,-1.0)';
    'MGA_DQS_H0':
      PIN_NUMBER='(0,0,0,0,0,0,G2,0,0,0,0,0,0,0,0,0,0,0,0,0,0,0,0,0,0,0,0,0,0,0,0,0,0,0,0,0,0,0,0,0)';
      BIDIRECTIONAL='TRUE';
      INPUT_LOAD='(-0.01,0.01)';
      OUTPUT_LOAD='(1.0,-1.0)';
    'MGA_DATA28':
      PIN_NUMBER='(0,0,0,0,0,0,AG2,0,0,0,0,0,0,0,0,0,0,0,0,0,0,0,0,0,0,0,0,0,0,0,0,0,0,0,0,0,0,0,0,0)';
      BIDIRECTIONAL='TRUE';
      INPUT_LOAD='(-0.01,0.01)';
      OUTPUT_LOAD='(1.0,-1.0)';
    'MGA_DATA17':
      PIN_NUMBER='(0,0,0,0,0,0,V4,0,0,0,0,0,0,0,0,0,0,0,0,0,0,0,0,0,0,0,0,0,0,0,0,0,0,0,0,0,0,0,0,0)';
      BIDIRECTIONAL='TRUE';
      INPUT_LOAD='(-0.01,0.01)';
      OUTPUT_LOAD='(1.0,-1.0)';
    'MGA_DATA7':
      PIN_NUMBER='(0,0,0,0,0,0,L3,0,0,0,0,0,0,0,0,0,0,0,0,0,0,0,0,0,0,0,0,0,0,0,0,0,0,0,0,0,0,0,0,0)';
      BIDIRECTIONAL='TRUE';
      INPUT_LOAD='(-0.01,0.01)';
      OUTPUT_LOAD='(1.0,-1.0)';
    'MGA_CA3':
      PIN_NUMBER='(0,0,0,0,0,0,BA3,0,0,0,0,0,0,0,0,0,0,0,0,0,0,0,0,0,0,0,0,0,0,0,0,0,0,0,0,0,0,0,0,0)';
      OUTPUT_LOAD='(1.0,-1.0)';
    'MGB_DATA23':
      PIN_NUMBER='(0,0,0,0,0,0,CY4,0,0,0,0,0,0,0,0,0,0,0,0,0,0,0,0,0,0,0,0,0,0,0,0,0,0,0,0,0,0,0,0,0)';
      BIDIRECTIONAL='TRUE';
      INPUT_LOAD='(-0.01,0.01)';
      OUTPUT_LOAD='(1.0,-1.0)';
    'MGB_DATA12':
      PIN_NUMBER='(0,0,0,0,0,0,CM2,0,0,0,0,0,0,0,0,0,0,0,0,0,0,0,0,0,0,0,0,0,0,0,0,0,0,0,0,0,0,0,0,0)';
      BIDIRECTIONAL='TRUE';
      INPUT_LOAD='(-0.01,0.01)';
      OUTPUT_LOAD='(1.0,-1.0)';
    'MGB_DATA8':
      PIN_NUMBER='(0,0,0,0,0,0,CH2,0,0,0,0,0,0,0,0,0,0,0,0,0,0,0,0,0,0,0,0,0,0,0,0,0,0,0,0,0,0,0,0,0)';
      BIDIRECTIONAL='TRUE';
      INPUT_LOAD='(-0.01,0.01)';
      OUTPUT_LOAD='(1.0,-1.0)';
    'MGB_CHECK3':
      PIN_NUMBER='(0,0,0,0,0,0,CB4,0,0,0,0,0,0,0,0,0,0,0,0,0,0,0,0,0,0,0,0,0,0,0,0,0,0,0,0,0,0,0,0,0)';
      BIDIRECTIONAL='TRUE';
      INPUT_LOAD='(-0.01,0.01)';
      OUTPUT_LOAD='(1.0,-1.0)';
    'MGB_CA3':
      PIN_NUMBER='(0,0,0,0,0,0,BJ2,0,0,0,0,0,0,0,0,0,0,0,0,0,0,0,0,0,0,0,0,0,0,0,0,0,0,0,0,0,0,0,0,0)';
      OUTPUT_LOAD='(1.0,-1.0)';
    'MGA_DQS_L5':
      PIN_NUMBER='(0,0,0,0,0,0,H4,0,0,0,0,0,0,0,0,0,0,0,0,0,0,0,0,0,0,0,0,0,0,0,0,0,0,0,0,0,0,0,0,0)';
      BIDIRECTIONAL='TRUE';
      INPUT_LOAD='(-0.01,0.01)';
      OUTPUT_LOAD='(1.0,-1.0)';
    'MGA_DQS_H1':
      PIN_NUMBER='(0,0,0,0,0,0,N2,0,0,0,0,0,0,0,0,0,0,0,0,0,0,0,0,0,0,0,0,0,0,0,0,0,0,0,0,0,0,0,0,0)';
      BIDIRECTIONAL='TRUE';
      INPUT_LOAD='(-0.01,0.01)';
      OUTPUT_LOAD='(1.0,-1.0)';
    'MGA_DATA29':
      PIN_NUMBER='(0,0,0,0,0,0,AH4,0,0,0,0,0,0,0,0,0,0,0,0,0,0,0,0,0,0,0,0,0,0,0,0,0,0,0,0,0,0,0,0,0)';
      BIDIRECTIONAL='TRUE';
      INPUT_LOAD='(-0.01,0.01)';
      OUTPUT_LOAD='(1.0,-1.0)';
    'MGA_DATA18':
      PIN_NUMBER='(0,0,0,0,0,0,V2,0,0,0,0,0,0,0,0,0,0,0,0,0,0,0,0,0,0,0,0,0,0,0,0,0,0,0,0,0,0,0,0,0)';
      BIDIRECTIONAL='TRUE';
      INPUT_LOAD='(-0.01,0.01)';
      OUTPUT_LOAD='(1.0,-1.0)';
    'MGA_DATA8':
      PIN_NUMBER='(0,0,0,0,0,0,L2,0,0,0,0,0,0,0,0,0,0,0,0,0,0,0,0,0,0,0,0,0,0,0,0,0,0,0,0,0,0,0,0,0)';
      BIDIRECTIONAL='TRUE';
      INPUT_LOAD='(-0.01,0.01)';
      OUTPUT_LOAD='(1.0,-1.0)';
    'MGA_CA4':
      PIN_NUMBER='(0,0,0,0,0,0,BA2,0,0,0,0,0,0,0,0,0,0,0,0,0,0,0,0,0,0,0,0,0,0,0,0,0,0,0,0,0,0,0,0,0)';
      OUTPUT_LOAD='(1.0,-1.0)';
    'MGB_DQS_L0':
      PIN_NUMBER='(0,0,0,0,0,0,CE2,0,0,0,0,0,0,0,0,0,0,0,0,0,0,0,0,0,0,0,0,0,0,0,0,0,0,0,0,0,0,0,0,0)';
      BIDIRECTIONAL='TRUE';
      INPUT_LOAD='(-0.01,0.01)';
      OUTPUT_LOAD='(1.0,-1.0)';
    'MGB_DATA24':
      PIN_NUMBER='(0,0,0,0,0,0,CY2,0,0,0,0,0,0,0,0,0,0,0,0,0,0,0,0,0,0,0,0,0,0,0,0,0,0,0,0,0,0,0,0,0)';
      BIDIRECTIONAL='TRUE';
      INPUT_LOAD='(-0.01,0.01)';
      OUTPUT_LOAD='(1.0,-1.0)';
    'MGB_DATA13':
      PIN_NUMBER='(0,0,0,0,0,0,CN3,0,0,0,0,0,0,0,0,0,0,0,0,0,0,0,0,0,0,0,0,0,0,0,0,0,0,0,0,0,0,0,0,0)';
      BIDIRECTIONAL='TRUE';
      INPUT_LOAD='(-0.01,0.01)';
      OUTPUT_LOAD='(1.0,-1.0)';
    'MGB_DATA9':
      PIN_NUMBER='(0,0,0,0,0,0,CJ3,0,0,0,0,0,0,0,0,0,0,0,0,0,0,0,0,0,0,0,0,0,0,0,0,0,0,0,0,0,0,0,0,0)';
      BIDIRECTIONAL='TRUE';
      INPUT_LOAD='(-0.01,0.01)';
      OUTPUT_LOAD='(1.0,-1.0)';
    'MGB_CHECK4':
      PIN_NUMBER='(0,0,0,0,0,0,BT2,0,0,0,0,0,0,0,0,0,0,0,0,0,0,0,0,0,0,0,0,0,0,0,0,0,0,0,0,0,0,0,0,0)';
      BIDIRECTIONAL='TRUE';
      INPUT_LOAD='(-0.01,0.01)';
      OUTPUT_LOAD='(1.0,-1.0)';
    'MGB_CA4':
      PIN_NUMBER='(0,0,0,0,0,0,BJ3,0,0,0,0,0,0,0,0,0,0,0,0,0,0,0,0,0,0,0,0,0,0,0,0,0,0,0,0,0,0,0,0,0)';
      OUTPUT_LOAD='(1.0,-1.0)';
    'MGA_DQS_L6':
      PIN_NUMBER='(0,0,0,0,0,0,P4,0,0,0,0,0,0,0,0,0,0,0,0,0,0,0,0,0,0,0,0,0,0,0,0,0,0,0,0,0,0,0,0,0)';
      BIDIRECTIONAL='TRUE';
      INPUT_LOAD='(-0.01,0.01)';
      OUTPUT_LOAD='(1.0,-1.0)';
    'MGA_DQS_H2':
      PIN_NUMBER='(0,0,0,0,0,0,W2,0,0,0,0,0,0,0,0,0,0,0,0,0,0,0,0,0,0,0,0,0,0,0,0,0,0,0,0,0,0,0,0,0)';
      BIDIRECTIONAL='TRUE';
      INPUT_LOAD='(-0.01,0.01)';
      OUTPUT_LOAD='(1.0,-1.0)';
    'MGA_DATA19':
      PIN_NUMBER='(0,0,0,0,0,0,W3,0,0,0,0,0,0,0,0,0,0,0,0,0,0,0,0,0,0,0,0,0,0,0,0,0,0,0,0,0,0,0,0,0)';
      BIDIRECTIONAL='TRUE';
      INPUT_LOAD='(-0.01,0.01)';
      OUTPUT_LOAD='(1.0,-1.0)';
    'MGA_DATA9':
      PIN_NUMBER='(0,0,0,0,0,0,M4,0,0,0,0,0,0,0,0,0,0,0,0,0,0,0,0,0,0,0,0,0,0,0,0,0,0,0,0,0,0,0,0,0)';
      BIDIRECTIONAL='TRUE';
      INPUT_LOAD='(-0.01,0.01)';
      OUTPUT_LOAD='(1.0,-1.0)';
    'MGA_CA5':
      PIN_NUMBER='(0,0,0,0,0,0,BB2,0,0,0,0,0,0,0,0,0,0,0,0,0,0,0,0,0,0,0,0,0,0,0,0,0,0,0,0,0,0,0,0,0)';
      OUTPUT_LOAD='(1.0,-1.0)';
    'MGB_DQS_L1':
      PIN_NUMBER='(0,0,0,0,0,0,CL2,0,0,0,0,0,0,0,0,0,0,0,0,0,0,0,0,0,0,0,0,0,0,0,0,0,0,0,0,0,0,0,0,0)';
      BIDIRECTIONAL='TRUE';
      INPUT_LOAD='(-0.01,0.01)';
      OUTPUT_LOAD='(1.0,-1.0)';
    'MGB_DATA25':
      PIN_NUMBER='(0,0,0,0,0,0,DA3,0,0,0,0,0,0,0,0,0,0,0,0,0,0,0,0,0,0,0,0,0,0,0,0,0,0,0,0,0,0,0,0,0)';
      BIDIRECTIONAL='TRUE';
      INPUT_LOAD='(-0.01,0.01)';
      OUTPUT_LOAD='(1.0,-1.0)';
    'MGB_DATA14':
      PIN_NUMBER='(0,0,0,0,0,0,CN2,0,0,0,0,0,0,0,0,0,0,0,0,0,0,0,0,0,0,0,0,0,0,0,0,0,0,0,0,0,0,0,0,0)';
      BIDIRECTIONAL='TRUE';
      INPUT_LOAD='(-0.01,0.01)';
      OUTPUT_LOAD='(1.0,-1.0)';
    'MGB_CHECK5':
      PIN_NUMBER='(0,0,0,0,0,0,BU3,0,0,0,0,0,0,0,0,0,0,0,0,0,0,0,0,0,0,0,0,0,0,0,0,0,0,0,0,0,0,0,0,0)';
      BIDIRECTIONAL='TRUE';
      INPUT_LOAD='(-0.01,0.01)';
      OUTPUT_LOAD='(1.0,-1.0)';
    'MGB_CA5':
      PIN_NUMBER='(0,0,0,0,0,0,BK4,0,0,0,0,0,0,0,0,0,0,0,0,0,0,0,0,0,0,0,0,0,0,0,0,0,0,0,0,0,0,0,0,0)';
      OUTPUT_LOAD='(1.0,-1.0)';
    'MGA_DQS_L7':
      PIN_NUMBER='(0,0,0,0,0,0,Y4,0,0,0,0,0,0,0,0,0,0,0,0,0,0,0,0,0,0,0,0,0,0,0,0,0,0,0,0,0,0,0,0,0)';
      BIDIRECTIONAL='TRUE';
      INPUT_LOAD='(-0.01,0.01)';
      OUTPUT_LOAD='(1.0,-1.0)';
    'MGA_DQS_H3':
      PIN_NUMBER='(0,0,0,0,0,0,AE2,0,0,0,0,0,0,0,0,0,0,0,0,0,0,0,0,0,0,0,0,0,0,0,0,0,0,0,0,0,0,0,0,0)';
      BIDIRECTIONAL='TRUE';
      INPUT_LOAD='(-0.01,0.01)';
      OUTPUT_LOAD='(1.0,-1.0)';
    'MGA_CA6':
      PIN_NUMBER='(0,0,0,0,0,0,BB4,0,0,0,0,0,0,0,0,0,0,0,0,0,0,0,0,0,0,0,0,0,0,0,0,0,0,0,0,0,0,0,0,0)';
      OUTPUT_LOAD='(1.0,-1.0)';
    'MGB_DQS_L2':
      PIN_NUMBER='(0,0,0,0,0,0,CU2,0,0,0,0,0,0,0,0,0,0,0,0,0,0,0,0,0,0,0,0,0,0,0,0,0,0,0,0,0,0,0,0,0)';
      BIDIRECTIONAL='TRUE';
      INPUT_LOAD='(-0.01,0.01)';
      OUTPUT_LOAD='(1.0,-1.0)';
    'MGB_DATA26':
      PIN_NUMBER='(0,0,0,0,0,0,DA2,0,0,0,0,0,0,0,0,0,0,0,0,0,0,0,0,0,0,0,0,0,0,0,0,0,0,0,0,0,0,0,0,0)';
      BIDIRECTIONAL='TRUE';
      INPUT_LOAD='(-0.01,0.01)';
      OUTPUT_LOAD='(1.0,-1.0)';
    'MGB_DATA15':
      PIN_NUMBER='(0,0,0,0,0,0,CP4,0,0,0,0,0,0,0,0,0,0,0,0,0,0,0,0,0,0,0,0,0,0,0,0,0,0,0,0,0,0,0,0,0)';
      BIDIRECTIONAL='TRUE';
      INPUT_LOAD='(-0.01,0.01)';
      OUTPUT_LOAD='(1.0,-1.0)';
    'MGB_CHECK6':
      PIN_NUMBER='(0,0,0,0,0,0,BU2,0,0,0,0,0,0,0,0,0,0,0,0,0,0,0,0,0,0,0,0,0,0,0,0,0,0,0,0,0,0,0,0,0)';
      BIDIRECTIONAL='TRUE';
      INPUT_LOAD='(-0.01,0.01)';
      OUTPUT_LOAD='(1.0,-1.0)';
    'MGB_CA6':
      PIN_NUMBER='(0,0,0,0,0,0,BK2,0,0,0,0,0,0,0,0,0,0,0,0,0,0,0,0,0,0,0,0,0,0,0,0,0,0,0,0,0,0,0,0,0)';
      OUTPUT_LOAD='(1.0,-1.0)';
    'MGA_DQS_L8':
      PIN_NUMBER='(0,0,0,0,0,0,AF4,0,0,0,0,0,0,0,0,0,0,0,0,0,0,0,0,0,0,0,0,0,0,0,0,0,0,0,0,0,0,0,0,0)';
      BIDIRECTIONAL='TRUE';
      INPUT_LOAD='(-0.01,0.01)';
      OUTPUT_LOAD='(1.0,-1.0)';
    'MGA_DQS_H4':
      PIN_NUMBER='(0,0,0,0,0,0,AL2,0,0,0,0,0,0,0,0,0,0,0,0,0,0,0,0,0,0,0,0,0,0,0,0,0,0,0,0,0,0,0,0,0)';
      BIDIRECTIONAL='TRUE';
      INPUT_LOAD='(-0.01,0.01)';
      OUTPUT_LOAD='(1.0,-1.0)';
    'MGB_DQS_L3':
      PIN_NUMBER='(0,0,0,0,0,0,DC2,0,0,0,0,0,0,0,0,0,0,0,0,0,0,0,0,0,0,0,0,0,0,0,0,0,0,0,0,0,0,0,0,0)';
      BIDIRECTIONAL='TRUE';
      INPUT_LOAD='(-0.01,0.01)';
      OUTPUT_LOAD='(1.0,-1.0)';
    'MGB_DATA27':
      PIN_NUMBER='(0,0,0,0,0,0,DB4,0,0,0,0,0,0,0,0,0,0,0,0,0,0,0,0,0,0,0,0,0,0,0,0,0,0,0,0,0,0,0,0,0)';
      BIDIRECTIONAL='TRUE';
      INPUT_LOAD='(-0.01,0.01)';
      OUTPUT_LOAD='(1.0,-1.0)';
    'MGB_DATA16':
      PIN_NUMBER='(0,0,0,0,0,0,CP2,0,0,0,0,0,0,0,0,0,0,0,0,0,0,0,0,0,0,0,0,0,0,0,0,0,0,0,0,0,0,0,0,0)';
      BIDIRECTIONAL='TRUE';
      INPUT_LOAD='(-0.01,0.01)';
      OUTPUT_LOAD='(1.0,-1.0)';
    'MGB_CHECK7':
      PIN_NUMBER='(0,0,0,0,0,0,BV4,0,0,0,0,0,0,0,0,0,0,0,0,0,0,0,0,0,0,0,0,0,0,0,0,0,0,0,0,0,0,0,0,0)';
      BIDIRECTIONAL='TRUE';
      INPUT_LOAD='(-0.01,0.01)';
      OUTPUT_LOAD='(1.0,-1.0)';
    'MGB1_RSP_L':
      PIN_NUMBER='(0,0,0,0,0,0,BR2,0,0,0,0,0,0,0,0,0,0,0,0,0,0,0,0,0,0,0,0,0,0,0,0,0,0,0,0,0,0,0,0,0)';
      INPUT_LOAD='(-0.01,0.01)';
    'MGB0_RSP_L':
      PIN_NUMBER='(0,0,0,0,0,0,BP2,0,0,0,0,0,0,0,0,0,0,0,0,0,0,0,0,0,0,0,0,0,0,0,0,0,0,0,0,0,0,0,0,0)';
      INPUT_LOAD='(-0.01,0.01)';
    'MGA_DQS_L9':
      PIN_NUMBER='(0,0,0,0,0,0,AM4,0,0,0,0,0,0,0,0,0,0,0,0,0,0,0,0,0,0,0,0,0,0,0,0,0,0,0,0,0,0,0,0,0)';
      BIDIRECTIONAL='TRUE';
      INPUT_LOAD='(-0.01,0.01)';
      OUTPUT_LOAD='(1.0,-1.0)';
    'MGA_DQS_H5':
      PIN_NUMBER='(0,0,0,0,0,0,J3,0,0,0,0,0,0,0,0,0,0,0,0,0,0,0,0,0,0,0,0,0,0,0,0,0,0,0,0,0,0,0,0,0)';
      BIDIRECTIONAL='TRUE';
      INPUT_LOAD='(-0.01,0.01)';
      OUTPUT_LOAD='(1.0,-1.0)';
    'MGB_DQS_L4':
      PIN_NUMBER='(0,0,0,0,0,0,BW3,0,0,0,0,0,0,0,0,0,0,0,0,0,0,0,0,0,0,0,0,0,0,0,0,0,0,0,0,0,0,0,0,0)';
      BIDIRECTIONAL='TRUE';
      INPUT_LOAD='(-0.01,0.01)';
      OUTPUT_LOAD='(1.0,-1.0)';
    'MGB_DQS_H0':
      PIN_NUMBER='(0,0,0,0,0,0,CD2,0,0,0,0,0,0,0,0,0,0,0,0,0,0,0,0,0,0,0,0,0,0,0,0,0,0,0,0,0,0,0,0,0)';
      BIDIRECTIONAL='TRUE';
      INPUT_LOAD='(-0.01,0.01)';
      OUTPUT_LOAD='(1.0,-1.0)';
    'MGB_DATA28':
      PIN_NUMBER='(0,0,0,0,0,0,DD2,0,0,0,0,0,0,0,0,0,0,0,0,0,0,0,0,0,0,0,0,0,0,0,0,0,0,0,0,0,0,0,0,0)';
      BIDIRECTIONAL='TRUE';
      INPUT_LOAD='(-0.01,0.01)';
      OUTPUT_LOAD='(1.0,-1.0)';
    'MGB_DATA17':
      PIN_NUMBER='(0,0,0,0,0,0,CR3,0,0,0,0,0,0,0,0,0,0,0,0,0,0,0,0,0,0,0,0,0,0,0,0,0,0,0,0,0,0,0,0,0)';
      BIDIRECTIONAL='TRUE';
      INPUT_LOAD='(-0.01,0.01)';
      OUTPUT_LOAD='(1.0,-1.0)';
    'MGA_DQS_H6':
      PIN_NUMBER='(0,0,0,0,0,0,R3,0,0,0,0,0,0,0,0,0,0,0,0,0,0,0,0,0,0,0,0,0,0,0,0,0,0,0,0,0,0,0,0,0)';
      BIDIRECTIONAL='TRUE';
      INPUT_LOAD='(-0.01,0.01)';
      OUTPUT_LOAD='(1.0,-1.0)';
    'MGB_DQS_L5':
      PIN_NUMBER='(0,0,0,0,0,0,CE3,0,0,0,0,0,0,0,0,0,0,0,0,0,0,0,0,0,0,0,0,0,0,0,0,0,0,0,0,0,0,0,0,0)';
      BIDIRECTIONAL='TRUE';
      INPUT_LOAD='(-0.01,0.01)';
      OUTPUT_LOAD='(1.0,-1.0)';
    'MGB_DQS_H1':
      PIN_NUMBER='(0,0,0,0,0,0,CK2,0,0,0,0,0,0,0,0,0,0,0,0,0,0,0,0,0,0,0,0,0,0,0,0,0,0,0,0,0,0,0,0,0)';
      BIDIRECTIONAL='TRUE';
      INPUT_LOAD='(-0.01,0.01)';
      OUTPUT_LOAD='(1.0,-1.0)';
    'MGB_DATA29':
      PIN_NUMBER='(0,0,0,0,0,0,DE3,0,0,0,0,0,0,0,0,0,0,0,0,0,0,0,0,0,0,0,0,0,0,0,0,0,0,0,0,0,0,0,0,0)';
      BIDIRECTIONAL='TRUE';
      INPUT_LOAD='(-0.01,0.01)';
      OUTPUT_LOAD='(1.0,-1.0)';
    'MGB_DATA18':
      PIN_NUMBER='(0,0,0,0,0,0,CR2,0,0,0,0,0,0,0,0,0,0,0,0,0,0,0,0,0,0,0,0,0,0,0,0,0,0,0,0,0,0,0,0,0)';
      BIDIRECTIONAL='TRUE';
      INPUT_LOAD='(-0.01,0.01)';
      OUTPUT_LOAD='(1.0,-1.0)';
    'MGA_DQS_H7':
      PIN_NUMBER='(0,0,0,0,0,0,AA3,0,0,0,0,0,0,0,0,0,0,0,0,0,0,0,0,0,0,0,0,0,0,0,0,0,0,0,0,0,0,0,0,0)';
      BIDIRECTIONAL='TRUE';
      INPUT_LOAD='(-0.01,0.01)';
      OUTPUT_LOAD='(1.0,-1.0)';
    'MGA1_CS_L0':
      PIN_NUMBER='(0,0,0,0,0,0,AV2,0,0,0,0,0,0,0,0,0,0,0,0,0,0,0,0,0,0,0,0,0,0,0,0,0,0,0,0,0,0,0,0,0)';
      OUTPUT_LOAD='(1.0,-1.0)';
    'MGA0_CS_L0':
      PIN_NUMBER='(0,0,0,0,0,0,AU2,0,0,0,0,0,0,0,0,0,0,0,0,0,0,0,0,0,0,0,0,0,0,0,0,0,0,0,0,0,0,0,0,0)';
      OUTPUT_LOAD='(1.0,-1.0)';
    'MGB_DQS_L6':
      PIN_NUMBER='(0,0,0,0,0,0,CL3,0,0,0,0,0,0,0,0,0,0,0,0,0,0,0,0,0,0,0,0,0,0,0,0,0,0,0,0,0,0,0,0,0)';
      BIDIRECTIONAL='TRUE';
      INPUT_LOAD='(-0.01,0.01)';
      OUTPUT_LOAD='(1.0,-1.0)';
    'MGB_DQS_H2':
      PIN_NUMBER='(0,0,0,0,0,0,CT2,0,0,0,0,0,0,0,0,0,0,0,0,0,0,0,0,0,0,0,0,0,0,0,0,0,0,0,0,0,0,0,0,0)';
      BIDIRECTIONAL='TRUE';
      INPUT_LOAD='(-0.01,0.01)';
      OUTPUT_LOAD='(1.0,-1.0)';
    'MGB_DATA19':
      PIN_NUMBER='(0,0,0,0,0,0,CT4,0,0,0,0,0,0,0,0,0,0,0,0,0,0,0,0,0,0,0,0,0,0,0,0,0,0,0,0,0,0,0,0,0)';
      BIDIRECTIONAL='TRUE';
      INPUT_LOAD='(-0.01,0.01)';
      OUTPUT_LOAD='(1.0,-1.0)';
    'MGA_DQS_H8':
      PIN_NUMBER='(0,0,0,0,0,0,AG3,0,0,0,0,0,0,0,0,0,0,0,0,0,0,0,0,0,0,0,0,0,0,0,0,0,0,0,0,0,0,0,0,0)';
      BIDIRECTIONAL='TRUE';
      INPUT_LOAD='(-0.01,0.01)';
      OUTPUT_LOAD='(1.0,-1.0)';
    'MGA_DATA30':
      PIN_NUMBER='(0,0,0,0,0,0,AH2,0,0,0,0,0,0,0,0,0,0,0,0,0,0,0,0,0,0,0,0,0,0,0,0,0,0,0,0,0,0,0,0,0)';
      BIDIRECTIONAL='TRUE';
      INPUT_LOAD='(-0.01,0.01)';
      OUTPUT_LOAD='(1.0,-1.0)';
    'MGA1_CS_L1':
      PIN_NUMBER='(0,0,0,0,0,0,AW3,0,0,0,0,0,0,0,0,0,0,0,0,0,0,0,0,0,0,0,0,0,0,0,0,0,0,0,0,0,0,0,0,0)';
      OUTPUT_LOAD='(1.0,-1.0)';
    'MGA0_CS_L1':
      PIN_NUMBER='(0,0,0,0,0,0,AV4,0,0,0,0,0,0,0,0,0,0,0,0,0,0,0,0,0,0,0,0,0,0,0,0,0,0,0,0,0,0,0,0,0)';
      OUTPUT_LOAD='(1.0,-1.0)';
    'MGB_DQS_L7':
      PIN_NUMBER='(0,0,0,0,0,0,CU3,0,0,0,0,0,0,0,0,0,0,0,0,0,0,0,0,0,0,0,0,0,0,0,0,0,0,0,0,0,0,0,0,0)';
      BIDIRECTIONAL='TRUE';
      INPUT_LOAD='(-0.01,0.01)';
      OUTPUT_LOAD='(1.0,-1.0)';
    'MGB_DQS_H3':
      PIN_NUMBER='(0,0,0,0,0,0,DB2,0,0,0,0,0,0,0,0,0,0,0,0,0,0,0,0,0,0,0,0,0,0,0,0,0,0,0,0,0,0,0,0,0)';
      BIDIRECTIONAL='TRUE';
      INPUT_LOAD='(-0.01,0.01)';
      OUTPUT_LOAD='(1.0,-1.0)';
    'MGA_DQS_H9':
      PIN_NUMBER='(0,0,0,0,0,0,AN3,0,0,0,0,0,0,0,0,0,0,0,0,0,0,0,0,0,0,0,0,0,0,0,0,0,0,0,0,0,0,0,0,0)';
      BIDIRECTIONAL='TRUE';
      INPUT_LOAD='(-0.01,0.01)';
      OUTPUT_LOAD='(1.0,-1.0)';
    'MGA_DATA31':
      PIN_NUMBER='(0,0,0,0,0,0,AJ3,0,0,0,0,0,0,0,0,0,0,0,0,0,0,0,0,0,0,0,0,0,0,0,0,0,0,0,0,0,0,0,0,0)';
      BIDIRECTIONAL='TRUE';
      INPUT_LOAD='(-0.01,0.01)';
      OUTPUT_LOAD='(1.0,-1.0)';
    'MGA_DATA20':
      PIN_NUMBER='(0,0,0,0,0,0,AA2,0,0,0,0,0,0,0,0,0,0,0,0,0,0,0,0,0,0,0,0,0,0,0,0,0,0,0,0,0,0,0,0,0)';
      BIDIRECTIONAL='TRUE';
      INPUT_LOAD='(-0.01,0.01)';
      OUTPUT_LOAD='(1.0,-1.0)';
    'MGA_CHECK0':
      PIN_NUMBER='(0,0,0,0,0,0,AJ2,0,0,0,0,0,0,0,0,0,0,0,0,0,0,0,0,0,0,0,0,0,0,0,0,0,0,0,0,0,0,0,0,0)';
      BIDIRECTIONAL='TRUE';
      INPUT_LOAD='(-0.01,0.01)';
      OUTPUT_LOAD='(1.0,-1.0)';
    'MGB_DQS_L8':
      PIN_NUMBER='(0,0,0,0,0,0,DC3,0,0,0,0,0,0,0,0,0,0,0,0,0,0,0,0,0,0,0,0,0,0,0,0,0,0,0,0,0,0,0,0,0)';
      BIDIRECTIONAL='TRUE';
      INPUT_LOAD='(-0.01,0.01)';
      OUTPUT_LOAD='(1.0,-1.0)';
    'MGB_DQS_H4':
      PIN_NUMBER='(0,0,0,0,0,0,BY4,0,0,0,0,0,0,0,0,0,0,0,0,0,0,0,0,0,0,0,0,0,0,0,0,0,0,0,0,0,0,0,0,0)';
      BIDIRECTIONAL='TRUE';
      INPUT_LOAD='(-0.01,0.01)';
      OUTPUT_LOAD='(1.0,-1.0)';
    'MGB_DATA0':
      PIN_NUMBER='(0,0,0,0,0,0,CB2,0,0,0,0,0,0,0,0,0,0,0,0,0,0,0,0,0,0,0,0,0,0,0,0,0,0,0,0,0,0,0,0,0)';
      BIDIRECTIONAL='TRUE';
      INPUT_LOAD='(-0.01,0.01)';
      OUTPUT_LOAD='(1.0,-1.0)';
    'MGA_DATA21':
      PIN_NUMBER='(0,0,0,0,0,0,AB4,0,0,0,0,0,0,0,0,0,0,0,0,0,0,0,0,0,0,0,0,0,0,0,0,0,0,0,0,0,0,0,0,0)';
      BIDIRECTIONAL='TRUE';
      INPUT_LOAD='(-0.01,0.01)';
      OUTPUT_LOAD='(1.0,-1.0)';
    'MGA_DATA10':
      PIN_NUMBER='(0,0,0,0,0,0,M2,0,0,0,0,0,0,0,0,0,0,0,0,0,0,0,0,0,0,0,0,0,0,0,0,0,0,0,0,0,0,0,0,0)';
      BIDIRECTIONAL='TRUE';
      INPUT_LOAD='(-0.01,0.01)';
      OUTPUT_LOAD='(1.0,-1.0)';
    'MGA_DATA0':
      PIN_NUMBER='(0,0,0,0,0,0,E2,0,0,0,0,0,0,0,0,0,0,0,0,0,0,0,0,0,0,0,0,0,0,0,0,0,0,0,0,0,0,0,0,0)';
      BIDIRECTIONAL='TRUE';
      INPUT_LOAD='(-0.01,0.01)';
      OUTPUT_LOAD='(1.0,-1.0)';
    'MGA_CHECK1':
      PIN_NUMBER='(0,0,0,0,0,0,AK4,0,0,0,0,0,0,0,0,0,0,0,0,0,0,0,0,0,0,0,0,0,0,0,0,0,0,0,0,0,0,0,0,0)';
      BIDIRECTIONAL='TRUE';
      INPUT_LOAD='(-0.01,0.01)';
      OUTPUT_LOAD='(1.0,-1.0)';
    'MGB_PAR':
      PIN_NUMBER='(0,0,0,0,0,0,BL3,0,0,0,0,0,0,0,0,0,0,0,0,0,0,0,0,0,0,0,0,0,0,0,0,0,0,0,0,0,0,0,0,0)';
      OUTPUT_LOAD='(1.0,-1.0)';
    'MGB_DQS_H9':
      PIN_NUMBER='(0,0,0,0,0,0,BV2,0,0,0,0,0,0,0,0,0,0,0,0,0,0,0,0,0,0,0,0,0,0,0,0,0,0,0,0,0,0,0,0,0)';
      BIDIRECTIONAL='TRUE';
      INPUT_LOAD='(-0.01,0.01)';
      OUTPUT_LOAD='(1.0,-1.0)';
    'MGA_PAR':
      PIN_NUMBER='(0,0,0,0,0,0,BC3,0,0,0,0,0,0,0,0,0,0,0,0,0,0,0,0,0,0,0,0,0,0,0,0,0,0,0,0,0,0,0,0,0)';
      OUTPUT_LOAD='(1.0,-1.0)';
    'MG0_CLK_H':
      PIN_NUMBER='(0,0,0,0,0,0,BC2,0,0,0,0,0,0,0,0,0,0,0,0,0,0,0,0,0,0,0,0,0,0,0,0,0,0,0,0,0,0,0,0,0)';
      OUTPUT_LOAD='(1.0,-1.0)';
    'MG0_CLK_L':
      PIN_NUMBER='(0,0,0,0,0,0,BD2,0,0,0,0,0,0,0,0,0,0,0,0,0,0,0,0,0,0,0,0,0,0,0,0,0,0,0,0,0,0,0,0,0)';
      OUTPUT_LOAD='(1.0,-1.0)';
    'MG1_CLK_H':
      PIN_NUMBER='(0,0,0,0,0,0,BF2,0,0,0,0,0,0,0,0,0,0,0,0,0,0,0,0,0,0,0,0,0,0,0,0,0,0,0,0,0,0,0,0,0)';
      OUTPUT_LOAD='(1.0,-1.0)';
    'MG1_CLK_L':
      PIN_NUMBER='(0,0,0,0,0,0,BG2,0,0,0,0,0,0,0,0,0,0,0,0,0,0,0,0,0,0,0,0,0,0,0,0,0,0,0,0,0,0,0,0,0)';
      OUTPUT_LOAD='(1.0,-1.0)';
    'TEST39G':
      PIN_NUMBER='(0,0,0,0,0,0,BF4,0,0,0,0,0,0,0,0,0,0,0,0,0,0,0,0,0,0,0,0,0,0,0,0,0,0,0,0,0,0,0,0,0)';
      OUTPUT_LOAD='(1.0,-1.0)';
    'MH_ALERT_L':
      PIN_NUMBER='(0,0,0,0,0,0,0,AT14,0,0,0,0,0,0,0,0,0,0,0,0,0,0,0,0,0,0,0,0,0,0,0,0,0,0,0,0,0,0,0,0)';
      INPUT_LOAD='(-0.01,0.01)';
    'MH_RESET_L':
      PIN_NUMBER='(0,0,0,0,0,0,0,AU14,0,0,0,0,0,0,0,0,0,0,0,0,0,0,0,0,0,0,0,0,0,0,0,0,0,0,0,0,0,0,0,0)';
      OUTPUT_LOAD='(1.0,-1.0)';
    'MHB_DATA31':
      PIN_NUMBER='(0,0,0,0,0,0,0,DF14,0,0,0,0,0,0,0,0,0,0,0,0,0,0,0,0,0,0,0,0,0,0,0,0,0,0,0,0,0,0,0,0)';
      BIDIRECTIONAL='TRUE';
      INPUT_LOAD='(-0.01,0.01)';
      OUTPUT_LOAD='(1.0,-1.0)';
    'MHB_DATA20':
      PIN_NUMBER='(0,0,0,0,0,0,0,CV13,0,0,0,0,0,0,0,0,0,0,0,0,0,0,0,0,0,0,0,0,0,0,0,0,0,0,0,0,0,0,0,0)';
      BIDIRECTIONAL='TRUE';
      INPUT_LOAD='(-0.01,0.01)';
      OUTPUT_LOAD='(1.0,-1.0)';
    'MHB_CHECK0':
      PIN_NUMBER='(0,0,0,0,0,0,0,BY13,0,0,0,0,0,0,0,0,0,0,0,0,0,0,0,0,0,0,0,0,0,0,0,0,0,0,0,0,0,0,0,0)';
      BIDIRECTIONAL='TRUE';
      INPUT_LOAD='(-0.01,0.01)';
      OUTPUT_LOAD='(1.0,-1.0)';
    'MHB1_CS_L1':
      PIN_NUMBER='(0,0,0,0,0,0,0,BM13,0,0,0,0,0,0,0,0,0,0,0,0,0,0,0,0,0,0,0,0,0,0,0,0,0,0,0,0,0,0,0,0)';
      OUTPUT_LOAD='(1.0,-1.0)';
    'MHA_DQS_L2':
      PIN_NUMBER='(0,0,0,0,0,0,0,Y13,0,0,0,0,0,0,0,0,0,0,0,0,0,0,0,0,0,0,0,0,0,0,0,0,0,0,0,0,0,0,0,0)';
      BIDIRECTIONAL='TRUE';
      INPUT_LOAD='(-0.01,0.01)';
      OUTPUT_LOAD='(1.0,-1.0)';
    'MHA_DATA26':
      PIN_NUMBER='(0,0,0,0,0,0,0,AD13,0,0,0,0,0,0,0,0,0,0,0,0,0,0,0,0,0,0,0,0,0,0,0,0,0,0,0,0,0,0,0,0)';
      BIDIRECTIONAL='TRUE';
      INPUT_LOAD='(-0.01,0.01)';
      OUTPUT_LOAD='(1.0,-1.0)';
    'MHA_DATA15':
      PIN_NUMBER='(0,0,0,0,0,0,0,U14,0,0,0,0,0,0,0,0,0,0,0,0,0,0,0,0,0,0,0,0,0,0,0,0,0,0,0,0,0,0,0,0)';
      BIDIRECTIONAL='TRUE';
      INPUT_LOAD='(-0.01,0.01)';
      OUTPUT_LOAD='(1.0,-1.0)';
    'MHA_CHECK6':
      PIN_NUMBER='(0,0,0,0,0,0,0,AP13,0,0,0,0,0,0,0,0,0,0,0,0,0,0,0,0,0,0,0,0,0,0,0,0,0,0,0,0,0,0,0,0)';
      BIDIRECTIONAL='TRUE';
      INPUT_LOAD='(-0.01,0.01)';
      OUTPUT_LOAD='(1.0,-1.0)';
    'MHB_DATA21':
      PIN_NUMBER='(0,0,0,0,0,0,0,CW14,0,0,0,0,0,0,0,0,0,0,0,0,0,0,0,0,0,0,0,0,0,0,0,0,0,0,0,0,0,0,0,0)';
      BIDIRECTIONAL='TRUE';
      INPUT_LOAD='(-0.01,0.01)';
      OUTPUT_LOAD='(1.0,-1.0)';
    'MHB_DATA10':
      PIN_NUMBER='(0,0,0,0,0,0,0,CJ12,0,0,0,0,0,0,0,0,0,0,0,0,0,0,0,0,0,0,0,0,0,0,0,0,0,0,0,0,0,0,0,0)';
      BIDIRECTIONAL='TRUE';
      INPUT_LOAD='(-0.01,0.01)';
      OUTPUT_LOAD='(1.0,-1.0)';
    'MHB_CHECK1':
      PIN_NUMBER='(0,0,0,0,0,0,0,CA14,0,0,0,0,0,0,0,0,0,0,0,0,0,0,0,0,0,0,0,0,0,0,0,0,0,0,0,0,0,0,0,0)';
      BIDIRECTIONAL='TRUE';
      INPUT_LOAD='(-0.01,0.01)';
      OUTPUT_LOAD='(1.0,-1.0)';
    'MHA_DQS_L3':
      PIN_NUMBER='(0,0,0,0,0,0,0,AF13,0,0,0,0,0,0,0,0,0,0,0,0,0,0,0,0,0,0,0,0,0,0,0,0,0,0,0,0,0,0,0,0)';
      BIDIRECTIONAL='TRUE';
      INPUT_LOAD='(-0.01,0.01)';
      OUTPUT_LOAD='(1.0,-1.0)';
    'MHA_DATA27':
      PIN_NUMBER='(0,0,0,0,0,0,0,AE14,0,0,0,0,0,0,0,0,0,0,0,0,0,0,0,0,0,0,0,0,0,0,0,0,0,0,0,0,0,0,0,0)';
      BIDIRECTIONAL='TRUE';
      INPUT_LOAD='(-0.01,0.01)';
      OUTPUT_LOAD='(1.0,-1.0)';
    'MHA_DATA16':
      PIN_NUMBER='(0,0,0,0,0,0,0,U12,0,0,0,0,0,0,0,0,0,0,0,0,0,0,0,0,0,0,0,0,0,0,0,0,0,0,0,0,0,0,0,0)';
      BIDIRECTIONAL='TRUE';
      INPUT_LOAD='(-0.01,0.01)';
      OUTPUT_LOAD='(1.0,-1.0)';
    'MHA_CHECK7':
      PIN_NUMBER='(0,0,0,0,0,0,0,AR14,0,0,0,0,0,0,0,0,0,0,0,0,0,0,0,0,0,0,0,0,0,0,0,0,0,0,0,0,0,0,0,0)';
      BIDIRECTIONAL='TRUE';
      INPUT_LOAD='(-0.01,0.01)';
      OUTPUT_LOAD='(1.0,-1.0)';
    'MHA0_RSP_L':
      PIN_NUMBER='(0,0,0,0,0,0,0,BN14,0,0,0,0,0,0,0,0,0,0,0,0,0,0,0,0,0,0,0,0,0,0,0,0,0,0,0,0,0,0,0,0)';
      INPUT_LOAD='(-0.01,0.01)';
    'MHB_DATA22':
      PIN_NUMBER='(0,0,0,0,0,0,0,CW12,0,0,0,0,0,0,0,0,0,0,0,0,0,0,0,0,0,0,0,0,0,0,0,0,0,0,0,0,0,0,0,0)';
      BIDIRECTIONAL='TRUE';
      INPUT_LOAD='(-0.01,0.01)';
      OUTPUT_LOAD='(1.0,-1.0)';
    'MHB_DATA11':
      PIN_NUMBER='(0,0,0,0,0,0,0,CK14,0,0,0,0,0,0,0,0,0,0,0,0,0,0,0,0,0,0,0,0,0,0,0,0,0,0,0,0,0,0,0,0)';
      BIDIRECTIONAL='TRUE';
      INPUT_LOAD='(-0.01,0.01)';
      OUTPUT_LOAD='(1.0,-1.0)';
    'MHB_CHECK2':
      PIN_NUMBER='(0,0,0,0,0,0,0,CA12,0,0,0,0,0,0,0,0,0,0,0,0,0,0,0,0,0,0,0,0,0,0,0,0,0,0,0,0,0,0,0,0)';
      BIDIRECTIONAL='TRUE';
      INPUT_LOAD='(-0.01,0.01)';
      OUTPUT_LOAD='(1.0,-1.0)';
    'MHA_DQS_L4':
      PIN_NUMBER='(0,0,0,0,0,0,0,AM13,0,0,0,0,0,0,0,0,0,0,0,0,0,0,0,0,0,0,0,0,0,0,0,0,0,0,0,0,0,0,0,0)';
      BIDIRECTIONAL='TRUE';
      INPUT_LOAD='(-0.01,0.01)';
      OUTPUT_LOAD='(1.0,-1.0)';
    'MHA_DQS_H0':
      PIN_NUMBER='(0,0,0,0,0,0,0,G12,0,0,0,0,0,0,0,0,0,0,0,0,0,0,0,0,0,0,0,0,0,0,0,0,0,0,0,0,0,0,0,0)';
      BIDIRECTIONAL='TRUE';
      INPUT_LOAD='(-0.01,0.01)';
      OUTPUT_LOAD='(1.0,-1.0)';
    'MHA_DATA28':
      PIN_NUMBER='(0,0,0,0,0,0,0,AG12,0,0,0,0,0,0,0,0,0,0,0,0,0,0,0,0,0,0,0,0,0,0,0,0,0,0,0,0,0,0,0,0)';
      BIDIRECTIONAL='TRUE';
      INPUT_LOAD='(-0.01,0.01)';
      OUTPUT_LOAD='(1.0,-1.0)';
    'MHA_DATA17':
      PIN_NUMBER='(0,0,0,0,0,0,0,V14,0,0,0,0,0,0,0,0,0,0,0,0,0,0,0,0,0,0,0,0,0,0,0,0,0,0,0,0,0,0,0,0)';
      BIDIRECTIONAL='TRUE';
      INPUT_LOAD='(-0.01,0.01)';
      OUTPUT_LOAD='(1.0,-1.0)';
    'MHA_CA0':
      PIN_NUMBER='(0,0,0,0,0,0,0,AW12,0,0,0,0,0,0,0,0,0,0,0,0,0,0,0,0,0,0,0,0,0,0,0,0,0,0,0,0,0,0,0,0)';
      OUTPUT_LOAD='(1.0,-1.0)';
    'MHA1_RSP_L':
      PIN_NUMBER='(0,0,0,0,0,0,0,BP14,0,0,0,0,0,0,0,0,0,0,0,0,0,0,0,0,0,0,0,0,0,0,0,0,0,0,0,0,0,0,0,0)';
      INPUT_LOAD='(-0.01,0.01)';
    'MHB_DATA23':
      PIN_NUMBER='(0,0,0,0,0,0,0,CY14,0,0,0,0,0,0,0,0,0,0,0,0,0,0,0,0,0,0,0,0,0,0,0,0,0,0,0,0,0,0,0,0)';
      BIDIRECTIONAL='TRUE';
      INPUT_LOAD='(-0.01,0.01)';
      OUTPUT_LOAD='(1.0,-1.0)';
    'MHB_DATA12':
      PIN_NUMBER='(0,0,0,0,0,0,0,CM13,0,0,0,0,0,0,0,0,0,0,0,0,0,0,0,0,0,0,0,0,0,0,0,0,0,0,0,0,0,0,0,0)';
      BIDIRECTIONAL='TRUE';
      INPUT_LOAD='(-0.01,0.01)';
      OUTPUT_LOAD='(1.0,-1.0)';
    'MHB_CHECK3':
      PIN_NUMBER='(0,0,0,0,0,0,0,CB14,0,0,0,0,0,0,0,0,0,0,0,0,0,0,0,0,0,0,0,0,0,0,0,0,0,0,0,0,0,0,0,0)';
      BIDIRECTIONAL='TRUE';
      INPUT_LOAD='(-0.01,0.01)';
      OUTPUT_LOAD='(1.0,-1.0)';
    'MHB_CA0':
      PIN_NUMBER='(0,0,0,0,0,0,0,BG14,0,0,0,0,0,0,0,0,0,0,0,0,0,0,0,0,0,0,0,0,0,0,0,0,0,0,0,0,0,0,0,0)';
      OUTPUT_LOAD='(1.0,-1.0)';
    'MHA_DQS_L5':
      PIN_NUMBER='(0,0,0,0,0,0,0,H14,0,0,0,0,0,0,0,0,0,0,0,0,0,0,0,0,0,0,0,0,0,0,0,0,0,0,0,0,0,0,0,0)';
      BIDIRECTIONAL='TRUE';
      INPUT_LOAD='(-0.01,0.01)';
      OUTPUT_LOAD='(1.0,-1.0)';
    'MHA_DQS_H1':
      PIN_NUMBER='(0,0,0,0,0,0,0,N12,0,0,0,0,0,0,0,0,0,0,0,0,0,0,0,0,0,0,0,0,0,0,0,0,0,0,0,0,0,0,0,0)';
      BIDIRECTIONAL='TRUE';
      INPUT_LOAD='(-0.01,0.01)';
      OUTPUT_LOAD='(1.0,-1.0)';
    'MHA_DATA29':
      PIN_NUMBER='(0,0,0,0,0,0,0,AH14,0,0,0,0,0,0,0,0,0,0,0,0,0,0,0,0,0,0,0,0,0,0,0,0,0,0,0,0,0,0,0,0)';
      BIDIRECTIONAL='TRUE';
      INPUT_LOAD='(-0.01,0.01)';
      OUTPUT_LOAD='(1.0,-1.0)';
    'MHA_DATA18':
      PIN_NUMBER='(0,0,0,0,0,0,0,V13,0,0,0,0,0,0,0,0,0,0,0,0,0,0,0,0,0,0,0,0,0,0,0,0,0,0,0,0,0,0,0,0)';
      BIDIRECTIONAL='TRUE';
      INPUT_LOAD='(-0.01,0.01)';
      OUTPUT_LOAD='(1.0,-1.0)';
    'MHA_CA1':
      PIN_NUMBER='(0,0,0,0,0,0,0,AY13,0,0,0,0,0,0,0,0,0,0,0,0,0,0,0,0,0,0,0,0,0,0,0,0,0,0,0,0,0,0,0,0)';
      OUTPUT_LOAD='(1.0,-1.0)';
    'MHB_DQS_L0':
      PIN_NUMBER='(0,0,0,0,0,0,0,CE12,0,0,0,0,0,0,0,0,0,0,0,0,0,0,0,0,0,0,0,0,0,0,0,0,0,0,0,0,0,0,0,0)';
      BIDIRECTIONAL='TRUE';
      INPUT_LOAD='(-0.01,0.01)';
      OUTPUT_LOAD='(1.0,-1.0)';
    'MHB_DATA24':
      PIN_NUMBER='(0,0,0,0,0,0,0,CY13,0,0,0,0,0,0,0,0,0,0,0,0,0,0,0,0,0,0,0,0,0,0,0,0,0,0,0,0,0,0,0,0)';
      BIDIRECTIONAL='TRUE';
      INPUT_LOAD='(-0.01,0.01)';
      OUTPUT_LOAD='(1.0,-1.0)';
    'MHB_DATA13':
      PIN_NUMBER='(0,0,0,0,0,0,0,CN14,0,0,0,0,0,0,0,0,0,0,0,0,0,0,0,0,0,0,0,0,0,0,0,0,0,0,0,0,0,0,0,0)';
      BIDIRECTIONAL='TRUE';
      INPUT_LOAD='(-0.01,0.01)';
      OUTPUT_LOAD='(1.0,-1.0)';
    'MHB_CHECK4':
      PIN_NUMBER='(0,0,0,0,0,0,0,BT13,0,0,0,0,0,0,0,0,0,0,0,0,0,0,0,0,0,0,0,0,0,0,0,0,0,0,0,0,0,0,0,0)';
      BIDIRECTIONAL='TRUE';
      INPUT_LOAD='(-0.01,0.01)';
      OUTPUT_LOAD='(1.0,-1.0)';
    'MHB_CA1':
      PIN_NUMBER='(0,0,0,0,0,0,0,BH14,0,0,0,0,0,0,0,0,0,0,0,0,0,0,0,0,0,0,0,0,0,0,0,0,0,0,0,0,0,0,0,0)';
      OUTPUT_LOAD='(1.0,-1.0)';
    'MHA_DQS_L6':
      PIN_NUMBER='(0,0,0,0,0,0,0,P14,0,0,0,0,0,0,0,0,0,0,0,0,0,0,0,0,0,0,0,0,0,0,0,0,0,0,0,0,0,0,0,0)';
      BIDIRECTIONAL='TRUE';
      INPUT_LOAD='(-0.01,0.01)';
      OUTPUT_LOAD='(1.0,-1.0)';
    'MHA_DQS_H2':
      PIN_NUMBER='(0,0,0,0,0,0,0,W12,0,0,0,0,0,0,0,0,0,0,0,0,0,0,0,0,0,0,0,0,0,0,0,0,0,0,0,0,0,0,0,0)';
      BIDIRECTIONAL='TRUE';
      INPUT_LOAD='(-0.01,0.01)';
      OUTPUT_LOAD='(1.0,-1.0)';
    'MHA_DATA19':
      PIN_NUMBER='(0,0,0,0,0,0,0,W14,0,0,0,0,0,0,0,0,0,0,0,0,0,0,0,0,0,0,0,0,0,0,0,0,0,0,0,0,0,0,0,0)';
      BIDIRECTIONAL='TRUE';
      INPUT_LOAD='(-0.01,0.01)';
      OUTPUT_LOAD='(1.0,-1.0)';
    'MHA_CA2':
      PIN_NUMBER='(0,0,0,0,0,0,0,AY14,0,0,0,0,0,0,0,0,0,0,0,0,0,0,0,0,0,0,0,0,0,0,0,0,0,0,0,0,0,0,0,0)';
      OUTPUT_LOAD='(1.0,-1.0)';
    'MHB_DQS_L1':
      PIN_NUMBER='(0,0,0,0,0,0,0,CL12,0,0,0,0,0,0,0,0,0,0,0,0,0,0,0,0,0,0,0,0,0,0,0,0,0,0,0,0,0,0,0,0)';
      BIDIRECTIONAL='TRUE';
      INPUT_LOAD='(-0.01,0.01)';
      OUTPUT_LOAD='(1.0,-1.0)';
    'MHB_DATA25':
      PIN_NUMBER='(0,0,0,0,0,0,0,DA14,0,0,0,0,0,0,0,0,0,0,0,0,0,0,0,0,0,0,0,0,0,0,0,0,0,0,0,0,0,0,0,0)';
      BIDIRECTIONAL='TRUE';
      INPUT_LOAD='(-0.01,0.01)';
      OUTPUT_LOAD='(1.0,-1.0)';
    'MHB_DATA14':
      PIN_NUMBER='(0,0,0,0,0,0,0,CN12,0,0,0,0,0,0,0,0,0,0,0,0,0,0,0,0,0,0,0,0,0,0,0,0,0,0,0,0,0,0,0,0)';
      BIDIRECTIONAL='TRUE';
      INPUT_LOAD='(-0.01,0.01)';
      OUTPUT_LOAD='(1.0,-1.0)';
    'MHB_DATA0':
      PIN_NUMBER='(0,0,0,0,0,0,0,CB13,0,0,0,0,0,0,0,0,0,0,0,0,0,0,0,0,0,0,0,0,0,0,0,0,0,0,0,0,0,0,0,0)';
      BIDIRECTIONAL='TRUE';
      INPUT_LOAD='(-0.01,0.01)';
      OUTPUT_LOAD='(1.0,-1.0)';
    'MHB_CHECK5':
      PIN_NUMBER='(0,0,0,0,0,0,0,BU14,0,0,0,0,0,0,0,0,0,0,0,0,0,0,0,0,0,0,0,0,0,0,0,0,0,0,0,0,0,0,0,0)';
      BIDIRECTIONAL='TRUE';
      INPUT_LOAD='(-0.01,0.01)';
      OUTPUT_LOAD='(1.0,-1.0)';
    'MHB_CA2':
      PIN_NUMBER='(0,0,0,0,0,0,0,BH13,0,0,0,0,0,0,0,0,0,0,0,0,0,0,0,0,0,0,0,0,0,0,0,0,0,0,0,0,0,0,0,0)';
      OUTPUT_LOAD='(1.0,-1.0)';
    'MHA_DQS_L7':
      PIN_NUMBER='(0,0,0,0,0,0,0,Y14,0,0,0,0,0,0,0,0,0,0,0,0,0,0,0,0,0,0,0,0,0,0,0,0,0,0,0,0,0,0,0,0)';
      BIDIRECTIONAL='TRUE';
      INPUT_LOAD='(-0.01,0.01)';
      OUTPUT_LOAD='(1.0,-1.0)';
    'MHA_DQS_H3':
      PIN_NUMBER='(0,0,0,0,0,0,0,AE12,0,0,0,0,0,0,0,0,0,0,0,0,0,0,0,0,0,0,0,0,0,0,0,0,0,0,0,0,0,0,0,0)';
      BIDIRECTIONAL='TRUE';
      INPUT_LOAD='(-0.01,0.01)';
      OUTPUT_LOAD='(1.0,-1.0)';
    'MHA_DATA0':
      PIN_NUMBER='(0,0,0,0,0,0,0,E12,0,0,0,0,0,0,0,0,0,0,0,0,0,0,0,0,0,0,0,0,0,0,0,0,0,0,0,0,0,0,0,0)';
      BIDIRECTIONAL='TRUE';
      INPUT_LOAD='(-0.01,0.01)';
      OUTPUT_LOAD='(1.0,-1.0)';
    'MHA_CA3':
      PIN_NUMBER='(0,0,0,0,0,0,0,BA14,0,0,0,0,0,0,0,0,0,0,0,0,0,0,0,0,0,0,0,0,0,0,0,0,0,0,0,0,0,0,0,0)';
      OUTPUT_LOAD='(1.0,-1.0)';
    'MHB_DQS_L2':
      PIN_NUMBER='(0,0,0,0,0,0,0,CU12,0,0,0,0,0,0,0,0,0,0,0,0,0,0,0,0,0,0,0,0,0,0,0,0,0,0,0,0,0,0,0,0)';
      BIDIRECTIONAL='TRUE';
      INPUT_LOAD='(-0.01,0.01)';
      OUTPUT_LOAD='(1.0,-1.0)';
    'MHB_DATA26':
      PIN_NUMBER='(0,0,0,0,0,0,0,DA12,0,0,0,0,0,0,0,0,0,0,0,0,0,0,0,0,0,0,0,0,0,0,0,0,0,0,0,0,0,0,0,0)';
      BIDIRECTIONAL='TRUE';
      INPUT_LOAD='(-0.01,0.01)';
      OUTPUT_LOAD='(1.0,-1.0)';
    'MHB_DATA15':
      PIN_NUMBER='(0,0,0,0,0,0,0,CP14,0,0,0,0,0,0,0,0,0,0,0,0,0,0,0,0,0,0,0,0,0,0,0,0,0,0,0,0,0,0,0,0)';
      BIDIRECTIONAL='TRUE';
      INPUT_LOAD='(-0.01,0.01)';
      OUTPUT_LOAD='(1.0,-1.0)';
    'MHB_DATA1':
      PIN_NUMBER='(0,0,0,0,0,0,0,CC14,0,0,0,0,0,0,0,0,0,0,0,0,0,0,0,0,0,0,0,0,0,0,0,0,0,0,0,0,0,0,0,0)';
      BIDIRECTIONAL='TRUE';
      INPUT_LOAD='(-0.01,0.01)';
      OUTPUT_LOAD='(1.0,-1.0)';
    'MHB_CHECK6':
      PIN_NUMBER='(0,0,0,0,0,0,0,BU12,0,0,0,0,0,0,0,0,0,0,0,0,0,0,0,0,0,0,0,0,0,0,0,0,0,0,0,0,0,0,0,0)';
      BIDIRECTIONAL='TRUE';
      INPUT_LOAD='(-0.01,0.01)';
      OUTPUT_LOAD='(1.0,-1.0)';
    'MHB_CA3':
      PIN_NUMBER='(0,0,0,0,0,0,0,BJ12,0,0,0,0,0,0,0,0,0,0,0,0,0,0,0,0,0,0,0,0,0,0,0,0,0,0,0,0,0,0,0,0)';
      OUTPUT_LOAD='(1.0,-1.0)';
    'MHA_DQS_L8':
      PIN_NUMBER='(0,0,0,0,0,0,0,AF14,0,0,0,0,0,0,0,0,0,0,0,0,0,0,0,0,0,0,0,0,0,0,0,0,0,0,0,0,0,0,0,0)';
      BIDIRECTIONAL='TRUE';
      INPUT_LOAD='(-0.01,0.01)';
      OUTPUT_LOAD='(1.0,-1.0)';
    'MHA_DQS_H4':
      PIN_NUMBER='(0,0,0,0,0,0,0,AL12,0,0,0,0,0,0,0,0,0,0,0,0,0,0,0,0,0,0,0,0,0,0,0,0,0,0,0,0,0,0,0,0)';
      BIDIRECTIONAL='TRUE';
      INPUT_LOAD='(-0.01,0.01)';
      OUTPUT_LOAD='(1.0,-1.0)';
    'MHA_DATA1':
      PIN_NUMBER='(0,0,0,0,0,0,0,F14,0,0,0,0,0,0,0,0,0,0,0,0,0,0,0,0,0,0,0,0,0,0,0,0,0,0,0,0,0,0,0,0)';
      BIDIRECTIONAL='TRUE';
      INPUT_LOAD='(-0.01,0.01)';
      OUTPUT_LOAD='(1.0,-1.0)';
    'MHA_CA4':
      PIN_NUMBER='(0,0,0,0,0,0,0,BA12,0,0,0,0,0,0,0,0,0,0,0,0,0,0,0,0,0,0,0,0,0,0,0,0,0,0,0,0,0,0,0,0)';
      OUTPUT_LOAD='(1.0,-1.0)';
    'MHB_DQS_L3':
      PIN_NUMBER='(0,0,0,0,0,0,0,DC12,0,0,0,0,0,0,0,0,0,0,0,0,0,0,0,0,0,0,0,0,0,0,0,0,0,0,0,0,0,0,0,0)';
      BIDIRECTIONAL='TRUE';
      INPUT_LOAD='(-0.01,0.01)';
      OUTPUT_LOAD='(1.0,-1.0)';
    'MHB_DATA27':
      PIN_NUMBER='(0,0,0,0,0,0,0,DB14,0,0,0,0,0,0,0,0,0,0,0,0,0,0,0,0,0,0,0,0,0,0,0,0,0,0,0,0,0,0,0,0)';
      BIDIRECTIONAL='TRUE';
      INPUT_LOAD='(-0.01,0.01)';
      OUTPUT_LOAD='(1.0,-1.0)';
    'MHB_DATA16':
      PIN_NUMBER='(0,0,0,0,0,0,0,CP13,0,0,0,0,0,0,0,0,0,0,0,0,0,0,0,0,0,0,0,0,0,0,0,0,0,0,0,0,0,0,0,0)';
      BIDIRECTIONAL='TRUE';
      INPUT_LOAD='(-0.01,0.01)';
      OUTPUT_LOAD='(1.0,-1.0)';
    'MHB_DATA2':
      PIN_NUMBER='(0,0,0,0,0,0,0,CC12,0,0,0,0,0,0,0,0,0,0,0,0,0,0,0,0,0,0,0,0,0,0,0,0,0,0,0,0,0,0,0,0)';
      BIDIRECTIONAL='TRUE';
      INPUT_LOAD='(-0.01,0.01)';
      OUTPUT_LOAD='(1.0,-1.0)';
    'MHB_CHECK7':
      PIN_NUMBER='(0,0,0,0,0,0,0,BV14,0,0,0,0,0,0,0,0,0,0,0,0,0,0,0,0,0,0,0,0,0,0,0,0,0,0,0,0,0,0,0,0)';
      BIDIRECTIONAL='TRUE';
      INPUT_LOAD='(-0.01,0.01)';
      OUTPUT_LOAD='(1.0,-1.0)';
    'MHB_CA4':
      PIN_NUMBER='(0,0,0,0,0,0,0,BJ14,0,0,0,0,0,0,0,0,0,0,0,0,0,0,0,0,0,0,0,0,0,0,0,0,0,0,0,0,0,0,0,0)';
      OUTPUT_LOAD='(1.0,-1.0)';
    'MHB0_RSP_L':
      PIN_NUMBER='(0,0,0,0,0,0,0,BP13,0,0,0,0,0,0,0,0,0,0,0,0,0,0,0,0,0,0,0,0,0,0,0,0,0,0,0,0,0,0,0,0)';
      INPUT_LOAD='(-0.01,0.01)';
    'MHA_DQS_L9':
      PIN_NUMBER='(0,0,0,0,0,0,0,AM14,0,0,0,0,0,0,0,0,0,0,0,0,0,0,0,0,0,0,0,0,0,0,0,0,0,0,0,0,0,0,0,0)';
      BIDIRECTIONAL='TRUE';
      INPUT_LOAD='(-0.01,0.01)';
      OUTPUT_LOAD='(1.0,-1.0)';
    'MHA_DQS_H5':
      PIN_NUMBER='(0,0,0,0,0,0,0,J14,0,0,0,0,0,0,0,0,0,0,0,0,0,0,0,0,0,0,0,0,0,0,0,0,0,0,0,0,0,0,0,0)';
      BIDIRECTIONAL='TRUE';
      INPUT_LOAD='(-0.01,0.01)';
      OUTPUT_LOAD='(1.0,-1.0)';
    'MHA_DATA2':
      PIN_NUMBER='(0,0,0,0,0,0,0,F13,0,0,0,0,0,0,0,0,0,0,0,0,0,0,0,0,0,0,0,0,0,0,0,0,0,0,0,0,0,0,0,0)';
      BIDIRECTIONAL='TRUE';
      INPUT_LOAD='(-0.01,0.01)';
      OUTPUT_LOAD='(1.0,-1.0)';
    'MHA_CA5':
      PIN_NUMBER='(0,0,0,0,0,0,0,BB13,0,0,0,0,0,0,0,0,0,0,0,0,0,0,0,0,0,0,0,0,0,0,0,0,0,0,0,0,0,0,0,0)';
      OUTPUT_LOAD='(1.0,-1.0)';
    'MHB_DQS_L4':
      PIN_NUMBER='(0,0,0,0,0,0,0,BW14,0,0,0,0,0,0,0,0,0,0,0,0,0,0,0,0,0,0,0,0,0,0,0,0,0,0,0,0,0,0,0,0)';
      BIDIRECTIONAL='TRUE';
      INPUT_LOAD='(-0.01,0.01)';
      OUTPUT_LOAD='(1.0,-1.0)';
    'MHB_DQS_H0':
      PIN_NUMBER='(0,0,0,0,0,0,0,CD13,0,0,0,0,0,0,0,0,0,0,0,0,0,0,0,0,0,0,0,0,0,0,0,0,0,0,0,0,0,0,0,0)';
      BIDIRECTIONAL='TRUE';
      INPUT_LOAD='(-0.01,0.01)';
      OUTPUT_LOAD='(1.0,-1.0)';
    'MHB_DATA28':
      PIN_NUMBER='(0,0,0,0,0,0,0,DD13,0,0,0,0,0,0,0,0,0,0,0,0,0,0,0,0,0,0,0,0,0,0,0,0,0,0,0,0,0,0,0,0)';
      BIDIRECTIONAL='TRUE';
      INPUT_LOAD='(-0.01,0.01)';
      OUTPUT_LOAD='(1.0,-1.0)';
    'MHB_DATA17':
      PIN_NUMBER='(0,0,0,0,0,0,0,CR14,0,0,0,0,0,0,0,0,0,0,0,0,0,0,0,0,0,0,0,0,0,0,0,0,0,0,0,0,0,0,0,0)';
      BIDIRECTIONAL='TRUE';
      INPUT_LOAD='(-0.01,0.01)';
      OUTPUT_LOAD='(1.0,-1.0)';
    'MHB_DATA3':
      PIN_NUMBER='(0,0,0,0,0,0,0,CD14,0,0,0,0,0,0,0,0,0,0,0,0,0,0,0,0,0,0,0,0,0,0,0,0,0,0,0,0,0,0,0,0)';
      BIDIRECTIONAL='TRUE';
      INPUT_LOAD='(-0.01,0.01)';
      OUTPUT_LOAD='(1.0,-1.0)';
    'MHB_CA5':
      PIN_NUMBER='(0,0,0,0,0,0,0,BK14,0,0,0,0,0,0,0,0,0,0,0,0,0,0,0,0,0,0,0,0,0,0,0,0,0,0,0,0,0,0,0,0)';
      OUTPUT_LOAD='(1.0,-1.0)';
    'MHB1_RSP_L':
      PIN_NUMBER='(0,0,0,0,0,0,0,BR12,0,0,0,0,0,0,0,0,0,0,0,0,0,0,0,0,0,0,0,0,0,0,0,0,0,0,0,0,0,0,0,0)';
      INPUT_LOAD='(-0.01,0.01)';
    'MHA_DQS_H6':
      PIN_NUMBER='(0,0,0,0,0,0,0,R14,0,0,0,0,0,0,0,0,0,0,0,0,0,0,0,0,0,0,0,0,0,0,0,0,0,0,0,0,0,0,0,0)';
      BIDIRECTIONAL='TRUE';
      INPUT_LOAD='(-0.01,0.01)';
      OUTPUT_LOAD='(1.0,-1.0)';
    'MHA_DATA3':
      PIN_NUMBER='(0,0,0,0,0,0,0,G14,0,0,0,0,0,0,0,0,0,0,0,0,0,0,0,0,0,0,0,0,0,0,0,0,0,0,0,0,0,0,0,0)';
      BIDIRECTIONAL='TRUE';
      INPUT_LOAD='(-0.01,0.01)';
      OUTPUT_LOAD='(1.0,-1.0)';
    'MHA_CA6':
      PIN_NUMBER='(0,0,0,0,0,0,0,BB14,0,0,0,0,0,0,0,0,0,0,0,0,0,0,0,0,0,0,0,0,0,0,0,0,0,0,0,0,0,0,0,0)';
      OUTPUT_LOAD='(1.0,-1.0)';
    'MHB_DQS_L5':
      PIN_NUMBER='(0,0,0,0,0,0,0,CE14,0,0,0,0,0,0,0,0,0,0,0,0,0,0,0,0,0,0,0,0,0,0,0,0,0,0,0,0,0,0,0,0)';
      BIDIRECTIONAL='TRUE';
      INPUT_LOAD='(-0.01,0.01)';
      OUTPUT_LOAD='(1.0,-1.0)';
    'MHB_DQS_H1':
      PIN_NUMBER='(0,0,0,0,0,0,0,CK13,0,0,0,0,0,0,0,0,0,0,0,0,0,0,0,0,0,0,0,0,0,0,0,0,0,0,0,0,0,0,0,0)';
      BIDIRECTIONAL='TRUE';
      INPUT_LOAD='(-0.01,0.01)';
      OUTPUT_LOAD='(1.0,-1.0)';
    'MHB_DATA29':
      PIN_NUMBER='(0,0,0,0,0,0,0,DE14,0,0,0,0,0,0,0,0,0,0,0,0,0,0,0,0,0,0,0,0,0,0,0,0,0,0,0,0,0,0,0,0)';
      BIDIRECTIONAL='TRUE';
      INPUT_LOAD='(-0.01,0.01)';
      OUTPUT_LOAD='(1.0,-1.0)';
    'MHB_DATA18':
      PIN_NUMBER='(0,0,0,0,0,0,0,CR12,0,0,0,0,0,0,0,0,0,0,0,0,0,0,0,0,0,0,0,0,0,0,0,0,0,0,0,0,0,0,0,0)';
      BIDIRECTIONAL='TRUE';
      INPUT_LOAD='(-0.01,0.01)';
      OUTPUT_LOAD='(1.0,-1.0)';
    'MHB_DATA4':
      PIN_NUMBER='(0,0,0,0,0,0,0,CF13,0,0,0,0,0,0,0,0,0,0,0,0,0,0,0,0,0,0,0,0,0,0,0,0,0,0,0,0,0,0,0,0)';
      BIDIRECTIONAL='TRUE';
      INPUT_LOAD='(-0.01,0.01)';
      OUTPUT_LOAD='(1.0,-1.0)';
    'MHB_CA6':
      PIN_NUMBER='(0,0,0,0,0,0,0,BK13,0,0,0,0,0,0,0,0,0,0,0,0,0,0,0,0,0,0,0,0,0,0,0,0,0,0,0,0,0,0,0,0)';
      OUTPUT_LOAD='(1.0,-1.0)';
    'MHA_DQS_H7':
      PIN_NUMBER='(0,0,0,0,0,0,0,AA14,0,0,0,0,0,0,0,0,0,0,0,0,0,0,0,0,0,0,0,0,0,0,0,0,0,0,0,0,0,0,0,0)';
      BIDIRECTIONAL='TRUE';
      INPUT_LOAD='(-0.01,0.01)';
      OUTPUT_LOAD='(1.0,-1.0)';
    'MHA_DATA4':
      PIN_NUMBER='(0,0,0,0,0,0,0,J12,0,0,0,0,0,0,0,0,0,0,0,0,0,0,0,0,0,0,0,0,0,0,0,0,0,0,0,0,0,0,0,0)';
      BIDIRECTIONAL='TRUE';
      INPUT_LOAD='(-0.01,0.01)';
      OUTPUT_LOAD='(1.0,-1.0)';
    'MHA0_CS_L0':
      PIN_NUMBER='(0,0,0,0,0,0,0,AU12,0,0,0,0,0,0,0,0,0,0,0,0,0,0,0,0,0,0,0,0,0,0,0,0,0,0,0,0,0,0,0,0)';
      OUTPUT_LOAD='(1.0,-1.0)';
    'MHB_DQS_L6':
      PIN_NUMBER='(0,0,0,0,0,0,0,CL14,0,0,0,0,0,0,0,0,0,0,0,0,0,0,0,0,0,0,0,0,0,0,0,0,0,0,0,0,0,0,0,0)';
      BIDIRECTIONAL='TRUE';
      INPUT_LOAD='(-0.01,0.01)';
      OUTPUT_LOAD='(1.0,-1.0)';
    'MHB_DQS_H2':
      PIN_NUMBER='(0,0,0,0,0,0,0,CT13,0,0,0,0,0,0,0,0,0,0,0,0,0,0,0,0,0,0,0,0,0,0,0,0,0,0,0,0,0,0,0,0)';
      BIDIRECTIONAL='TRUE';
      INPUT_LOAD='(-0.01,0.01)';
      OUTPUT_LOAD='(1.0,-1.0)';
    'MHB_DATA19':
      PIN_NUMBER='(0,0,0,0,0,0,0,CT14,0,0,0,0,0,0,0,0,0,0,0,0,0,0,0,0,0,0,0,0,0,0,0,0,0,0,0,0,0,0,0,0)';
      BIDIRECTIONAL='TRUE';
      INPUT_LOAD='(-0.01,0.01)';
      OUTPUT_LOAD='(1.0,-1.0)';
    'MHB_DATA5':
      PIN_NUMBER='(0,0,0,0,0,0,0,CG14,0,0,0,0,0,0,0,0,0,0,0,0,0,0,0,0,0,0,0,0,0,0,0,0,0,0,0,0,0,0,0,0)';
      BIDIRECTIONAL='TRUE';
      INPUT_LOAD='(-0.01,0.01)';
      OUTPUT_LOAD='(1.0,-1.0)';
    'MHA_DQS_H8':
      PIN_NUMBER='(0,0,0,0,0,0,0,AG14,0,0,0,0,0,0,0,0,0,0,0,0,0,0,0,0,0,0,0,0,0,0,0,0,0,0,0,0,0,0,0,0)';
      BIDIRECTIONAL='TRUE';
      INPUT_LOAD='(-0.01,0.01)';
      OUTPUT_LOAD='(1.0,-1.0)';
    'MHA_DATA30':
      PIN_NUMBER='(0,0,0,0,0,0,0,AH13,0,0,0,0,0,0,0,0,0,0,0,0,0,0,0,0,0,0,0,0,0,0,0,0,0,0,0,0,0,0,0,0)';
      BIDIRECTIONAL='TRUE';
      INPUT_LOAD='(-0.01,0.01)';
      OUTPUT_LOAD='(1.0,-1.0)';
    'MHA_DATA5':
      PIN_NUMBER='(0,0,0,0,0,0,0,K14,0,0,0,0,0,0,0,0,0,0,0,0,0,0,0,0,0,0,0,0,0,0,0,0,0,0,0,0,0,0,0,0)';
      BIDIRECTIONAL='TRUE';
      INPUT_LOAD='(-0.01,0.01)';
      OUTPUT_LOAD='(1.0,-1.0)';
    'MHA1_CS_L0':
      PIN_NUMBER='(0,0,0,0,0,0,0,AV13,0,0,0,0,0,0,0,0,0,0,0,0,0,0,0,0,0,0,0,0,0,0,0,0,0,0,0,0,0,0,0,0)';
      OUTPUT_LOAD='(1.0,-1.0)';
    'MHA0_CS_L1':
      PIN_NUMBER='(0,0,0,0,0,0,0,AV14,0,0,0,0,0,0,0,0,0,0,0,0,0,0,0,0,0,0,0,0,0,0,0,0,0,0,0,0,0,0,0,0)';
      OUTPUT_LOAD='(1.0,-1.0)';
    'MHB_DQS_L7':
      PIN_NUMBER='(0,0,0,0,0,0,0,CU14,0,0,0,0,0,0,0,0,0,0,0,0,0,0,0,0,0,0,0,0,0,0,0,0,0,0,0,0,0,0,0,0)';
      BIDIRECTIONAL='TRUE';
      INPUT_LOAD='(-0.01,0.01)';
      OUTPUT_LOAD='(1.0,-1.0)';
    'MHB_DQS_H3':
      PIN_NUMBER='(0,0,0,0,0,0,0,DB13,0,0,0,0,0,0,0,0,0,0,0,0,0,0,0,0,0,0,0,0,0,0,0,0,0,0,0,0,0,0,0,0)';
      BIDIRECTIONAL='TRUE';
      INPUT_LOAD='(-0.01,0.01)';
      OUTPUT_LOAD='(1.0,-1.0)';
    'MHB_DATA6':
      PIN_NUMBER='(0,0,0,0,0,0,0,CG12,0,0,0,0,0,0,0,0,0,0,0,0,0,0,0,0,0,0,0,0,0,0,0,0,0,0,0,0,0,0,0,0)';
      BIDIRECTIONAL='TRUE';
      INPUT_LOAD='(-0.01,0.01)';
      OUTPUT_LOAD='(1.0,-1.0)';
    'MHA_DQS_H9':
      PIN_NUMBER='(0,0,0,0,0,0,0,AN14,0,0,0,0,0,0,0,0,0,0,0,0,0,0,0,0,0,0,0,0,0,0,0,0,0,0,0,0,0,0,0,0)';
      BIDIRECTIONAL='TRUE';
      INPUT_LOAD='(-0.01,0.01)';
      OUTPUT_LOAD='(1.0,-1.0)';
    'MHA_DATA31':
      PIN_NUMBER='(0,0,0,0,0,0,0,AJ14,0,0,0,0,0,0,0,0,0,0,0,0,0,0,0,0,0,0,0,0,0,0,0,0,0,0,0,0,0,0,0,0)';
      BIDIRECTIONAL='TRUE';
      INPUT_LOAD='(-0.01,0.01)';
      OUTPUT_LOAD='(1.0,-1.0)';
    'MHA_DATA20':
      PIN_NUMBER='(0,0,0,0,0,0,0,AA12,0,0,0,0,0,0,0,0,0,0,0,0,0,0,0,0,0,0,0,0,0,0,0,0,0,0,0,0,0,0,0,0)';
      BIDIRECTIONAL='TRUE';
      INPUT_LOAD='(-0.01,0.01)';
      OUTPUT_LOAD='(1.0,-1.0)';
    'MHA_DATA6':
      PIN_NUMBER='(0,0,0,0,0,0,0,K13,0,0,0,0,0,0,0,0,0,0,0,0,0,0,0,0,0,0,0,0,0,0,0,0,0,0,0,0,0,0,0,0)';
      BIDIRECTIONAL='TRUE';
      INPUT_LOAD='(-0.01,0.01)';
      OUTPUT_LOAD='(1.0,-1.0)';
    'MHA_CHECK0':
      PIN_NUMBER='(0,0,0,0,0,0,0,AJ12,0,0,0,0,0,0,0,0,0,0,0,0,0,0,0,0,0,0,0,0,0,0,0,0,0,0,0,0,0,0,0,0)';
      BIDIRECTIONAL='TRUE';
      INPUT_LOAD='(-0.01,0.01)';
      OUTPUT_LOAD='(1.0,-1.0)';
    'MHA1_CS_L1':
      PIN_NUMBER='(0,0,0,0,0,0,0,AW14,0,0,0,0,0,0,0,0,0,0,0,0,0,0,0,0,0,0,0,0,0,0,0,0,0,0,0,0,0,0,0,0)';
      OUTPUT_LOAD='(1.0,-1.0)';
    'MHB_DQS_L8':
      PIN_NUMBER='(0,0,0,0,0,0,0,DC14,0,0,0,0,0,0,0,0,0,0,0,0,0,0,0,0,0,0,0,0,0,0,0,0,0,0,0,0,0,0,0,0)';
      BIDIRECTIONAL='TRUE';
      INPUT_LOAD='(-0.01,0.01)';
      OUTPUT_LOAD='(1.0,-1.0)';
    'MHB_DQS_H4':
      PIN_NUMBER='(0,0,0,0,0,0,0,BY14,0,0,0,0,0,0,0,0,0,0,0,0,0,0,0,0,0,0,0,0,0,0,0,0,0,0,0,0,0,0,0,0)';
      BIDIRECTIONAL='TRUE';
      INPUT_LOAD='(-0.01,0.01)';
      OUTPUT_LOAD='(1.0,-1.0)';
    'MHB_DATA7':
      PIN_NUMBER='(0,0,0,0,0,0,0,CH14,0,0,0,0,0,0,0,0,0,0,0,0,0,0,0,0,0,0,0,0,0,0,0,0,0,0,0,0,0,0,0,0)';
      BIDIRECTIONAL='TRUE';
      INPUT_LOAD='(-0.01,0.01)';
      OUTPUT_LOAD='(1.0,-1.0)';
    'MHA_DATA21':
      PIN_NUMBER='(0,0,0,0,0,0,0,AB14,0,0,0,0,0,0,0,0,0,0,0,0,0,0,0,0,0,0,0,0,0,0,0,0,0,0,0,0,0,0,0,0)';
      BIDIRECTIONAL='TRUE';
      INPUT_LOAD='(-0.01,0.01)';
      OUTPUT_LOAD='(1.0,-1.0)';
    'MHA_DATA10':
      PIN_NUMBER='(0,0,0,0,0,0,0,M13,0,0,0,0,0,0,0,0,0,0,0,0,0,0,0,0,0,0,0,0,0,0,0,0,0,0,0,0,0,0,0,0)';
      BIDIRECTIONAL='TRUE';
      INPUT_LOAD='(-0.01,0.01)';
      OUTPUT_LOAD='(1.0,-1.0)';
    'MHA_DATA7':
      PIN_NUMBER='(0,0,0,0,0,0,0,L14,0,0,0,0,0,0,0,0,0,0,0,0,0,0,0,0,0,0,0,0,0,0,0,0,0,0,0,0,0,0,0,0)';
      BIDIRECTIONAL='TRUE';
      INPUT_LOAD='(-0.01,0.01)';
      OUTPUT_LOAD='(1.0,-1.0)';
    'MHA_CHECK1':
      PIN_NUMBER='(0,0,0,0,0,0,0,AK14,0,0,0,0,0,0,0,0,0,0,0,0,0,0,0,0,0,0,0,0,0,0,0,0,0,0,0,0,0,0,0,0)';
      BIDIRECTIONAL='TRUE';
      INPUT_LOAD='(-0.01,0.01)';
      OUTPUT_LOAD='(1.0,-1.0)';
    'MHB_DQS_L9':
      PIN_NUMBER='(0,0,0,0,0,0,0,BW12,0,0,0,0,0,0,0,0,0,0,0,0,0,0,0,0,0,0,0,0,0,0,0,0,0,0,0,0,0,0,0,0)';
      BIDIRECTIONAL='TRUE';
      INPUT_LOAD='(-0.01,0.01)';
      OUTPUT_LOAD='(1.0,-1.0)';
    'MHB_DQS_H5':
      PIN_NUMBER='(0,0,0,0,0,0,0,CF14,0,0,0,0,0,0,0,0,0,0,0,0,0,0,0,0,0,0,0,0,0,0,0,0,0,0,0,0,0,0,0,0)';
      BIDIRECTIONAL='TRUE';
      INPUT_LOAD='(-0.01,0.01)';
      OUTPUT_LOAD='(1.0,-1.0)';
    'MHB_DATA8':
      PIN_NUMBER='(0,0,0,0,0,0,0,CH13,0,0,0,0,0,0,0,0,0,0,0,0,0,0,0,0,0,0,0,0,0,0,0,0,0,0,0,0,0,0,0,0)';
      BIDIRECTIONAL='TRUE';
      INPUT_LOAD='(-0.01,0.01)';
      OUTPUT_LOAD='(1.0,-1.0)';
    'MHA_DATA22':
      PIN_NUMBER='(0,0,0,0,0,0,0,AB13,0,0,0,0,0,0,0,0,0,0,0,0,0,0,0,0,0,0,0,0,0,0,0,0,0,0,0,0,0,0,0,0)';
      BIDIRECTIONAL='TRUE';
      INPUT_LOAD='(-0.01,0.01)';
      OUTPUT_LOAD='(1.0,-1.0)';
    'MHA_DATA11':
      PIN_NUMBER='(0,0,0,0,0,0,0,N14,0,0,0,0,0,0,0,0,0,0,0,0,0,0,0,0,0,0,0,0,0,0,0,0,0,0,0,0,0,0,0,0)';
      BIDIRECTIONAL='TRUE';
      INPUT_LOAD='(-0.01,0.01)';
      OUTPUT_LOAD='(1.0,-1.0)';
    'MHA_DATA8':
      PIN_NUMBER='(0,0,0,0,0,0,0,L12,0,0,0,0,0,0,0,0,0,0,0,0,0,0,0,0,0,0,0,0,0,0,0,0,0,0,0,0,0,0,0,0)';
      BIDIRECTIONAL='TRUE';
      INPUT_LOAD='(-0.01,0.01)';
      OUTPUT_LOAD='(1.0,-1.0)';
    'MHA_CHECK2':
      PIN_NUMBER='(0,0,0,0,0,0,0,AK13,0,0,0,0,0,0,0,0,0,0,0,0,0,0,0,0,0,0,0,0,0,0,0,0,0,0,0,0,0,0,0,0)';
      BIDIRECTIONAL='TRUE';
      INPUT_LOAD='(-0.01,0.01)';
      OUTPUT_LOAD='(1.0,-1.0)';
    'MHB_DQS_H6':
      PIN_NUMBER='(0,0,0,0,0,0,0,CM14,0,0,0,0,0,0,0,0,0,0,0,0,0,0,0,0,0,0,0,0,0,0,0,0,0,0,0,0,0,0,0,0)';
      BIDIRECTIONAL='TRUE';
      INPUT_LOAD='(-0.01,0.01)';
      OUTPUT_LOAD='(1.0,-1.0)';
    'MHB_DATA9':
      PIN_NUMBER='(0,0,0,0,0,0,0,CJ14,0,0,0,0,0,0,0,0,0,0,0,0,0,0,0,0,0,0,0,0,0,0,0,0,0,0,0,0,0,0,0,0)';
      BIDIRECTIONAL='TRUE';
      INPUT_LOAD='(-0.01,0.01)';
      OUTPUT_LOAD='(1.0,-1.0)';
    'MHA_DATA23':
      PIN_NUMBER='(0,0,0,0,0,0,0,AC14,0,0,0,0,0,0,0,0,0,0,0,0,0,0,0,0,0,0,0,0,0,0,0,0,0,0,0,0,0,0,0,0)';
      BIDIRECTIONAL='TRUE';
      INPUT_LOAD='(-0.01,0.01)';
      OUTPUT_LOAD='(1.0,-1.0)';
    'MHA_DATA12':
      PIN_NUMBER='(0,0,0,0,0,0,0,R12,0,0,0,0,0,0,0,0,0,0,0,0,0,0,0,0,0,0,0,0,0,0,0,0,0,0,0,0,0,0,0,0)';
      BIDIRECTIONAL='TRUE';
      INPUT_LOAD='(-0.01,0.01)';
      OUTPUT_LOAD='(1.0,-1.0)';
    'MHA_DATA9':
      PIN_NUMBER='(0,0,0,0,0,0,0,M14,0,0,0,0,0,0,0,0,0,0,0,0,0,0,0,0,0,0,0,0,0,0,0,0,0,0,0,0,0,0,0,0)';
      BIDIRECTIONAL='TRUE';
      INPUT_LOAD='(-0.01,0.01)';
      OUTPUT_LOAD='(1.0,-1.0)';
    'MHA_CHECK3':
      PIN_NUMBER='(0,0,0,0,0,0,0,AL14,0,0,0,0,0,0,0,0,0,0,0,0,0,0,0,0,0,0,0,0,0,0,0,0,0,0,0,0,0,0,0,0)';
      BIDIRECTIONAL='TRUE';
      INPUT_LOAD='(-0.01,0.01)';
      OUTPUT_LOAD='(1.0,-1.0)';
    'MHB_DQS_H7':
      PIN_NUMBER='(0,0,0,0,0,0,0,CV14,0,0,0,0,0,0,0,0,0,0,0,0,0,0,0,0,0,0,0,0,0,0,0,0,0,0,0,0,0,0,0,0)';
      BIDIRECTIONAL='TRUE';
      INPUT_LOAD='(-0.01,0.01)';
      OUTPUT_LOAD='(1.0,-1.0)';
    'MHB0_CS_L0':
      PIN_NUMBER='(0,0,0,0,0,0,0,BM14,0,0,0,0,0,0,0,0,0,0,0,0,0,0,0,0,0,0,0,0,0,0,0,0,0,0,0,0,0,0,0,0)';
      OUTPUT_LOAD='(1.0,-1.0)';
    'MHA_DQS_L0':
      PIN_NUMBER='(0,0,0,0,0,0,0,H13,0,0,0,0,0,0,0,0,0,0,0,0,0,0,0,0,0,0,0,0,0,0,0,0,0,0,0,0,0,0,0,0)';
      BIDIRECTIONAL='TRUE';
      INPUT_LOAD='(-0.01,0.01)';
      OUTPUT_LOAD='(1.0,-1.0)';
    'MHA_DATA24':
      PIN_NUMBER='(0,0,0,0,0,0,0,AC12,0,0,0,0,0,0,0,0,0,0,0,0,0,0,0,0,0,0,0,0,0,0,0,0,0,0,0,0,0,0,0,0)';
      BIDIRECTIONAL='TRUE';
      INPUT_LOAD='(-0.01,0.01)';
      OUTPUT_LOAD='(1.0,-1.0)';
    'MHA_DATA13':
      PIN_NUMBER='(0,0,0,0,0,0,0,T14,0,0,0,0,0,0,0,0,0,0,0,0,0,0,0,0,0,0,0,0,0,0,0,0,0,0,0,0,0,0,0,0)';
      BIDIRECTIONAL='TRUE';
      INPUT_LOAD='(-0.01,0.01)';
      OUTPUT_LOAD='(1.0,-1.0)';
    'MHA_CHECK4':
      PIN_NUMBER='(0,0,0,0,0,0,0,AN12,0,0,0,0,0,0,0,0,0,0,0,0,0,0,0,0,0,0,0,0,0,0,0,0,0,0,0,0,0,0,0,0)';
      BIDIRECTIONAL='TRUE';
      INPUT_LOAD='(-0.01,0.01)';
      OUTPUT_LOAD='(1.0,-1.0)';
    'MHB_DQS_H8':
      PIN_NUMBER='(0,0,0,0,0,0,0,DD14,0,0,0,0,0,0,0,0,0,0,0,0,0,0,0,0,0,0,0,0,0,0,0,0,0,0,0,0,0,0,0,0)';
      BIDIRECTIONAL='TRUE';
      INPUT_LOAD='(-0.01,0.01)';
      OUTPUT_LOAD='(1.0,-1.0)';
    'MHB_DATA30':
      PIN_NUMBER='(0,0,0,0,0,0,0,DE12,0,0,0,0,0,0,0,0,0,0,0,0,0,0,0,0,0,0,0,0,0,0,0,0,0,0,0,0,0,0,0,0)';
      BIDIRECTIONAL='TRUE';
      INPUT_LOAD='(-0.01,0.01)';
      OUTPUT_LOAD='(1.0,-1.0)';
    'MHB1_CS_L0':
      PIN_NUMBER='(0,0,0,0,0,0,0,BL12,0,0,0,0,0,0,0,0,0,0,0,0,0,0,0,0,0,0,0,0,0,0,0,0,0,0,0,0,0,0,0,0)';
      OUTPUT_LOAD='(1.0,-1.0)';
    'MHB0_CS_L1':
      PIN_NUMBER='(0,0,0,0,0,0,0,BN12,0,0,0,0,0,0,0,0,0,0,0,0,0,0,0,0,0,0,0,0,0,0,0,0,0,0,0,0,0,0,0,0)';
      OUTPUT_LOAD='(1.0,-1.0)';
    'MHA_DQS_L1':
      PIN_NUMBER='(0,0,0,0,0,0,0,P13,0,0,0,0,0,0,0,0,0,0,0,0,0,0,0,0,0,0,0,0,0,0,0,0,0,0,0,0,0,0,0,0)';
      BIDIRECTIONAL='TRUE';
      INPUT_LOAD='(-0.01,0.01)';
      OUTPUT_LOAD='(1.0,-1.0)';
    'MHA_DATA25':
      PIN_NUMBER='(0,0,0,0,0,0,0,AD14,0,0,0,0,0,0,0,0,0,0,0,0,0,0,0,0,0,0,0,0,0,0,0,0,0,0,0,0,0,0,0,0)';
      BIDIRECTIONAL='TRUE';
      INPUT_LOAD='(-0.01,0.01)';
      OUTPUT_LOAD='(1.0,-1.0)';
    'MHA_DATA14':
      PIN_NUMBER='(0,0,0,0,0,0,0,T13,0,0,0,0,0,0,0,0,0,0,0,0,0,0,0,0,0,0,0,0,0,0,0,0,0,0,0,0,0,0,0,0)';
      BIDIRECTIONAL='TRUE';
      INPUT_LOAD='(-0.01,0.01)';
      OUTPUT_LOAD='(1.0,-1.0)';
    'MHA_CHECK5':
      PIN_NUMBER='(0,0,0,0,0,0,0,AP14,0,0,0,0,0,0,0,0,0,0,0,0,0,0,0,0,0,0,0,0,0,0,0,0,0,0,0,0,0,0,0,0)';
      BIDIRECTIONAL='TRUE';
      INPUT_LOAD='(-0.01,0.01)';
      OUTPUT_LOAD='(1.0,-1.0)';
    'MHB_DQS_H9':
      PIN_NUMBER='(0,0,0,0,0,0,0,BV13,0,0,0,0,0,0,0,0,0,0,0,0,0,0,0,0,0,0,0,0,0,0,0,0,0,0,0,0,0,0,0,0)';
      BIDIRECTIONAL='TRUE';
      INPUT_LOAD='(-0.01,0.01)';
      OUTPUT_LOAD='(1.0,-1.0)';
    'MHA_PAR':
      PIN_NUMBER='(0,0,0,0,0,0,0,BC14,0,0,0,0,0,0,0,0,0,0,0,0,0,0,0,0,0,0,0,0,0,0,0,0,0,0,0,0,0,0,0,0)';
      OUTPUT_LOAD='(1.0,-1.0)';
    'MHB_PAR':
      PIN_NUMBER='(0,0,0,0,0,0,0,BL14,0,0,0,0,0,0,0,0,0,0,0,0,0,0,0,0,0,0,0,0,0,0,0,0,0,0,0,0,0,0,0,0)';
      OUTPUT_LOAD='(1.0,-1.0)';
    'MH0_CLK_H':
      PIN_NUMBER='(0,0,0,0,0,0,0,BC12,0,0,0,0,0,0,0,0,0,0,0,0,0,0,0,0,0,0,0,0,0,0,0,0,0,0,0,0,0,0,0,0)';
      OUTPUT_LOAD='(1.0,-1.0)';
    'MH0_CLK_L':
      PIN_NUMBER='(0,0,0,0,0,0,0,BD13,0,0,0,0,0,0,0,0,0,0,0,0,0,0,0,0,0,0,0,0,0,0,0,0,0,0,0,0,0,0,0,0)';
      OUTPUT_LOAD='(1.0,-1.0)';
    'MH1_CLK_H':
      PIN_NUMBER='(0,0,0,0,0,0,0,BF13,0,0,0,0,0,0,0,0,0,0,0,0,0,0,0,0,0,0,0,0,0,0,0,0,0,0,0,0,0,0,0,0)';
      OUTPUT_LOAD='(1.0,-1.0)';
    'MH1_CLK_L':
      PIN_NUMBER='(0,0,0,0,0,0,0,BG12,0,0,0,0,0,0,0,0,0,0,0,0,0,0,0,0,0,0,0,0,0,0,0,0,0,0,0,0,0,0,0,0)';
      OUTPUT_LOAD='(1.0,-1.0)';
    'TEST39H':
      PIN_NUMBER='(0,0,0,0,0,0,0,BF14,0,0,0,0,0,0,0,0,0,0,0,0,0,0,0,0,0,0,0,0,0,0,0,0,0,0,0,0,0,0,0,0)';
      OUTPUT_LOAD='(1.0,-1.0)';
    'MIB_DATA23':
      PIN_NUMBER='(0,0,0,0,0,0,0,0,CY21,0,0,0,0,0,0,0,0,0,0,0,0,0,0,0,0,0,0,0,0,0,0,0,0,0,0,0,0,0,0,0)';
      BIDIRECTIONAL='TRUE';
      INPUT_LOAD='(-0.01,0.01)';
      OUTPUT_LOAD='(1.0,-1.0)';
    'MIB_DATA12':
      PIN_NUMBER='(0,0,0,0,0,0,0,0,CM20,0,0,0,0,0,0,0,0,0,0,0,0,0,0,0,0,0,0,0,0,0,0,0,0,0,0,0,0,0,0,0)';
      BIDIRECTIONAL='TRUE';
      INPUT_LOAD='(-0.01,0.01)';
      OUTPUT_LOAD='(1.0,-1.0)';
    'MIB_DATA6':
      PIN_NUMBER='(0,0,0,0,0,0,0,0,CG19,0,0,0,0,0,0,0,0,0,0,0,0,0,0,0,0,0,0,0,0,0,0,0,0,0,0,0,0,0,0,0)';
      BIDIRECTIONAL='TRUE';
      INPUT_LOAD='(-0.01,0.01)';
      OUTPUT_LOAD='(1.0,-1.0)';
    'MIB_CHECK3':
      PIN_NUMBER='(0,0,0,0,0,0,0,0,CB21,0,0,0,0,0,0,0,0,0,0,0,0,0,0,0,0,0,0,0,0,0,0,0,0,0,0,0,0,0,0,0)';
      BIDIRECTIONAL='TRUE';
      INPUT_LOAD='(-0.01,0.01)';
      OUTPUT_LOAD='(1.0,-1.0)';
    'MIA_DQS_L5':
      PIN_NUMBER='(0,0,0,0,0,0,0,0,H21,0,0,0,0,0,0,0,0,0,0,0,0,0,0,0,0,0,0,0,0,0,0,0,0,0,0,0,0,0,0,0)';
      BIDIRECTIONAL='TRUE';
      INPUT_LOAD='(-0.01,0.01)';
      OUTPUT_LOAD='(1.0,-1.0)';
    'MIA_DQS_H1':
      PIN_NUMBER='(0,0,0,0,0,0,0,0,N19,0,0,0,0,0,0,0,0,0,0,0,0,0,0,0,0,0,0,0,0,0,0,0,0,0,0,0,0,0,0,0)';
      BIDIRECTIONAL='TRUE';
      INPUT_LOAD='(-0.01,0.01)';
      OUTPUT_LOAD='(1.0,-1.0)';
    'MIA_DATA29':
      PIN_NUMBER='(0,0,0,0,0,0,0,0,AH21,0,0,0,0,0,0,0,0,0,0,0,0,0,0,0,0,0,0,0,0,0,0,0,0,0,0,0,0,0,0,0)';
      BIDIRECTIONAL='TRUE';
      INPUT_LOAD='(-0.01,0.01)';
      OUTPUT_LOAD='(1.0,-1.0)';
    'MIA_DATA18':
      PIN_NUMBER='(0,0,0,0,0,0,0,0,V20,0,0,0,0,0,0,0,0,0,0,0,0,0,0,0,0,0,0,0,0,0,0,0,0,0,0,0,0,0,0,0)';
      BIDIRECTIONAL='TRUE';
      INPUT_LOAD='(-0.01,0.01)';
      OUTPUT_LOAD='(1.0,-1.0)';
    'MIA_DATA6':
      PIN_NUMBER='(0,0,0,0,0,0,0,0,K20,0,0,0,0,0,0,0,0,0,0,0,0,0,0,0,0,0,0,0,0,0,0,0,0,0,0,0,0,0,0,0)';
      BIDIRECTIONAL='TRUE';
      INPUT_LOAD='(-0.01,0.01)';
      OUTPUT_LOAD='(1.0,-1.0)';
    'MIB_DQS_L0':
      PIN_NUMBER='(0,0,0,0,0,0,0,0,CE19,0,0,0,0,0,0,0,0,0,0,0,0,0,0,0,0,0,0,0,0,0,0,0,0,0,0,0,0,0,0,0)';
      BIDIRECTIONAL='TRUE';
      INPUT_LOAD='(-0.01,0.01)';
      OUTPUT_LOAD='(1.0,-1.0)';
    'MIB_DATA24':
      PIN_NUMBER='(0,0,0,0,0,0,0,0,CY20,0,0,0,0,0,0,0,0,0,0,0,0,0,0,0,0,0,0,0,0,0,0,0,0,0,0,0,0,0,0,0)';
      BIDIRECTIONAL='TRUE';
      INPUT_LOAD='(-0.01,0.01)';
      OUTPUT_LOAD='(1.0,-1.0)';
    'MIB_DATA13':
      PIN_NUMBER='(0,0,0,0,0,0,0,0,CN21,0,0,0,0,0,0,0,0,0,0,0,0,0,0,0,0,0,0,0,0,0,0,0,0,0,0,0,0,0,0,0)';
      BIDIRECTIONAL='TRUE';
      INPUT_LOAD='(-0.01,0.01)';
      OUTPUT_LOAD='(1.0,-1.0)';
    'MIB_DATA7':
      PIN_NUMBER='(0,0,0,0,0,0,0,0,CH21,0,0,0,0,0,0,0,0,0,0,0,0,0,0,0,0,0,0,0,0,0,0,0,0,0,0,0,0,0,0,0)';
      BIDIRECTIONAL='TRUE';
      INPUT_LOAD='(-0.01,0.01)';
      OUTPUT_LOAD='(1.0,-1.0)';
    'MIB_CHECK4':
      PIN_NUMBER='(0,0,0,0,0,0,0,0,BT20,0,0,0,0,0,0,0,0,0,0,0,0,0,0,0,0,0,0,0,0,0,0,0,0,0,0,0,0,0,0,0)';
      BIDIRECTIONAL='TRUE';
      INPUT_LOAD='(-0.01,0.01)';
      OUTPUT_LOAD='(1.0,-1.0)';
    'MIA_DQS_L6':
      PIN_NUMBER='(0,0,0,0,0,0,0,0,P21,0,0,0,0,0,0,0,0,0,0,0,0,0,0,0,0,0,0,0,0,0,0,0,0,0,0,0,0,0,0,0)';
      BIDIRECTIONAL='TRUE';
      INPUT_LOAD='(-0.01,0.01)';
      OUTPUT_LOAD='(1.0,-1.0)';
    'MIA_DQS_H2':
      PIN_NUMBER='(0,0,0,0,0,0,0,0,W19,0,0,0,0,0,0,0,0,0,0,0,0,0,0,0,0,0,0,0,0,0,0,0,0,0,0,0,0,0,0,0)';
      BIDIRECTIONAL='TRUE';
      INPUT_LOAD='(-0.01,0.01)';
      OUTPUT_LOAD='(1.0,-1.0)';
    'MIA_DATA19':
      PIN_NUMBER='(0,0,0,0,0,0,0,0,W21,0,0,0,0,0,0,0,0,0,0,0,0,0,0,0,0,0,0,0,0,0,0,0,0,0,0,0,0,0,0,0)';
      BIDIRECTIONAL='TRUE';
      INPUT_LOAD='(-0.01,0.01)';
      OUTPUT_LOAD='(1.0,-1.0)';
    'MIA_DATA7':
      PIN_NUMBER='(0,0,0,0,0,0,0,0,L21,0,0,0,0,0,0,0,0,0,0,0,0,0,0,0,0,0,0,0,0,0,0,0,0,0,0,0,0,0,0,0)';
      BIDIRECTIONAL='TRUE';
      INPUT_LOAD='(-0.01,0.01)';
      OUTPUT_LOAD='(1.0,-1.0)';
    'MIA_CA0':
      PIN_NUMBER='(0,0,0,0,0,0,0,0,AW19,0,0,0,0,0,0,0,0,0,0,0,0,0,0,0,0,0,0,0,0,0,0,0,0,0,0,0,0,0,0,0)';
      OUTPUT_LOAD='(1.0,-1.0)';
    'MIB_DQS_L1':
      PIN_NUMBER='(0,0,0,0,0,0,0,0,CL19,0,0,0,0,0,0,0,0,0,0,0,0,0,0,0,0,0,0,0,0,0,0,0,0,0,0,0,0,0,0,0)';
      BIDIRECTIONAL='TRUE';
      INPUT_LOAD='(-0.01,0.01)';
      OUTPUT_LOAD='(1.0,-1.0)';
    'MIB_DATA25':
      PIN_NUMBER='(0,0,0,0,0,0,0,0,DA21,0,0,0,0,0,0,0,0,0,0,0,0,0,0,0,0,0,0,0,0,0,0,0,0,0,0,0,0,0,0,0)';
      BIDIRECTIONAL='TRUE';
      INPUT_LOAD='(-0.01,0.01)';
      OUTPUT_LOAD='(1.0,-1.0)';
    'MIB_DATA14':
      PIN_NUMBER='(0,0,0,0,0,0,0,0,CN19,0,0,0,0,0,0,0,0,0,0,0,0,0,0,0,0,0,0,0,0,0,0,0,0,0,0,0,0,0,0,0)';
      BIDIRECTIONAL='TRUE';
      INPUT_LOAD='(-0.01,0.01)';
      OUTPUT_LOAD='(1.0,-1.0)';
    'MIB_DATA8':
      PIN_NUMBER='(0,0,0,0,0,0,0,0,CH20,0,0,0,0,0,0,0,0,0,0,0,0,0,0,0,0,0,0,0,0,0,0,0,0,0,0,0,0,0,0,0)';
      BIDIRECTIONAL='TRUE';
      INPUT_LOAD='(-0.01,0.01)';
      OUTPUT_LOAD='(1.0,-1.0)';
    'MIB_CHECK5':
      PIN_NUMBER='(0,0,0,0,0,0,0,0,BU21,0,0,0,0,0,0,0,0,0,0,0,0,0,0,0,0,0,0,0,0,0,0,0,0,0,0,0,0,0,0,0)';
      BIDIRECTIONAL='TRUE';
      INPUT_LOAD='(-0.01,0.01)';
      OUTPUT_LOAD='(1.0,-1.0)';
    'MIB_CA0':
      PIN_NUMBER='(0,0,0,0,0,0,0,0,BG21,0,0,0,0,0,0,0,0,0,0,0,0,0,0,0,0,0,0,0,0,0,0,0,0,0,0,0,0,0,0,0)';
      OUTPUT_LOAD='(1.0,-1.0)';
    'MIA_DQS_L7':
      PIN_NUMBER='(0,0,0,0,0,0,0,0,Y21,0,0,0,0,0,0,0,0,0,0,0,0,0,0,0,0,0,0,0,0,0,0,0,0,0,0,0,0,0,0,0)';
      BIDIRECTIONAL='TRUE';
      INPUT_LOAD='(-0.01,0.01)';
      OUTPUT_LOAD='(1.0,-1.0)';
    'MIA_DQS_H3':
      PIN_NUMBER='(0,0,0,0,0,0,0,0,AE19,0,0,0,0,0,0,0,0,0,0,0,0,0,0,0,0,0,0,0,0,0,0,0,0,0,0,0,0,0,0,0)';
      BIDIRECTIONAL='TRUE';
      INPUT_LOAD='(-0.01,0.01)';
      OUTPUT_LOAD='(1.0,-1.0)';
    'MIA_DATA8':
      PIN_NUMBER='(0,0,0,0,0,0,0,0,L19,0,0,0,0,0,0,0,0,0,0,0,0,0,0,0,0,0,0,0,0,0,0,0,0,0,0,0,0,0,0,0)';
      BIDIRECTIONAL='TRUE';
      INPUT_LOAD='(-0.01,0.01)';
      OUTPUT_LOAD='(1.0,-1.0)';
    'MIA_CA1':
      PIN_NUMBER='(0,0,0,0,0,0,0,0,AY20,0,0,0,0,0,0,0,0,0,0,0,0,0,0,0,0,0,0,0,0,0,0,0,0,0,0,0,0,0,0,0)';
      OUTPUT_LOAD='(1.0,-1.0)';
    'MIB_DQS_L2':
      PIN_NUMBER='(0,0,0,0,0,0,0,0,CU19,0,0,0,0,0,0,0,0,0,0,0,0,0,0,0,0,0,0,0,0,0,0,0,0,0,0,0,0,0,0,0)';
      BIDIRECTIONAL='TRUE';
      INPUT_LOAD='(-0.01,0.01)';
      OUTPUT_LOAD='(1.0,-1.0)';
    'MIB_DATA26':
      PIN_NUMBER='(0,0,0,0,0,0,0,0,DA19,0,0,0,0,0,0,0,0,0,0,0,0,0,0,0,0,0,0,0,0,0,0,0,0,0,0,0,0,0,0,0)';
      BIDIRECTIONAL='TRUE';
      INPUT_LOAD='(-0.01,0.01)';
      OUTPUT_LOAD='(1.0,-1.0)';
    'MIB_DATA15':
      PIN_NUMBER='(0,0,0,0,0,0,0,0,CP21,0,0,0,0,0,0,0,0,0,0,0,0,0,0,0,0,0,0,0,0,0,0,0,0,0,0,0,0,0,0,0)';
      BIDIRECTIONAL='TRUE';
      INPUT_LOAD='(-0.01,0.01)';
      OUTPUT_LOAD='(1.0,-1.0)';
    'MIB_DATA9':
      PIN_NUMBER='(0,0,0,0,0,0,0,0,CJ21,0,0,0,0,0,0,0,0,0,0,0,0,0,0,0,0,0,0,0,0,0,0,0,0,0,0,0,0,0,0,0)';
      BIDIRECTIONAL='TRUE';
      INPUT_LOAD='(-0.01,0.01)';
      OUTPUT_LOAD='(1.0,-1.0)';
    'MIB_CHECK6':
      PIN_NUMBER='(0,0,0,0,0,0,0,0,BU19,0,0,0,0,0,0,0,0,0,0,0,0,0,0,0,0,0,0,0,0,0,0,0,0,0,0,0,0,0,0,0)';
      BIDIRECTIONAL='TRUE';
      INPUT_LOAD='(-0.01,0.01)';
      OUTPUT_LOAD='(1.0,-1.0)';
    'MIB_CA1':
      PIN_NUMBER='(0,0,0,0,0,0,0,0,BH21,0,0,0,0,0,0,0,0,0,0,0,0,0,0,0,0,0,0,0,0,0,0,0,0,0,0,0,0,0,0,0)';
      OUTPUT_LOAD='(1.0,-1.0)';
    'MIA_DQS_L8':
      PIN_NUMBER='(0,0,0,0,0,0,0,0,AF21,0,0,0,0,0,0,0,0,0,0,0,0,0,0,0,0,0,0,0,0,0,0,0,0,0,0,0,0,0,0,0)';
      BIDIRECTIONAL='TRUE';
      INPUT_LOAD='(-0.01,0.01)';
      OUTPUT_LOAD='(1.0,-1.0)';
    'MIA_DQS_H4':
      PIN_NUMBER='(0,0,0,0,0,0,0,0,AL19,0,0,0,0,0,0,0,0,0,0,0,0,0,0,0,0,0,0,0,0,0,0,0,0,0,0,0,0,0,0,0)';
      BIDIRECTIONAL='TRUE';
      INPUT_LOAD='(-0.01,0.01)';
      OUTPUT_LOAD='(1.0,-1.0)';
    'MIA_DATA9':
      PIN_NUMBER='(0,0,0,0,0,0,0,0,M21,0,0,0,0,0,0,0,0,0,0,0,0,0,0,0,0,0,0,0,0,0,0,0,0,0,0,0,0,0,0,0)';
      BIDIRECTIONAL='TRUE';
      INPUT_LOAD='(-0.01,0.01)';
      OUTPUT_LOAD='(1.0,-1.0)';
    'MIA_CA2':
      PIN_NUMBER='(0,0,0,0,0,0,0,0,AY21,0,0,0,0,0,0,0,0,0,0,0,0,0,0,0,0,0,0,0,0,0,0,0,0,0,0,0,0,0,0,0)';
      OUTPUT_LOAD='(1.0,-1.0)';
    'MIB_DQS_L3':
      PIN_NUMBER='(0,0,0,0,0,0,0,0,DC19,0,0,0,0,0,0,0,0,0,0,0,0,0,0,0,0,0,0,0,0,0,0,0,0,0,0,0,0,0,0,0)';
      BIDIRECTIONAL='TRUE';
      INPUT_LOAD='(-0.01,0.01)';
      OUTPUT_LOAD='(1.0,-1.0)';
    'MIB_DATA27':
      PIN_NUMBER='(0,0,0,0,0,0,0,0,DB21,0,0,0,0,0,0,0,0,0,0,0,0,0,0,0,0,0,0,0,0,0,0,0,0,0,0,0,0,0,0,0)';
      BIDIRECTIONAL='TRUE';
      INPUT_LOAD='(-0.01,0.01)';
      OUTPUT_LOAD='(1.0,-1.0)';
    'MIB_DATA16':
      PIN_NUMBER='(0,0,0,0,0,0,0,0,CP20,0,0,0,0,0,0,0,0,0,0,0,0,0,0,0,0,0,0,0,0,0,0,0,0,0,0,0,0,0,0,0)';
      BIDIRECTIONAL='TRUE';
      INPUT_LOAD='(-0.01,0.01)';
      OUTPUT_LOAD='(1.0,-1.0)';
    'MIB_CHECK7':
      PIN_NUMBER='(0,0,0,0,0,0,0,0,BV21,0,0,0,0,0,0,0,0,0,0,0,0,0,0,0,0,0,0,0,0,0,0,0,0,0,0,0,0,0,0,0)';
      BIDIRECTIONAL='TRUE';
      INPUT_LOAD='(-0.01,0.01)';
      OUTPUT_LOAD='(1.0,-1.0)';
    'MIB_CA2':
      PIN_NUMBER='(0,0,0,0,0,0,0,0,BH20,0,0,0,0,0,0,0,0,0,0,0,0,0,0,0,0,0,0,0,0,0,0,0,0,0,0,0,0,0,0,0)';
      OUTPUT_LOAD='(1.0,-1.0)';
    'MIB0_RSP_L':
      PIN_NUMBER='(0,0,0,0,0,0,0,0,BP20,0,0,0,0,0,0,0,0,0,0,0,0,0,0,0,0,0,0,0,0,0,0,0,0,0,0,0,0,0,0,0)';
      INPUT_LOAD='(-0.01,0.01)';
    'MIA_DQS_L9':
      PIN_NUMBER='(0,0,0,0,0,0,0,0,AM21,0,0,0,0,0,0,0,0,0,0,0,0,0,0,0,0,0,0,0,0,0,0,0,0,0,0,0,0,0,0,0)';
      BIDIRECTIONAL='TRUE';
      INPUT_LOAD='(-0.01,0.01)';
      OUTPUT_LOAD='(1.0,-1.0)';
    'MIA_DQS_H5':
      PIN_NUMBER='(0,0,0,0,0,0,0,0,J21,0,0,0,0,0,0,0,0,0,0,0,0,0,0,0,0,0,0,0,0,0,0,0,0,0,0,0,0,0,0,0)';
      BIDIRECTIONAL='TRUE';
      INPUT_LOAD='(-0.01,0.01)';
      OUTPUT_LOAD='(1.0,-1.0)';
    'MIA_CA3':
      PIN_NUMBER='(0,0,0,0,0,0,0,0,BA21,0,0,0,0,0,0,0,0,0,0,0,0,0,0,0,0,0,0,0,0,0,0,0,0,0,0,0,0,0,0,0)';
      OUTPUT_LOAD='(1.0,-1.0)';
    'MIB_DQS_L4':
      PIN_NUMBER='(0,0,0,0,0,0,0,0,BW21,0,0,0,0,0,0,0,0,0,0,0,0,0,0,0,0,0,0,0,0,0,0,0,0,0,0,0,0,0,0,0)';
      BIDIRECTIONAL='TRUE';
      INPUT_LOAD='(-0.01,0.01)';
      OUTPUT_LOAD='(1.0,-1.0)';
    'MIB_DQS_H0':
      PIN_NUMBER='(0,0,0,0,0,0,0,0,CD20,0,0,0,0,0,0,0,0,0,0,0,0,0,0,0,0,0,0,0,0,0,0,0,0,0,0,0,0,0,0,0)';
      BIDIRECTIONAL='TRUE';
      INPUT_LOAD='(-0.01,0.01)';
      OUTPUT_LOAD='(1.0,-1.0)';
    'MIB_DATA28':
      PIN_NUMBER='(0,0,0,0,0,0,0,0,DD20,0,0,0,0,0,0,0,0,0,0,0,0,0,0,0,0,0,0,0,0,0,0,0,0,0,0,0,0,0,0,0)';
      BIDIRECTIONAL='TRUE';
      INPUT_LOAD='(-0.01,0.01)';
      OUTPUT_LOAD='(1.0,-1.0)';
    'MIB_DATA17':
      PIN_NUMBER='(0,0,0,0,0,0,0,0,CR21,0,0,0,0,0,0,0,0,0,0,0,0,0,0,0,0,0,0,0,0,0,0,0,0,0,0,0,0,0,0,0)';
      BIDIRECTIONAL='TRUE';
      INPUT_LOAD='(-0.01,0.01)';
      OUTPUT_LOAD='(1.0,-1.0)';
    'MIB_CA3':
      PIN_NUMBER='(0,0,0,0,0,0,0,0,BJ19,0,0,0,0,0,0,0,0,0,0,0,0,0,0,0,0,0,0,0,0,0,0,0,0,0,0,0,0,0,0,0)';
      OUTPUT_LOAD='(1.0,-1.0)';
    'MIB1_RSP_L':
      PIN_NUMBER='(0,0,0,0,0,0,0,0,BR19,0,0,0,0,0,0,0,0,0,0,0,0,0,0,0,0,0,0,0,0,0,0,0,0,0,0,0,0,0,0,0)';
      INPUT_LOAD='(-0.01,0.01)';
    'MIA_DQS_H6':
      PIN_NUMBER='(0,0,0,0,0,0,0,0,R21,0,0,0,0,0,0,0,0,0,0,0,0,0,0,0,0,0,0,0,0,0,0,0,0,0,0,0,0,0,0,0)';
      BIDIRECTIONAL='TRUE';
      INPUT_LOAD='(-0.01,0.01)';
      OUTPUT_LOAD='(1.0,-1.0)';
    'MIA_CA4':
      PIN_NUMBER='(0,0,0,0,0,0,0,0,BA19,0,0,0,0,0,0,0,0,0,0,0,0,0,0,0,0,0,0,0,0,0,0,0,0,0,0,0,0,0,0,0)';
      OUTPUT_LOAD='(1.0,-1.0)';
    'MIB_DQS_L5':
      PIN_NUMBER='(0,0,0,0,0,0,0,0,CE21,0,0,0,0,0,0,0,0,0,0,0,0,0,0,0,0,0,0,0,0,0,0,0,0,0,0,0,0,0,0,0)';
      BIDIRECTIONAL='TRUE';
      INPUT_LOAD='(-0.01,0.01)';
      OUTPUT_LOAD='(1.0,-1.0)';
    'MIB_DQS_H1':
      PIN_NUMBER='(0,0,0,0,0,0,0,0,CK20,0,0,0,0,0,0,0,0,0,0,0,0,0,0,0,0,0,0,0,0,0,0,0,0,0,0,0,0,0,0,0)';
      BIDIRECTIONAL='TRUE';
      INPUT_LOAD='(-0.01,0.01)';
      OUTPUT_LOAD='(1.0,-1.0)';
    'MIB_DATA29':
      PIN_NUMBER='(0,0,0,0,0,0,0,0,DE21,0,0,0,0,0,0,0,0,0,0,0,0,0,0,0,0,0,0,0,0,0,0,0,0,0,0,0,0,0,0,0)';
      BIDIRECTIONAL='TRUE';
      INPUT_LOAD='(-0.01,0.01)';
      OUTPUT_LOAD='(1.0,-1.0)';
    'MIB_DATA18':
      PIN_NUMBER='(0,0,0,0,0,0,0,0,CR19,0,0,0,0,0,0,0,0,0,0,0,0,0,0,0,0,0,0,0,0,0,0,0,0,0,0,0,0,0,0,0)';
      BIDIRECTIONAL='TRUE';
      INPUT_LOAD='(-0.01,0.01)';
      OUTPUT_LOAD='(1.0,-1.0)';
    'MIB_CA4':
      PIN_NUMBER='(0,0,0,0,0,0,0,0,BJ21,0,0,0,0,0,0,0,0,0,0,0,0,0,0,0,0,0,0,0,0,0,0,0,0,0,0,0,0,0,0,0)';
      OUTPUT_LOAD='(1.0,-1.0)';
    'MIA_DQS_H7':
      PIN_NUMBER='(0,0,0,0,0,0,0,0,AA21,0,0,0,0,0,0,0,0,0,0,0,0,0,0,0,0,0,0,0,0,0,0,0,0,0,0,0,0,0,0,0)';
      BIDIRECTIONAL='TRUE';
      INPUT_LOAD='(-0.01,0.01)';
      OUTPUT_LOAD='(1.0,-1.0)';
    'MIA_CA5':
      PIN_NUMBER='(0,0,0,0,0,0,0,0,BB20,0,0,0,0,0,0,0,0,0,0,0,0,0,0,0,0,0,0,0,0,0,0,0,0,0,0,0,0,0,0,0)';
      OUTPUT_LOAD='(1.0,-1.0)';
    'MIA1_CS_L0':
      PIN_NUMBER='(0,0,0,0,0,0,0,0,AV20,0,0,0,0,0,0,0,0,0,0,0,0,0,0,0,0,0,0,0,0,0,0,0,0,0,0,0,0,0,0,0)';
      OUTPUT_LOAD='(1.0,-1.0)';
    'MIA0_CS_L0':
      PIN_NUMBER='(0,0,0,0,0,0,0,0,AU19,0,0,0,0,0,0,0,0,0,0,0,0,0,0,0,0,0,0,0,0,0,0,0,0,0,0,0,0,0,0,0)';
      OUTPUT_LOAD='(1.0,-1.0)';
    'MI1_CLK_H':
      PIN_NUMBER='(0,0,0,0,0,0,0,0,BF20,0,0,0,0,0,0,0,0,0,0,0,0,0,0,0,0,0,0,0,0,0,0,0,0,0,0,0,0,0,0,0)';
      OUTPUT_LOAD='(1.0,-1.0)';
    'MI0_CLK_H':
      PIN_NUMBER='(0,0,0,0,0,0,0,0,BC19,0,0,0,0,0,0,0,0,0,0,0,0,0,0,0,0,0,0,0,0,0,0,0,0,0,0,0,0,0,0,0)';
      OUTPUT_LOAD='(1.0,-1.0)';
    'MIB_DQS_L6':
      PIN_NUMBER='(0,0,0,0,0,0,0,0,CL21,0,0,0,0,0,0,0,0,0,0,0,0,0,0,0,0,0,0,0,0,0,0,0,0,0,0,0,0,0,0,0)';
      BIDIRECTIONAL='TRUE';
      INPUT_LOAD='(-0.01,0.01)';
      OUTPUT_LOAD='(1.0,-1.0)';
    'MIB_DQS_H2':
      PIN_NUMBER='(0,0,0,0,0,0,0,0,CT20,0,0,0,0,0,0,0,0,0,0,0,0,0,0,0,0,0,0,0,0,0,0,0,0,0,0,0,0,0,0,0)';
      BIDIRECTIONAL='TRUE';
      INPUT_LOAD='(-0.01,0.01)';
      OUTPUT_LOAD='(1.0,-1.0)';
    'MIB_DATA19':
      PIN_NUMBER='(0,0,0,0,0,0,0,0,CT21,0,0,0,0,0,0,0,0,0,0,0,0,0,0,0,0,0,0,0,0,0,0,0,0,0,0,0,0,0,0,0)';
      BIDIRECTIONAL='TRUE';
      INPUT_LOAD='(-0.01,0.01)';
      OUTPUT_LOAD='(1.0,-1.0)';
    'MIB_CA5':
      PIN_NUMBER='(0,0,0,0,0,0,0,0,BK21,0,0,0,0,0,0,0,0,0,0,0,0,0,0,0,0,0,0,0,0,0,0,0,0,0,0,0,0,0,0,0)';
      OUTPUT_LOAD='(1.0,-1.0)';
    'MIA_DQS_H8':
      PIN_NUMBER='(0,0,0,0,0,0,0,0,AG21,0,0,0,0,0,0,0,0,0,0,0,0,0,0,0,0,0,0,0,0,0,0,0,0,0,0,0,0,0,0,0)';
      BIDIRECTIONAL='TRUE';
      INPUT_LOAD='(-0.01,0.01)';
      OUTPUT_LOAD='(1.0,-1.0)';
    'MIA_DATA30':
      PIN_NUMBER='(0,0,0,0,0,0,0,0,AH20,0,0,0,0,0,0,0,0,0,0,0,0,0,0,0,0,0,0,0,0,0,0,0,0,0,0,0,0,0,0,0)';
      BIDIRECTIONAL='TRUE';
      INPUT_LOAD='(-0.01,0.01)';
      OUTPUT_LOAD='(1.0,-1.0)';
    'MIA_CA6':
      PIN_NUMBER='(0,0,0,0,0,0,0,0,BB21,0,0,0,0,0,0,0,0,0,0,0,0,0,0,0,0,0,0,0,0,0,0,0,0,0,0,0,0,0,0,0)';
      OUTPUT_LOAD='(1.0,-1.0)';
    'MIA1_CS_L1':
      PIN_NUMBER='(0,0,0,0,0,0,0,0,AW21,0,0,0,0,0,0,0,0,0,0,0,0,0,0,0,0,0,0,0,0,0,0,0,0,0,0,0,0,0,0,0)';
      OUTPUT_LOAD='(1.0,-1.0)';
    'MIA0_CS_L1':
      PIN_NUMBER='(0,0,0,0,0,0,0,0,AV21,0,0,0,0,0,0,0,0,0,0,0,0,0,0,0,0,0,0,0,0,0,0,0,0,0,0,0,0,0,0,0)';
      OUTPUT_LOAD='(1.0,-1.0)';
    'MIB_DQS_L7':
      PIN_NUMBER='(0,0,0,0,0,0,0,0,CU21,0,0,0,0,0,0,0,0,0,0,0,0,0,0,0,0,0,0,0,0,0,0,0,0,0,0,0,0,0,0,0)';
      BIDIRECTIONAL='TRUE';
      INPUT_LOAD='(-0.01,0.01)';
      OUTPUT_LOAD='(1.0,-1.0)';
    'MIB_DQS_H3':
      PIN_NUMBER='(0,0,0,0,0,0,0,0,DB20,0,0,0,0,0,0,0,0,0,0,0,0,0,0,0,0,0,0,0,0,0,0,0,0,0,0,0,0,0,0,0)';
      BIDIRECTIONAL='TRUE';
      INPUT_LOAD='(-0.01,0.01)';
      OUTPUT_LOAD='(1.0,-1.0)';
    'MIB_CA6':
      PIN_NUMBER='(0,0,0,0,0,0,0,0,BK20,0,0,0,0,0,0,0,0,0,0,0,0,0,0,0,0,0,0,0,0,0,0,0,0,0,0,0,0,0,0,0)';
      OUTPUT_LOAD='(1.0,-1.0)';
    'MIA_DQS_H9':
      PIN_NUMBER='(0,0,0,0,0,0,0,0,AN21,0,0,0,0,0,0,0,0,0,0,0,0,0,0,0,0,0,0,0,0,0,0,0,0,0,0,0,0,0,0,0)';
      BIDIRECTIONAL='TRUE';
      INPUT_LOAD='(-0.01,0.01)';
      OUTPUT_LOAD='(1.0,-1.0)';
    'MIA_DATA31':
      PIN_NUMBER='(0,0,0,0,0,0,0,0,AJ21,0,0,0,0,0,0,0,0,0,0,0,0,0,0,0,0,0,0,0,0,0,0,0,0,0,0,0,0,0,0,0)';
      BIDIRECTIONAL='TRUE';
      INPUT_LOAD='(-0.01,0.01)';
      OUTPUT_LOAD='(1.0,-1.0)';
    'MIA_DATA20':
      PIN_NUMBER='(0,0,0,0,0,0,0,0,AA19,0,0,0,0,0,0,0,0,0,0,0,0,0,0,0,0,0,0,0,0,0,0,0,0,0,0,0,0,0,0,0)';
      BIDIRECTIONAL='TRUE';
      INPUT_LOAD='(-0.01,0.01)';
      OUTPUT_LOAD='(1.0,-1.0)';
    'MIA_CHECK0':
      PIN_NUMBER='(0,0,0,0,0,0,0,0,AJ19,0,0,0,0,0,0,0,0,0,0,0,0,0,0,0,0,0,0,0,0,0,0,0,0,0,0,0,0,0,0,0)';
      BIDIRECTIONAL='TRUE';
      INPUT_LOAD='(-0.01,0.01)';
      OUTPUT_LOAD='(1.0,-1.0)';
    'MIB_DQS_L8':
      PIN_NUMBER='(0,0,0,0,0,0,0,0,DC21,0,0,0,0,0,0,0,0,0,0,0,0,0,0,0,0,0,0,0,0,0,0,0,0,0,0,0,0,0,0,0)';
      BIDIRECTIONAL='TRUE';
      INPUT_LOAD='(-0.01,0.01)';
      OUTPUT_LOAD='(1.0,-1.0)';
    'MIB_DQS_H4':
      PIN_NUMBER='(0,0,0,0,0,0,0,0,BY21,0,0,0,0,0,0,0,0,0,0,0,0,0,0,0,0,0,0,0,0,0,0,0,0,0,0,0,0,0,0,0)';
      BIDIRECTIONAL='TRUE';
      INPUT_LOAD='(-0.01,0.01)';
      OUTPUT_LOAD='(1.0,-1.0)';
    'MIA_DATA21':
      PIN_NUMBER='(0,0,0,0,0,0,0,0,AB21,0,0,0,0,0,0,0,0,0,0,0,0,0,0,0,0,0,0,0,0,0,0,0,0,0,0,0,0,0,0,0)';
      BIDIRECTIONAL='TRUE';
      INPUT_LOAD='(-0.01,0.01)';
      OUTPUT_LOAD='(1.0,-1.0)';
    'MIA_DATA10':
      PIN_NUMBER='(0,0,0,0,0,0,0,0,M20,0,0,0,0,0,0,0,0,0,0,0,0,0,0,0,0,0,0,0,0,0,0,0,0,0,0,0,0,0,0,0)';
      BIDIRECTIONAL='TRUE';
      INPUT_LOAD='(-0.01,0.01)';
      OUTPUT_LOAD='(1.0,-1.0)';
    'MIA_CHECK1':
      PIN_NUMBER='(0,0,0,0,0,0,0,0,AK21,0,0,0,0,0,0,0,0,0,0,0,0,0,0,0,0,0,0,0,0,0,0,0,0,0,0,0,0,0,0,0)';
      BIDIRECTIONAL='TRUE';
      INPUT_LOAD='(-0.01,0.01)';
      OUTPUT_LOAD='(1.0,-1.0)';
    'MIB_DQS_L9':
      PIN_NUMBER='(0,0,0,0,0,0,0,0,BW19,0,0,0,0,0,0,0,0,0,0,0,0,0,0,0,0,0,0,0,0,0,0,0,0,0,0,0,0,0,0,0)';
      BIDIRECTIONAL='TRUE';
      INPUT_LOAD='(-0.01,0.01)';
      OUTPUT_LOAD='(1.0,-1.0)';
    'MIB_DQS_H5':
      PIN_NUMBER='(0,0,0,0,0,0,0,0,CF21,0,0,0,0,0,0,0,0,0,0,0,0,0,0,0,0,0,0,0,0,0,0,0,0,0,0,0,0,0,0,0)';
      BIDIRECTIONAL='TRUE';
      INPUT_LOAD='(-0.01,0.01)';
      OUTPUT_LOAD='(1.0,-1.0)';
    'MIA_DATA22':
      PIN_NUMBER='(0,0,0,0,0,0,0,0,AB20,0,0,0,0,0,0,0,0,0,0,0,0,0,0,0,0,0,0,0,0,0,0,0,0,0,0,0,0,0,0,0)';
      BIDIRECTIONAL='TRUE';
      INPUT_LOAD='(-0.01,0.01)';
      OUTPUT_LOAD='(1.0,-1.0)';
    'MIA_DATA11':
      PIN_NUMBER='(0,0,0,0,0,0,0,0,N21,0,0,0,0,0,0,0,0,0,0,0,0,0,0,0,0,0,0,0,0,0,0,0,0,0,0,0,0,0,0,0)';
      BIDIRECTIONAL='TRUE';
      INPUT_LOAD='(-0.01,0.01)';
      OUTPUT_LOAD='(1.0,-1.0)';
    'MIA_CHECK2':
      PIN_NUMBER='(0,0,0,0,0,0,0,0,AK20,0,0,0,0,0,0,0,0,0,0,0,0,0,0,0,0,0,0,0,0,0,0,0,0,0,0,0,0,0,0,0)';
      BIDIRECTIONAL='TRUE';
      INPUT_LOAD='(-0.01,0.01)';
      OUTPUT_LOAD='(1.0,-1.0)';
    'MI1_CLK_L':
      PIN_NUMBER='(0,0,0,0,0,0,0,0,BG19,0,0,0,0,0,0,0,0,0,0,0,0,0,0,0,0,0,0,0,0,0,0,0,0,0,0,0,0,0,0,0)';
      OUTPUT_LOAD='(1.0,-1.0)';
    'MI0_CLK_L':
      PIN_NUMBER='(0,0,0,0,0,0,0,0,BD20,0,0,0,0,0,0,0,0,0,0,0,0,0,0,0,0,0,0,0,0,0,0,0,0,0,0,0,0,0,0,0)';
      OUTPUT_LOAD='(1.0,-1.0)';
    'MI_RESET_L':
      PIN_NUMBER='(0,0,0,0,0,0,0,0,AU21,0,0,0,0,0,0,0,0,0,0,0,0,0,0,0,0,0,0,0,0,0,0,0,0,0,0,0,0,0,0,0)';
      OUTPUT_LOAD='(1.0,-1.0)';
    'MIB_DQS_H6':
      PIN_NUMBER='(0,0,0,0,0,0,0,0,CM21,0,0,0,0,0,0,0,0,0,0,0,0,0,0,0,0,0,0,0,0,0,0,0,0,0,0,0,0,0,0,0)';
      BIDIRECTIONAL='TRUE';
      INPUT_LOAD='(-0.01,0.01)';
      OUTPUT_LOAD='(1.0,-1.0)';
    'MIB_DATA0':
      PIN_NUMBER='(0,0,0,0,0,0,0,0,CB20,0,0,0,0,0,0,0,0,0,0,0,0,0,0,0,0,0,0,0,0,0,0,0,0,0,0,0,0,0,0,0)';
      BIDIRECTIONAL='TRUE';
      INPUT_LOAD='(-0.01,0.01)';
      OUTPUT_LOAD='(1.0,-1.0)';
    'MIA_DATA23':
      PIN_NUMBER='(0,0,0,0,0,0,0,0,AC21,0,0,0,0,0,0,0,0,0,0,0,0,0,0,0,0,0,0,0,0,0,0,0,0,0,0,0,0,0,0,0)';
      BIDIRECTIONAL='TRUE';
      INPUT_LOAD='(-0.01,0.01)';
      OUTPUT_LOAD='(1.0,-1.0)';
    'MIA_DATA12':
      PIN_NUMBER='(0,0,0,0,0,0,0,0,R19,0,0,0,0,0,0,0,0,0,0,0,0,0,0,0,0,0,0,0,0,0,0,0,0,0,0,0,0,0,0,0)';
      BIDIRECTIONAL='TRUE';
      INPUT_LOAD='(-0.01,0.01)';
      OUTPUT_LOAD='(1.0,-1.0)';
    'MIA_DATA0':
      PIN_NUMBER='(0,0,0,0,0,0,0,0,E19,0,0,0,0,0,0,0,0,0,0,0,0,0,0,0,0,0,0,0,0,0,0,0,0,0,0,0,0,0,0,0)';
      BIDIRECTIONAL='TRUE';
      INPUT_LOAD='(-0.01,0.01)';
      OUTPUT_LOAD='(1.0,-1.0)';
    'MIA_CHECK3':
      PIN_NUMBER='(0,0,0,0,0,0,0,0,AL21,0,0,0,0,0,0,0,0,0,0,0,0,0,0,0,0,0,0,0,0,0,0,0,0,0,0,0,0,0,0,0)';
      BIDIRECTIONAL='TRUE';
      INPUT_LOAD='(-0.01,0.01)';
      OUTPUT_LOAD='(1.0,-1.0)';
    'MIB_DQS_H7':
      PIN_NUMBER='(0,0,0,0,0,0,0,0,CV21,0,0,0,0,0,0,0,0,0,0,0,0,0,0,0,0,0,0,0,0,0,0,0,0,0,0,0,0,0,0,0)';
      BIDIRECTIONAL='TRUE';
      INPUT_LOAD='(-0.01,0.01)';
      OUTPUT_LOAD='(1.0,-1.0)';
    'MIB_DATA1':
      PIN_NUMBER='(0,0,0,0,0,0,0,0,CC21,0,0,0,0,0,0,0,0,0,0,0,0,0,0,0,0,0,0,0,0,0,0,0,0,0,0,0,0,0,0,0)';
      BIDIRECTIONAL='TRUE';
      INPUT_LOAD='(-0.01,0.01)';
      OUTPUT_LOAD='(1.0,-1.0)';
    'MIB0_CS_L0':
      PIN_NUMBER='(0,0,0,0,0,0,0,0,BM21,0,0,0,0,0,0,0,0,0,0,0,0,0,0,0,0,0,0,0,0,0,0,0,0,0,0,0,0,0,0,0)';
      OUTPUT_LOAD='(1.0,-1.0)';
    'MIA_DQS_L0':
      PIN_NUMBER='(0,0,0,0,0,0,0,0,H20,0,0,0,0,0,0,0,0,0,0,0,0,0,0,0,0,0,0,0,0,0,0,0,0,0,0,0,0,0,0,0)';
      BIDIRECTIONAL='TRUE';
      INPUT_LOAD='(-0.01,0.01)';
      OUTPUT_LOAD='(1.0,-1.0)';
    'MIA_DATA24':
      PIN_NUMBER='(0,0,0,0,0,0,0,0,AC19,0,0,0,0,0,0,0,0,0,0,0,0,0,0,0,0,0,0,0,0,0,0,0,0,0,0,0,0,0,0,0)';
      BIDIRECTIONAL='TRUE';
      INPUT_LOAD='(-0.01,0.01)';
      OUTPUT_LOAD='(1.0,-1.0)';
    'MIA_DATA13':
      PIN_NUMBER='(0,0,0,0,0,0,0,0,T21,0,0,0,0,0,0,0,0,0,0,0,0,0,0,0,0,0,0,0,0,0,0,0,0,0,0,0,0,0,0,0)';
      BIDIRECTIONAL='TRUE';
      INPUT_LOAD='(-0.01,0.01)';
      OUTPUT_LOAD='(1.0,-1.0)';
    'MIA_DATA1':
      PIN_NUMBER='(0,0,0,0,0,0,0,0,F21,0,0,0,0,0,0,0,0,0,0,0,0,0,0,0,0,0,0,0,0,0,0,0,0,0,0,0,0,0,0,0)';
      BIDIRECTIONAL='TRUE';
      INPUT_LOAD='(-0.01,0.01)';
      OUTPUT_LOAD='(1.0,-1.0)';
    'MIA_CHECK4':
      PIN_NUMBER='(0,0,0,0,0,0,0,0,AN19,0,0,0,0,0,0,0,0,0,0,0,0,0,0,0,0,0,0,0,0,0,0,0,0,0,0,0,0,0,0,0)';
      BIDIRECTIONAL='TRUE';
      INPUT_LOAD='(-0.01,0.01)';
      OUTPUT_LOAD='(1.0,-1.0)';
    'MIB_DQS_H8':
      PIN_NUMBER='(0,0,0,0,0,0,0,0,DD21,0,0,0,0,0,0,0,0,0,0,0,0,0,0,0,0,0,0,0,0,0,0,0,0,0,0,0,0,0,0,0)';
      BIDIRECTIONAL='TRUE';
      INPUT_LOAD='(-0.01,0.01)';
      OUTPUT_LOAD='(1.0,-1.0)';
    'MIB_DATA30':
      PIN_NUMBER='(0,0,0,0,0,0,0,0,DE19,0,0,0,0,0,0,0,0,0,0,0,0,0,0,0,0,0,0,0,0,0,0,0,0,0,0,0,0,0,0,0)';
      BIDIRECTIONAL='TRUE';
      INPUT_LOAD='(-0.01,0.01)';
      OUTPUT_LOAD='(1.0,-1.0)';
    'MIB_DATA2':
      PIN_NUMBER='(0,0,0,0,0,0,0,0,CC19,0,0,0,0,0,0,0,0,0,0,0,0,0,0,0,0,0,0,0,0,0,0,0,0,0,0,0,0,0,0,0)';
      BIDIRECTIONAL='TRUE';
      INPUT_LOAD='(-0.01,0.01)';
      OUTPUT_LOAD='(1.0,-1.0)';
    'MIB1_CS_L0':
      PIN_NUMBER='(0,0,0,0,0,0,0,0,BL19,0,0,0,0,0,0,0,0,0,0,0,0,0,0,0,0,0,0,0,0,0,0,0,0,0,0,0,0,0,0,0)';
      OUTPUT_LOAD='(1.0,-1.0)';
    'MIB0_CS_L1':
      PIN_NUMBER='(0,0,0,0,0,0,0,0,BN19,0,0,0,0,0,0,0,0,0,0,0,0,0,0,0,0,0,0,0,0,0,0,0,0,0,0,0,0,0,0,0)';
      OUTPUT_LOAD='(1.0,-1.0)';
    'MIA_DQS_L1':
      PIN_NUMBER='(0,0,0,0,0,0,0,0,P20,0,0,0,0,0,0,0,0,0,0,0,0,0,0,0,0,0,0,0,0,0,0,0,0,0,0,0,0,0,0,0)';
      BIDIRECTIONAL='TRUE';
      INPUT_LOAD='(-0.01,0.01)';
      OUTPUT_LOAD='(1.0,-1.0)';
    'MIA_DATA25':
      PIN_NUMBER='(0,0,0,0,0,0,0,0,AD21,0,0,0,0,0,0,0,0,0,0,0,0,0,0,0,0,0,0,0,0,0,0,0,0,0,0,0,0,0,0,0)';
      BIDIRECTIONAL='TRUE';
      INPUT_LOAD='(-0.01,0.01)';
      OUTPUT_LOAD='(1.0,-1.0)';
    'MIA_DATA14':
      PIN_NUMBER='(0,0,0,0,0,0,0,0,T20,0,0,0,0,0,0,0,0,0,0,0,0,0,0,0,0,0,0,0,0,0,0,0,0,0,0,0,0,0,0,0)';
      BIDIRECTIONAL='TRUE';
      INPUT_LOAD='(-0.01,0.01)';
      OUTPUT_LOAD='(1.0,-1.0)';
    'MIA_DATA2':
      PIN_NUMBER='(0,0,0,0,0,0,0,0,F20,0,0,0,0,0,0,0,0,0,0,0,0,0,0,0,0,0,0,0,0,0,0,0,0,0,0,0,0,0,0,0)';
      BIDIRECTIONAL='TRUE';
      INPUT_LOAD='(-0.01,0.01)';
      OUTPUT_LOAD='(1.0,-1.0)';
    'MIA_CHECK5':
      PIN_NUMBER='(0,0,0,0,0,0,0,0,AP21,0,0,0,0,0,0,0,0,0,0,0,0,0,0,0,0,0,0,0,0,0,0,0,0,0,0,0,0,0,0,0)';
      BIDIRECTIONAL='TRUE';
      INPUT_LOAD='(-0.01,0.01)';
      OUTPUT_LOAD='(1.0,-1.0)';
    'MIB_DQS_H9':
      PIN_NUMBER='(0,0,0,0,0,0,0,0,BV20,0,0,0,0,0,0,0,0,0,0,0,0,0,0,0,0,0,0,0,0,0,0,0,0,0,0,0,0,0,0,0)';
      BIDIRECTIONAL='TRUE';
      INPUT_LOAD='(-0.01,0.01)';
      OUTPUT_LOAD='(1.0,-1.0)';
    'MIB_DATA31':
      PIN_NUMBER='(0,0,0,0,0,0,0,0,DF21,0,0,0,0,0,0,0,0,0,0,0,0,0,0,0,0,0,0,0,0,0,0,0,0,0,0,0,0,0,0,0)';
      BIDIRECTIONAL='TRUE';
      INPUT_LOAD='(-0.01,0.01)';
      OUTPUT_LOAD='(1.0,-1.0)';
    'MIB_DATA20':
      PIN_NUMBER='(0,0,0,0,0,0,0,0,CV20,0,0,0,0,0,0,0,0,0,0,0,0,0,0,0,0,0,0,0,0,0,0,0,0,0,0,0,0,0,0,0)';
      BIDIRECTIONAL='TRUE';
      INPUT_LOAD='(-0.01,0.01)';
      OUTPUT_LOAD='(1.0,-1.0)';
    'MIB_DATA3':
      PIN_NUMBER='(0,0,0,0,0,0,0,0,CD21,0,0,0,0,0,0,0,0,0,0,0,0,0,0,0,0,0,0,0,0,0,0,0,0,0,0,0,0,0,0,0)';
      BIDIRECTIONAL='TRUE';
      INPUT_LOAD='(-0.01,0.01)';
      OUTPUT_LOAD='(1.0,-1.0)';
    'MIB_CHECK0':
      PIN_NUMBER='(0,0,0,0,0,0,0,0,BY20,0,0,0,0,0,0,0,0,0,0,0,0,0,0,0,0,0,0,0,0,0,0,0,0,0,0,0,0,0,0,0)';
      BIDIRECTIONAL='TRUE';
      INPUT_LOAD='(-0.01,0.01)';
      OUTPUT_LOAD='(1.0,-1.0)';
    'MIB1_CS_L1':
      PIN_NUMBER='(0,0,0,0,0,0,0,0,BM20,0,0,0,0,0,0,0,0,0,0,0,0,0,0,0,0,0,0,0,0,0,0,0,0,0,0,0,0,0,0,0)';
      OUTPUT_LOAD='(1.0,-1.0)';
    'MIA_PAR':
      PIN_NUMBER='(0,0,0,0,0,0,0,0,BC21,0,0,0,0,0,0,0,0,0,0,0,0,0,0,0,0,0,0,0,0,0,0,0,0,0,0,0,0,0,0,0)';
      OUTPUT_LOAD='(1.0,-1.0)';
    'MIA_DQS_L2':
      PIN_NUMBER='(0,0,0,0,0,0,0,0,Y20,0,0,0,0,0,0,0,0,0,0,0,0,0,0,0,0,0,0,0,0,0,0,0,0,0,0,0,0,0,0,0)';
      BIDIRECTIONAL='TRUE';
      INPUT_LOAD='(-0.01,0.01)';
      OUTPUT_LOAD='(1.0,-1.0)';
    'MIA_DATA26':
      PIN_NUMBER='(0,0,0,0,0,0,0,0,AD20,0,0,0,0,0,0,0,0,0,0,0,0,0,0,0,0,0,0,0,0,0,0,0,0,0,0,0,0,0,0,0)';
      BIDIRECTIONAL='TRUE';
      INPUT_LOAD='(-0.01,0.01)';
      OUTPUT_LOAD='(1.0,-1.0)';
    'MIA_DATA15':
      PIN_NUMBER='(0,0,0,0,0,0,0,0,U21,0,0,0,0,0,0,0,0,0,0,0,0,0,0,0,0,0,0,0,0,0,0,0,0,0,0,0,0,0,0,0)';
      BIDIRECTIONAL='TRUE';
      INPUT_LOAD='(-0.01,0.01)';
      OUTPUT_LOAD='(1.0,-1.0)';
    'MIA_DATA3':
      PIN_NUMBER='(0,0,0,0,0,0,0,0,G21,0,0,0,0,0,0,0,0,0,0,0,0,0,0,0,0,0,0,0,0,0,0,0,0,0,0,0,0,0,0,0)';
      BIDIRECTIONAL='TRUE';
      INPUT_LOAD='(-0.01,0.01)';
      OUTPUT_LOAD='(1.0,-1.0)';
    'MIA_CHECK6':
      PIN_NUMBER='(0,0,0,0,0,0,0,0,AP20,0,0,0,0,0,0,0,0,0,0,0,0,0,0,0,0,0,0,0,0,0,0,0,0,0,0,0,0,0,0,0)';
      BIDIRECTIONAL='TRUE';
      INPUT_LOAD='(-0.01,0.01)';
      OUTPUT_LOAD='(1.0,-1.0)';
    'MIB_PAR':
      PIN_NUMBER='(0,0,0,0,0,0,0,0,BL21,0,0,0,0,0,0,0,0,0,0,0,0,0,0,0,0,0,0,0,0,0,0,0,0,0,0,0,0,0,0,0)';
      OUTPUT_LOAD='(1.0,-1.0)';
    'MIB_DATA21':
      PIN_NUMBER='(0,0,0,0,0,0,0,0,CW21,0,0,0,0,0,0,0,0,0,0,0,0,0,0,0,0,0,0,0,0,0,0,0,0,0,0,0,0,0,0,0)';
      BIDIRECTIONAL='TRUE';
      INPUT_LOAD='(-0.01,0.01)';
      OUTPUT_LOAD='(1.0,-1.0)';
    'MIB_DATA10':
      PIN_NUMBER='(0,0,0,0,0,0,0,0,CJ19,0,0,0,0,0,0,0,0,0,0,0,0,0,0,0,0,0,0,0,0,0,0,0,0,0,0,0,0,0,0,0)';
      BIDIRECTIONAL='TRUE';
      INPUT_LOAD='(-0.01,0.01)';
      OUTPUT_LOAD='(1.0,-1.0)';
    'MIB_DATA4':
      PIN_NUMBER='(0,0,0,0,0,0,0,0,CF20,0,0,0,0,0,0,0,0,0,0,0,0,0,0,0,0,0,0,0,0,0,0,0,0,0,0,0,0,0,0,0)';
      BIDIRECTIONAL='TRUE';
      INPUT_LOAD='(-0.01,0.01)';
      OUTPUT_LOAD='(1.0,-1.0)';
    'MIB_CHECK1':
      PIN_NUMBER='(0,0,0,0,0,0,0,0,CA21,0,0,0,0,0,0,0,0,0,0,0,0,0,0,0,0,0,0,0,0,0,0,0,0,0,0,0,0,0,0,0)';
      BIDIRECTIONAL='TRUE';
      INPUT_LOAD='(-0.01,0.01)';
      OUTPUT_LOAD='(1.0,-1.0)';
    'MIA_DQS_L3':
      PIN_NUMBER='(0,0,0,0,0,0,0,0,AF20,0,0,0,0,0,0,0,0,0,0,0,0,0,0,0,0,0,0,0,0,0,0,0,0,0,0,0,0,0,0,0)';
      BIDIRECTIONAL='TRUE';
      INPUT_LOAD='(-0.01,0.01)';
      OUTPUT_LOAD='(1.0,-1.0)';
    'MIA_DATA27':
      PIN_NUMBER='(0,0,0,0,0,0,0,0,AE21,0,0,0,0,0,0,0,0,0,0,0,0,0,0,0,0,0,0,0,0,0,0,0,0,0,0,0,0,0,0,0)';
      BIDIRECTIONAL='TRUE';
      INPUT_LOAD='(-0.01,0.01)';
      OUTPUT_LOAD='(1.0,-1.0)';
    'MIA_DATA16':
      PIN_NUMBER='(0,0,0,0,0,0,0,0,U19,0,0,0,0,0,0,0,0,0,0,0,0,0,0,0,0,0,0,0,0,0,0,0,0,0,0,0,0,0,0,0)';
      BIDIRECTIONAL='TRUE';
      INPUT_LOAD='(-0.01,0.01)';
      OUTPUT_LOAD='(1.0,-1.0)';
    'MIA_DATA4':
      PIN_NUMBER='(0,0,0,0,0,0,0,0,J19,0,0,0,0,0,0,0,0,0,0,0,0,0,0,0,0,0,0,0,0,0,0,0,0,0,0,0,0,0,0,0)';
      BIDIRECTIONAL='TRUE';
      INPUT_LOAD='(-0.01,0.01)';
      OUTPUT_LOAD='(1.0,-1.0)';
    'MIA_CHECK7':
      PIN_NUMBER='(0,0,0,0,0,0,0,0,AR21,0,0,0,0,0,0,0,0,0,0,0,0,0,0,0,0,0,0,0,0,0,0,0,0,0,0,0,0,0,0,0)';
      BIDIRECTIONAL='TRUE';
      INPUT_LOAD='(-0.01,0.01)';
      OUTPUT_LOAD='(1.0,-1.0)';
    'MIA1_RSP_L':
      PIN_NUMBER='(0,0,0,0,0,0,0,0,BP21,0,0,0,0,0,0,0,0,0,0,0,0,0,0,0,0,0,0,0,0,0,0,0,0,0,0,0,0,0,0,0)';
      INPUT_LOAD='(-0.01,0.01)';
    'MIA0_RSP_L':
      PIN_NUMBER='(0,0,0,0,0,0,0,0,BN21,0,0,0,0,0,0,0,0,0,0,0,0,0,0,0,0,0,0,0,0,0,0,0,0,0,0,0,0,0,0,0)';
      INPUT_LOAD='(-0.01,0.01)';
    'MI_ALERT_L':
      PIN_NUMBER='(0,0,0,0,0,0,0,0,AT21,0,0,0,0,0,0,0,0,0,0,0,0,0,0,0,0,0,0,0,0,0,0,0,0,0,0,0,0,0,0,0)';
      INPUT_LOAD='(-0.01,0.01)';
    'MIB_DATA22':
      PIN_NUMBER='(0,0,0,0,0,0,0,0,CW19,0,0,0,0,0,0,0,0,0,0,0,0,0,0,0,0,0,0,0,0,0,0,0,0,0,0,0,0,0,0,0)';
      BIDIRECTIONAL='TRUE';
      INPUT_LOAD='(-0.01,0.01)';
      OUTPUT_LOAD='(1.0,-1.0)';
    'MIB_DATA11':
      PIN_NUMBER='(0,0,0,0,0,0,0,0,CK21,0,0,0,0,0,0,0,0,0,0,0,0,0,0,0,0,0,0,0,0,0,0,0,0,0,0,0,0,0,0,0)';
      BIDIRECTIONAL='TRUE';
      INPUT_LOAD='(-0.01,0.01)';
      OUTPUT_LOAD='(1.0,-1.0)';
    'MIB_DATA5':
      PIN_NUMBER='(0,0,0,0,0,0,0,0,CG21,0,0,0,0,0,0,0,0,0,0,0,0,0,0,0,0,0,0,0,0,0,0,0,0,0,0,0,0,0,0,0)';
      BIDIRECTIONAL='TRUE';
      INPUT_LOAD='(-0.01,0.01)';
      OUTPUT_LOAD='(1.0,-1.0)';
    'MIB_CHECK2':
      PIN_NUMBER='(0,0,0,0,0,0,0,0,CA19,0,0,0,0,0,0,0,0,0,0,0,0,0,0,0,0,0,0,0,0,0,0,0,0,0,0,0,0,0,0,0)';
      BIDIRECTIONAL='TRUE';
      INPUT_LOAD='(-0.01,0.01)';
      OUTPUT_LOAD='(1.0,-1.0)';
    'MIA_DQS_L4':
      PIN_NUMBER='(0,0,0,0,0,0,0,0,AM20,0,0,0,0,0,0,0,0,0,0,0,0,0,0,0,0,0,0,0,0,0,0,0,0,0,0,0,0,0,0,0)';
      BIDIRECTIONAL='TRUE';
      INPUT_LOAD='(-0.01,0.01)';
      OUTPUT_LOAD='(1.0,-1.0)';
    'MIA_DQS_H0':
      PIN_NUMBER='(0,0,0,0,0,0,0,0,G19,0,0,0,0,0,0,0,0,0,0,0,0,0,0,0,0,0,0,0,0,0,0,0,0,0,0,0,0,0,0,0)';
      BIDIRECTIONAL='TRUE';
      INPUT_LOAD='(-0.01,0.01)';
      OUTPUT_LOAD='(1.0,-1.0)';
    'MIA_DATA28':
      PIN_NUMBER='(0,0,0,0,0,0,0,0,AG19,0,0,0,0,0,0,0,0,0,0,0,0,0,0,0,0,0,0,0,0,0,0,0,0,0,0,0,0,0,0,0)';
      BIDIRECTIONAL='TRUE';
      INPUT_LOAD='(-0.01,0.01)';
      OUTPUT_LOAD='(1.0,-1.0)';
    'MIA_DATA17':
      PIN_NUMBER='(0,0,0,0,0,0,0,0,V21,0,0,0,0,0,0,0,0,0,0,0,0,0,0,0,0,0,0,0,0,0,0,0,0,0,0,0,0,0,0,0)';
      BIDIRECTIONAL='TRUE';
      INPUT_LOAD='(-0.01,0.01)';
      OUTPUT_LOAD='(1.0,-1.0)';
    'MIA_DATA5':
      PIN_NUMBER='(0,0,0,0,0,0,0,0,K21,0,0,0,0,0,0,0,0,0,0,0,0,0,0,0,0,0,0,0,0,0,0,0,0,0,0,0,0,0,0,0)';
      BIDIRECTIONAL='TRUE';
      INPUT_LOAD='(-0.01,0.01)';
      OUTPUT_LOAD='(1.0,-1.0)';
    'TEST39I':
      PIN_NUMBER='(0,0,0,0,0,0,0,0,BF21,0,0,0,0,0,0,0,0,0,0,0,0,0,0,0,0,0,0,0,0,0,0,0,0,0,0,0,0,0,0,0)';
      OUTPUT_LOAD='(1.0,-1.0)';
    'MJ_RESET_L':
      PIN_NUMBER='(0,0,0,0,0,0,0,0,0,AU17,0,0,0,0,0,0,0,0,0,0,0,0,0,0,0,0,0,0,0,0,0,0,0,0,0,0,0,0,0,0)';
      OUTPUT_LOAD='(1.0,-1.0)';
    'MJ_ALERT_L':
      PIN_NUMBER='(0,0,0,0,0,0,0,0,0,AT18,0,0,0,0,0,0,0,0,0,0,0,0,0,0,0,0,0,0,0,0,0,0,0,0,0,0,0,0,0,0)';
      INPUT_LOAD='(-0.01,0.01)';
    'MJB_PAR':
      PIN_NUMBER='(0,0,0,0,0,0,0,0,0,BL17,0,0,0,0,0,0,0,0,0,0,0,0,0,0,0,0,0,0,0,0,0,0,0,0,0,0,0,0,0,0)';
      OUTPUT_LOAD='(1.0,-1.0)';
    'MJB_DQS_L9':
      PIN_NUMBER='(0,0,0,0,0,0,0,0,0,BW16,0,0,0,0,0,0,0,0,0,0,0,0,0,0,0,0,0,0,0,0,0,0,0,0,0,0,0,0,0,0)';
      BIDIRECTIONAL='TRUE';
      INPUT_LOAD='(-0.01,0.01)';
      OUTPUT_LOAD='(1.0,-1.0)';
    'MJB_DQS_L8':
      PIN_NUMBER='(0,0,0,0,0,0,0,0,0,DC17,0,0,0,0,0,0,0,0,0,0,0,0,0,0,0,0,0,0,0,0,0,0,0,0,0,0,0,0,0,0)';
      BIDIRECTIONAL='TRUE';
      INPUT_LOAD='(-0.01,0.01)';
      OUTPUT_LOAD='(1.0,-1.0)';
    'MJB_DQS_L7':
      PIN_NUMBER='(0,0,0,0,0,0,0,0,0,CU17,0,0,0,0,0,0,0,0,0,0,0,0,0,0,0,0,0,0,0,0,0,0,0,0,0,0,0,0,0,0)';
      BIDIRECTIONAL='TRUE';
      INPUT_LOAD='(-0.01,0.01)';
      OUTPUT_LOAD='(1.0,-1.0)';
    'MJB_DQS_L6':
      PIN_NUMBER='(0,0,0,0,0,0,0,0,0,CL17,0,0,0,0,0,0,0,0,0,0,0,0,0,0,0,0,0,0,0,0,0,0,0,0,0,0,0,0,0,0)';
      BIDIRECTIONAL='TRUE';
      INPUT_LOAD='(-0.01,0.01)';
      OUTPUT_LOAD='(1.0,-1.0)';
    'MJB_DQS_L5':
      PIN_NUMBER='(0,0,0,0,0,0,0,0,0,CE17,0,0,0,0,0,0,0,0,0,0,0,0,0,0,0,0,0,0,0,0,0,0,0,0,0,0,0,0,0,0)';
      BIDIRECTIONAL='TRUE';
      INPUT_LOAD='(-0.01,0.01)';
      OUTPUT_LOAD='(1.0,-1.0)';
    'MJB_DQS_L3':
      PIN_NUMBER='(0,0,0,0,0,0,0,0,0,DC16,0,0,0,0,0,0,0,0,0,0,0,0,0,0,0,0,0,0,0,0,0,0,0,0,0,0,0,0,0,0)';
      BIDIRECTIONAL='TRUE';
      INPUT_LOAD='(-0.01,0.01)';
      OUTPUT_LOAD='(1.0,-1.0)';
    'MJB_DQS_L2':
      PIN_NUMBER='(0,0,0,0,0,0,0,0,0,CU16,0,0,0,0,0,0,0,0,0,0,0,0,0,0,0,0,0,0,0,0,0,0,0,0,0,0,0,0,0,0)';
      BIDIRECTIONAL='TRUE';
      INPUT_LOAD='(-0.01,0.01)';
      OUTPUT_LOAD='(1.0,-1.0)';
    'MJB_DQS_L1':
      PIN_NUMBER='(0,0,0,0,0,0,0,0,0,CL16,0,0,0,0,0,0,0,0,0,0,0,0,0,0,0,0,0,0,0,0,0,0,0,0,0,0,0,0,0,0)';
      BIDIRECTIONAL='TRUE';
      INPUT_LOAD='(-0.01,0.01)';
      OUTPUT_LOAD='(1.0,-1.0)';
    'MJB_DQS_H9':
      PIN_NUMBER='(0,0,0,0,0,0,0,0,0,BV16,0,0,0,0,0,0,0,0,0,0,0,0,0,0,0,0,0,0,0,0,0,0,0,0,0,0,0,0,0,0)';
      BIDIRECTIONAL='TRUE';
      INPUT_LOAD='(-0.01,0.01)';
      OUTPUT_LOAD='(1.0,-1.0)';
    'MJB_DQS_H8':
      PIN_NUMBER='(0,0,0,0,0,0,0,0,0,DD18,0,0,0,0,0,0,0,0,0,0,0,0,0,0,0,0,0,0,0,0,0,0,0,0,0,0,0,0,0,0)';
      BIDIRECTIONAL='TRUE';
      INPUT_LOAD='(-0.01,0.01)';
      OUTPUT_LOAD='(1.0,-1.0)';
    'MJB_DQS_H7':
      PIN_NUMBER='(0,0,0,0,0,0,0,0,0,CV18,0,0,0,0,0,0,0,0,0,0,0,0,0,0,0,0,0,0,0,0,0,0,0,0,0,0,0,0,0,0)';
      BIDIRECTIONAL='TRUE';
      INPUT_LOAD='(-0.01,0.01)';
      OUTPUT_LOAD='(1.0,-1.0)';
    'MJB_DQS_H6':
      PIN_NUMBER='(0,0,0,0,0,0,0,0,0,CM18,0,0,0,0,0,0,0,0,0,0,0,0,0,0,0,0,0,0,0,0,0,0,0,0,0,0,0,0,0,0)';
      BIDIRECTIONAL='TRUE';
      INPUT_LOAD='(-0.01,0.01)';
      OUTPUT_LOAD='(1.0,-1.0)';
    'MJB_DQS_H4':
      PIN_NUMBER='(0,0,0,0,0,0,0,0,0,BY18,0,0,0,0,0,0,0,0,0,0,0,0,0,0,0,0,0,0,0,0,0,0,0,0,0,0,0,0,0,0)';
      BIDIRECTIONAL='TRUE';
      INPUT_LOAD='(-0.01,0.01)';
      OUTPUT_LOAD='(1.0,-1.0)';
    'MJB_DQS_H3':
      PIN_NUMBER='(0,0,0,0,0,0,0,0,0,DB16,0,0,0,0,0,0,0,0,0,0,0,0,0,0,0,0,0,0,0,0,0,0,0,0,0,0,0,0,0,0)';
      BIDIRECTIONAL='TRUE';
      INPUT_LOAD='(-0.01,0.01)';
      OUTPUT_LOAD='(1.0,-1.0)';
    'MJB_DQS_H2':
      PIN_NUMBER='(0,0,0,0,0,0,0,0,0,CT16,0,0,0,0,0,0,0,0,0,0,0,0,0,0,0,0,0,0,0,0,0,0,0,0,0,0,0,0,0,0)';
      BIDIRECTIONAL='TRUE';
      INPUT_LOAD='(-0.01,0.01)';
      OUTPUT_LOAD='(1.0,-1.0)';
    'MJB_DQS_H1':
      PIN_NUMBER='(0,0,0,0,0,0,0,0,0,CK16,0,0,0,0,0,0,0,0,0,0,0,0,0,0,0,0,0,0,0,0,0,0,0,0,0,0,0,0,0,0)';
      BIDIRECTIONAL='TRUE';
      INPUT_LOAD='(-0.01,0.01)';
      OUTPUT_LOAD='(1.0,-1.0)';
    'MJB_DQS_H0':
      PIN_NUMBER='(0,0,0,0,0,0,0,0,0,CD16,0,0,0,0,0,0,0,0,0,0,0,0,0,0,0,0,0,0,0,0,0,0,0,0,0,0,0,0,0,0)';
      BIDIRECTIONAL='TRUE';
      INPUT_LOAD='(-0.01,0.01)';
      OUTPUT_LOAD='(1.0,-1.0)';
    'MJB_DATA31':
      PIN_NUMBER='(0,0,0,0,0,0,0,0,0,DF16,0,0,0,0,0,0,0,0,0,0,0,0,0,0,0,0,0,0,0,0,0,0,0,0,0,0,0,0,0,0)';
      BIDIRECTIONAL='TRUE';
      INPUT_LOAD='(-0.01,0.01)';
      OUTPUT_LOAD='(1.0,-1.0)';
    'MJB_DATA30':
      PIN_NUMBER='(0,0,0,0,0,0,0,0,0,DE16,0,0,0,0,0,0,0,0,0,0,0,0,0,0,0,0,0,0,0,0,0,0,0,0,0,0,0,0,0,0)';
      BIDIRECTIONAL='TRUE';
      INPUT_LOAD='(-0.01,0.01)';
      OUTPUT_LOAD='(1.0,-1.0)';
    'MJB_DATA29':
      PIN_NUMBER='(0,0,0,0,0,0,0,0,0,DE17,0,0,0,0,0,0,0,0,0,0,0,0,0,0,0,0,0,0,0,0,0,0,0,0,0,0,0,0,0,0)';
      BIDIRECTIONAL='TRUE';
      INPUT_LOAD='(-0.01,0.01)';
      OUTPUT_LOAD='(1.0,-1.0)';
    'MJB_DATA28':
      PIN_NUMBER='(0,0,0,0,0,0,0,0,0,DD16,0,0,0,0,0,0,0,0,0,0,0,0,0,0,0,0,0,0,0,0,0,0,0,0,0,0,0,0,0,0)';
      BIDIRECTIONAL='TRUE';
      INPUT_LOAD='(-0.01,0.01)';
      OUTPUT_LOAD='(1.0,-1.0)';
    'MJB_DATA27':
      PIN_NUMBER='(0,0,0,0,0,0,0,0,0,DB18,0,0,0,0,0,0,0,0,0,0,0,0,0,0,0,0,0,0,0,0,0,0,0,0,0,0,0,0,0,0)';
      BIDIRECTIONAL='TRUE';
      INPUT_LOAD='(-0.01,0.01)';
      OUTPUT_LOAD='(1.0,-1.0)';
    'MJB_DATA26':
      PIN_NUMBER='(0,0,0,0,0,0,0,0,0,DA16,0,0,0,0,0,0,0,0,0,0,0,0,0,0,0,0,0,0,0,0,0,0,0,0,0,0,0,0,0,0)';
      BIDIRECTIONAL='TRUE';
      INPUT_LOAD='(-0.01,0.01)';
      OUTPUT_LOAD='(1.0,-1.0)';
    'MJB_DATA25':
      PIN_NUMBER='(0,0,0,0,0,0,0,0,0,DA17,0,0,0,0,0,0,0,0,0,0,0,0,0,0,0,0,0,0,0,0,0,0,0,0,0,0,0,0,0,0)';
      BIDIRECTIONAL='TRUE';
      INPUT_LOAD='(-0.01,0.01)';
      OUTPUT_LOAD='(1.0,-1.0)';
    'MJB_DATA24':
      PIN_NUMBER='(0,0,0,0,0,0,0,0,0,CY16,0,0,0,0,0,0,0,0,0,0,0,0,0,0,0,0,0,0,0,0,0,0,0,0,0,0,0,0,0,0)';
      BIDIRECTIONAL='TRUE';
      INPUT_LOAD='(-0.01,0.01)';
      OUTPUT_LOAD='(1.0,-1.0)';
    'MJB_DATA23':
      PIN_NUMBER='(0,0,0,0,0,0,0,0,0,CY18,0,0,0,0,0,0,0,0,0,0,0,0,0,0,0,0,0,0,0,0,0,0,0,0,0,0,0,0,0,0)';
      BIDIRECTIONAL='TRUE';
      INPUT_LOAD='(-0.01,0.01)';
      OUTPUT_LOAD='(1.0,-1.0)';
    'MJB_DATA22':
      PIN_NUMBER='(0,0,0,0,0,0,0,0,0,CW16,0,0,0,0,0,0,0,0,0,0,0,0,0,0,0,0,0,0,0,0,0,0,0,0,0,0,0,0,0,0)';
      BIDIRECTIONAL='TRUE';
      INPUT_LOAD='(-0.01,0.01)';
      OUTPUT_LOAD='(1.0,-1.0)';
    'MJB_DATA21':
      PIN_NUMBER='(0,0,0,0,0,0,0,0,0,CW17,0,0,0,0,0,0,0,0,0,0,0,0,0,0,0,0,0,0,0,0,0,0,0,0,0,0,0,0,0,0)';
      BIDIRECTIONAL='TRUE';
      INPUT_LOAD='(-0.01,0.01)';
      OUTPUT_LOAD='(1.0,-1.0)';
    'MJB_DATA20':
      PIN_NUMBER='(0,0,0,0,0,0,0,0,0,CV16,0,0,0,0,0,0,0,0,0,0,0,0,0,0,0,0,0,0,0,0,0,0,0,0,0,0,0,0,0,0)';
      BIDIRECTIONAL='TRUE';
      INPUT_LOAD='(-0.01,0.01)';
      OUTPUT_LOAD='(1.0,-1.0)';
    'MJB_DATA19':
      PIN_NUMBER='(0,0,0,0,0,0,0,0,0,CT18,0,0,0,0,0,0,0,0,0,0,0,0,0,0,0,0,0,0,0,0,0,0,0,0,0,0,0,0,0,0)';
      BIDIRECTIONAL='TRUE';
      INPUT_LOAD='(-0.01,0.01)';
      OUTPUT_LOAD='(1.0,-1.0)';
    'MJB_DATA18':
      PIN_NUMBER='(0,0,0,0,0,0,0,0,0,CR16,0,0,0,0,0,0,0,0,0,0,0,0,0,0,0,0,0,0,0,0,0,0,0,0,0,0,0,0,0,0)';
      BIDIRECTIONAL='TRUE';
      INPUT_LOAD='(-0.01,0.01)';
      OUTPUT_LOAD='(1.0,-1.0)';
    'MJB_DATA17':
      PIN_NUMBER='(0,0,0,0,0,0,0,0,0,CR17,0,0,0,0,0,0,0,0,0,0,0,0,0,0,0,0,0,0,0,0,0,0,0,0,0,0,0,0,0,0)';
      BIDIRECTIONAL='TRUE';
      INPUT_LOAD='(-0.01,0.01)';
      OUTPUT_LOAD='(1.0,-1.0)';
    'MJB_DATA16':
      PIN_NUMBER='(0,0,0,0,0,0,0,0,0,CP16,0,0,0,0,0,0,0,0,0,0,0,0,0,0,0,0,0,0,0,0,0,0,0,0,0,0,0,0,0,0)';
      BIDIRECTIONAL='TRUE';
      INPUT_LOAD='(-0.01,0.01)';
      OUTPUT_LOAD='(1.0,-1.0)';
    'MJB_DATA15':
      PIN_NUMBER='(0,0,0,0,0,0,0,0,0,CP18,0,0,0,0,0,0,0,0,0,0,0,0,0,0,0,0,0,0,0,0,0,0,0,0,0,0,0,0,0,0)';
      BIDIRECTIONAL='TRUE';
      INPUT_LOAD='(-0.01,0.01)';
      OUTPUT_LOAD='(1.0,-1.0)';
    'MJB_DATA14':
      PIN_NUMBER='(0,0,0,0,0,0,0,0,0,CN16,0,0,0,0,0,0,0,0,0,0,0,0,0,0,0,0,0,0,0,0,0,0,0,0,0,0,0,0,0,0)';
      BIDIRECTIONAL='TRUE';
      INPUT_LOAD='(-0.01,0.01)';
      OUTPUT_LOAD='(1.0,-1.0)';
    'MJB_DATA13':
      PIN_NUMBER='(0,0,0,0,0,0,0,0,0,CN17,0,0,0,0,0,0,0,0,0,0,0,0,0,0,0,0,0,0,0,0,0,0,0,0,0,0,0,0,0,0)';
      BIDIRECTIONAL='TRUE';
      INPUT_LOAD='(-0.01,0.01)';
      OUTPUT_LOAD='(1.0,-1.0)';
    'MJB_DATA12':
      PIN_NUMBER='(0,0,0,0,0,0,0,0,0,CM16,0,0,0,0,0,0,0,0,0,0,0,0,0,0,0,0,0,0,0,0,0,0,0,0,0,0,0,0,0,0)';
      BIDIRECTIONAL='TRUE';
      INPUT_LOAD='(-0.01,0.01)';
      OUTPUT_LOAD='(1.0,-1.0)';
    'MJB_DATA11':
      PIN_NUMBER='(0,0,0,0,0,0,0,0,0,CK18,0,0,0,0,0,0,0,0,0,0,0,0,0,0,0,0,0,0,0,0,0,0,0,0,0,0,0,0,0,0)';
      BIDIRECTIONAL='TRUE';
      INPUT_LOAD='(-0.01,0.01)';
      OUTPUT_LOAD='(1.0,-1.0)';
    'MJB_DATA10':
      PIN_NUMBER='(0,0,0,0,0,0,0,0,0,CJ16,0,0,0,0,0,0,0,0,0,0,0,0,0,0,0,0,0,0,0,0,0,0,0,0,0,0,0,0,0,0)';
      BIDIRECTIONAL='TRUE';
      INPUT_LOAD='(-0.01,0.01)';
      OUTPUT_LOAD='(1.0,-1.0)';
    'MJB_DATA9':
      PIN_NUMBER='(0,0,0,0,0,0,0,0,0,CJ17,0,0,0,0,0,0,0,0,0,0,0,0,0,0,0,0,0,0,0,0,0,0,0,0,0,0,0,0,0,0)';
      BIDIRECTIONAL='TRUE';
      INPUT_LOAD='(-0.01,0.01)';
      OUTPUT_LOAD='(1.0,-1.0)';
    'MJB_DATA8':
      PIN_NUMBER='(0,0,0,0,0,0,0,0,0,CH16,0,0,0,0,0,0,0,0,0,0,0,0,0,0,0,0,0,0,0,0,0,0,0,0,0,0,0,0,0,0)';
      BIDIRECTIONAL='TRUE';
      INPUT_LOAD='(-0.01,0.01)';
      OUTPUT_LOAD='(1.0,-1.0)';
    'MJB_DATA2':
      PIN_NUMBER='(0,0,0,0,0,0,0,0,0,CC16,0,0,0,0,0,0,0,0,0,0,0,0,0,0,0,0,0,0,0,0,0,0,0,0,0,0,0,0,0,0)';
      BIDIRECTIONAL='TRUE';
      INPUT_LOAD='(-0.01,0.01)';
      OUTPUT_LOAD='(1.0,-1.0)';
    'MJB_DATA1':
      PIN_NUMBER='(0,0,0,0,0,0,0,0,0,CC17,0,0,0,0,0,0,0,0,0,0,0,0,0,0,0,0,0,0,0,0,0,0,0,0,0,0,0,0,0,0)';
      BIDIRECTIONAL='TRUE';
      INPUT_LOAD='(-0.01,0.01)';
      OUTPUT_LOAD='(1.0,-1.0)';
    'MJB_CHECK7':
      PIN_NUMBER='(0,0,0,0,0,0,0,0,0,BV18,0,0,0,0,0,0,0,0,0,0,0,0,0,0,0,0,0,0,0,0,0,0,0,0,0,0,0,0,0,0)';
      BIDIRECTIONAL='TRUE';
      INPUT_LOAD='(-0.01,0.01)';
      OUTPUT_LOAD='(1.0,-1.0)';
    'MJB_CHECK6':
      PIN_NUMBER='(0,0,0,0,0,0,0,0,0,BU16,0,0,0,0,0,0,0,0,0,0,0,0,0,0,0,0,0,0,0,0,0,0,0,0,0,0,0,0,0,0)';
      BIDIRECTIONAL='TRUE';
      INPUT_LOAD='(-0.01,0.01)';
      OUTPUT_LOAD='(1.0,-1.0)';
    'MJB_CHECK5':
      PIN_NUMBER='(0,0,0,0,0,0,0,0,0,BU17,0,0,0,0,0,0,0,0,0,0,0,0,0,0,0,0,0,0,0,0,0,0,0,0,0,0,0,0,0,0)';
      BIDIRECTIONAL='TRUE';
      INPUT_LOAD='(-0.01,0.01)';
      OUTPUT_LOAD='(1.0,-1.0)';
    'MJB_CHECK4':
      PIN_NUMBER='(0,0,0,0,0,0,0,0,0,BT16,0,0,0,0,0,0,0,0,0,0,0,0,0,0,0,0,0,0,0,0,0,0,0,0,0,0,0,0,0,0)';
      BIDIRECTIONAL='TRUE';
      INPUT_LOAD='(-0.01,0.01)';
      OUTPUT_LOAD='(1.0,-1.0)';
    'MJB_CHECK3':
      PIN_NUMBER='(0,0,0,0,0,0,0,0,0,CB18,0,0,0,0,0,0,0,0,0,0,0,0,0,0,0,0,0,0,0,0,0,0,0,0,0,0,0,0,0,0)';
      BIDIRECTIONAL='TRUE';
      INPUT_LOAD='(-0.01,0.01)';
      OUTPUT_LOAD='(1.0,-1.0)';
    'MJB_CHECK2':
      PIN_NUMBER='(0,0,0,0,0,0,0,0,0,CA16,0,0,0,0,0,0,0,0,0,0,0,0,0,0,0,0,0,0,0,0,0,0,0,0,0,0,0,0,0,0)';
      BIDIRECTIONAL='TRUE';
      INPUT_LOAD='(-0.01,0.01)';
      OUTPUT_LOAD='(1.0,-1.0)';
    'MJB_CHECK1':
      PIN_NUMBER='(0,0,0,0,0,0,0,0,0,CA17,0,0,0,0,0,0,0,0,0,0,0,0,0,0,0,0,0,0,0,0,0,0,0,0,0,0,0,0,0,0)';
      BIDIRECTIONAL='TRUE';
      INPUT_LOAD='(-0.01,0.01)';
      OUTPUT_LOAD='(1.0,-1.0)';
    'MJB_CHECK0':
      PIN_NUMBER='(0,0,0,0,0,0,0,0,0,BY16,0,0,0,0,0,0,0,0,0,0,0,0,0,0,0,0,0,0,0,0,0,0,0,0,0,0,0,0,0,0)';
      BIDIRECTIONAL='TRUE';
      INPUT_LOAD='(-0.01,0.01)';
      OUTPUT_LOAD='(1.0,-1.0)';
    'MJB_CA6':
      PIN_NUMBER='(0,0,0,0,0,0,0,0,0,BK16,0,0,0,0,0,0,0,0,0,0,0,0,0,0,0,0,0,0,0,0,0,0,0,0,0,0,0,0,0,0)';
      OUTPUT_LOAD='(1.0,-1.0)';
    'MJB_CA5':
      PIN_NUMBER='(0,0,0,0,0,0,0,0,0,BK18,0,0,0,0,0,0,0,0,0,0,0,0,0,0,0,0,0,0,0,0,0,0,0,0,0,0,0,0,0,0)';
      OUTPUT_LOAD='(1.0,-1.0)';
    'MJB_CA4':
      PIN_NUMBER='(0,0,0,0,0,0,0,0,0,BJ17,0,0,0,0,0,0,0,0,0,0,0,0,0,0,0,0,0,0,0,0,0,0,0,0,0,0,0,0,0,0)';
      OUTPUT_LOAD='(1.0,-1.0)';
    'MJB_CA3':
      PIN_NUMBER='(0,0,0,0,0,0,0,0,0,BJ16,0,0,0,0,0,0,0,0,0,0,0,0,0,0,0,0,0,0,0,0,0,0,0,0,0,0,0,0,0,0)';
      OUTPUT_LOAD='(1.0,-1.0)';
    'MJB_CA2':
      PIN_NUMBER='(0,0,0,0,0,0,0,0,0,BH16,0,0,0,0,0,0,0,0,0,0,0,0,0,0,0,0,0,0,0,0,0,0,0,0,0,0,0,0,0,0)';
      OUTPUT_LOAD='(1.0,-1.0)';
    'MJB_CA1':
      PIN_NUMBER='(0,0,0,0,0,0,0,0,0,BH18,0,0,0,0,0,0,0,0,0,0,0,0,0,0,0,0,0,0,0,0,0,0,0,0,0,0,0,0,0,0)';
      OUTPUT_LOAD='(1.0,-1.0)';
    'MJB_CA0':
      PIN_NUMBER='(0,0,0,0,0,0,0,0,0,BG17,0,0,0,0,0,0,0,0,0,0,0,0,0,0,0,0,0,0,0,0,0,0,0,0,0,0,0,0,0,0)';
      OUTPUT_LOAD='(1.0,-1.0)';
    'MJB1_RSP_L':
      PIN_NUMBER='(0,0,0,0,0,0,0,0,0,BR16,0,0,0,0,0,0,0,0,0,0,0,0,0,0,0,0,0,0,0,0,0,0,0,0,0,0,0,0,0,0)';
      INPUT_LOAD='(-0.01,0.01)';
    'MJB1_CS_L1':
      PIN_NUMBER='(0,0,0,0,0,0,0,0,0,BM16,0,0,0,0,0,0,0,0,0,0,0,0,0,0,0,0,0,0,0,0,0,0,0,0,0,0,0,0,0,0)';
      OUTPUT_LOAD='(1.0,-1.0)';
    'MJB1_CS_L0':
      PIN_NUMBER='(0,0,0,0,0,0,0,0,0,BL16,0,0,0,0,0,0,0,0,0,0,0,0,0,0,0,0,0,0,0,0,0,0,0,0,0,0,0,0,0,0)';
      OUTPUT_LOAD='(1.0,-1.0)';
    'MJB0_RSP_L':
      PIN_NUMBER='(0,0,0,0,0,0,0,0,0,BP16,0,0,0,0,0,0,0,0,0,0,0,0,0,0,0,0,0,0,0,0,0,0,0,0,0,0,0,0,0,0)';
      INPUT_LOAD='(-0.01,0.01)';
    'MJB0_CS_L1':
      PIN_NUMBER='(0,0,0,0,0,0,0,0,0,BN16,0,0,0,0,0,0,0,0,0,0,0,0,0,0,0,0,0,0,0,0,0,0,0,0,0,0,0,0,0,0)';
      OUTPUT_LOAD='(1.0,-1.0)';
    'MJB0_CS_L0':
      PIN_NUMBER='(0,0,0,0,0,0,0,0,0,BM18,0,0,0,0,0,0,0,0,0,0,0,0,0,0,0,0,0,0,0,0,0,0,0,0,0,0,0,0,0,0)';
      OUTPUT_LOAD='(1.0,-1.0)';
    'MJA_PAR':
      PIN_NUMBER='(0,0,0,0,0,0,0,0,0,BC17,0,0,0,0,0,0,0,0,0,0,0,0,0,0,0,0,0,0,0,0,0,0,0,0,0,0,0,0,0,0)';
      OUTPUT_LOAD='(1.0,-1.0)';
    'MJA_DQS_L9':
      PIN_NUMBER='(0,0,0,0,0,0,0,0,0,AM18,0,0,0,0,0,0,0,0,0,0,0,0,0,0,0,0,0,0,0,0,0,0,0,0,0,0,0,0,0,0)';
      BIDIRECTIONAL='TRUE';
      INPUT_LOAD='(-0.01,0.01)';
      OUTPUT_LOAD='(1.0,-1.0)';
    'MJA_DQS_L8':
      PIN_NUMBER='(0,0,0,0,0,0,0,0,0,AF18,0,0,0,0,0,0,0,0,0,0,0,0,0,0,0,0,0,0,0,0,0,0,0,0,0,0,0,0,0,0)';
      BIDIRECTIONAL='TRUE';
      INPUT_LOAD='(-0.01,0.01)';
      OUTPUT_LOAD='(1.0,-1.0)';
    'MJA_DQS_L6':
      PIN_NUMBER='(0,0,0,0,0,0,0,0,0,P18,0,0,0,0,0,0,0,0,0,0,0,0,0,0,0,0,0,0,0,0,0,0,0,0,0,0,0,0,0,0)';
      BIDIRECTIONAL='TRUE';
      INPUT_LOAD='(-0.01,0.01)';
      OUTPUT_LOAD='(1.0,-1.0)';
    'MJA_DQS_L3':
      PIN_NUMBER='(0,0,0,0,0,0,0,0,0,AF16,0,0,0,0,0,0,0,0,0,0,0,0,0,0,0,0,0,0,0,0,0,0,0,0,0,0,0,0,0,0)';
      BIDIRECTIONAL='TRUE';
      INPUT_LOAD='(-0.01,0.01)';
      OUTPUT_LOAD='(1.0,-1.0)';
    'MJA_DQS_L2':
      PIN_NUMBER='(0,0,0,0,0,0,0,0,0,Y16,0,0,0,0,0,0,0,0,0,0,0,0,0,0,0,0,0,0,0,0,0,0,0,0,0,0,0,0,0,0)';
      BIDIRECTIONAL='TRUE';
      INPUT_LOAD='(-0.01,0.01)';
      OUTPUT_LOAD='(1.0,-1.0)';
    'MJA_DQS_L1':
      PIN_NUMBER='(0,0,0,0,0,0,0,0,0,P16,0,0,0,0,0,0,0,0,0,0,0,0,0,0,0,0,0,0,0,0,0,0,0,0,0,0,0,0,0,0)';
      BIDIRECTIONAL='TRUE';
      INPUT_LOAD='(-0.01,0.01)';
      OUTPUT_LOAD='(1.0,-1.0)';
    'MJA_DQS_L0':
      PIN_NUMBER='(0,0,0,0,0,0,0,0,0,H16,0,0,0,0,0,0,0,0,0,0,0,0,0,0,0,0,0,0,0,0,0,0,0,0,0,0,0,0,0,0)';
      BIDIRECTIONAL='TRUE';
      INPUT_LOAD='(-0.01,0.01)';
      OUTPUT_LOAD='(1.0,-1.0)';
    'MJA_DQS_H9':
      PIN_NUMBER='(0,0,0,0,0,0,0,0,0,AN17,0,0,0,0,0,0,0,0,0,0,0,0,0,0,0,0,0,0,0,0,0,0,0,0,0,0,0,0,0,0)';
      BIDIRECTIONAL='TRUE';
      INPUT_LOAD='(-0.01,0.01)';
      OUTPUT_LOAD='(1.0,-1.0)';
    'MJA_DQS_H7':
      PIN_NUMBER='(0,0,0,0,0,0,0,0,0,AA17,0,0,0,0,0,0,0,0,0,0,0,0,0,0,0,0,0,0,0,0,0,0,0,0,0,0,0,0,0,0)';
      BIDIRECTIONAL='TRUE';
      INPUT_LOAD='(-0.01,0.01)';
      OUTPUT_LOAD='(1.0,-1.0)';
    'MJA_DQS_H6':
      PIN_NUMBER='(0,0,0,0,0,0,0,0,0,R17,0,0,0,0,0,0,0,0,0,0,0,0,0,0,0,0,0,0,0,0,0,0,0,0,0,0,0,0,0,0)';
      BIDIRECTIONAL='TRUE';
      INPUT_LOAD='(-0.01,0.01)';
      OUTPUT_LOAD='(1.0,-1.0)';
    'MJA_DQS_H5':
      PIN_NUMBER='(0,0,0,0,0,0,0,0,0,J17,0,0,0,0,0,0,0,0,0,0,0,0,0,0,0,0,0,0,0,0,0,0,0,0,0,0,0,0,0,0)';
      BIDIRECTIONAL='TRUE';
      INPUT_LOAD='(-0.01,0.01)';
      OUTPUT_LOAD='(1.0,-1.0)';
    'MJA_DQS_H3':
      PIN_NUMBER='(0,0,0,0,0,0,0,0,0,AE16,0,0,0,0,0,0,0,0,0,0,0,0,0,0,0,0,0,0,0,0,0,0,0,0,0,0,0,0,0,0)';
      BIDIRECTIONAL='TRUE';
      INPUT_LOAD='(-0.01,0.01)';
      OUTPUT_LOAD='(1.0,-1.0)';
    'MJA_DQS_H2':
      PIN_NUMBER='(0,0,0,0,0,0,0,0,0,W16,0,0,0,0,0,0,0,0,0,0,0,0,0,0,0,0,0,0,0,0,0,0,0,0,0,0,0,0,0,0)';
      BIDIRECTIONAL='TRUE';
      INPUT_LOAD='(-0.01,0.01)';
      OUTPUT_LOAD='(1.0,-1.0)';
    'MJA_DQS_H1':
      PIN_NUMBER='(0,0,0,0,0,0,0,0,0,N16,0,0,0,0,0,0,0,0,0,0,0,0,0,0,0,0,0,0,0,0,0,0,0,0,0,0,0,0,0,0)';
      BIDIRECTIONAL='TRUE';
      INPUT_LOAD='(-0.01,0.01)';
      OUTPUT_LOAD='(1.0,-1.0)';
    'MJA_DQS_H0':
      PIN_NUMBER='(0,0,0,0,0,0,0,0,0,G16,0,0,0,0,0,0,0,0,0,0,0,0,0,0,0,0,0,0,0,0,0,0,0,0,0,0,0,0,0,0)';
      BIDIRECTIONAL='TRUE';
      INPUT_LOAD='(-0.01,0.01)';
      OUTPUT_LOAD='(1.0,-1.0)';
    'MJA_DATA30':
      PIN_NUMBER='(0,0,0,0,0,0,0,0,0,AH16,0,0,0,0,0,0,0,0,0,0,0,0,0,0,0,0,0,0,0,0,0,0,0,0,0,0,0,0,0,0)';
      BIDIRECTIONAL='TRUE';
      INPUT_LOAD='(-0.01,0.01)';
      OUTPUT_LOAD='(1.0,-1.0)';
    'MJA_DATA29':
      PIN_NUMBER='(0,0,0,0,0,0,0,0,0,AH18,0,0,0,0,0,0,0,0,0,0,0,0,0,0,0,0,0,0,0,0,0,0,0,0,0,0,0,0,0,0)';
      BIDIRECTIONAL='TRUE';
      INPUT_LOAD='(-0.01,0.01)';
      OUTPUT_LOAD='(1.0,-1.0)';
    'MJA_DATA28':
      PIN_NUMBER='(0,0,0,0,0,0,0,0,0,AG16,0,0,0,0,0,0,0,0,0,0,0,0,0,0,0,0,0,0,0,0,0,0,0,0,0,0,0,0,0,0)';
      BIDIRECTIONAL='TRUE';
      INPUT_LOAD='(-0.01,0.01)';
      OUTPUT_LOAD='(1.0,-1.0)';
    'MJA_DATA27':
      PIN_NUMBER='(0,0,0,0,0,0,0,0,0,AE17,0,0,0,0,0,0,0,0,0,0,0,0,0,0,0,0,0,0,0,0,0,0,0,0,0,0,0,0,0,0)';
      BIDIRECTIONAL='TRUE';
      INPUT_LOAD='(-0.01,0.01)';
      OUTPUT_LOAD='(1.0,-1.0)';
    'MJA_DATA26':
      PIN_NUMBER='(0,0,0,0,0,0,0,0,0,AD16,0,0,0,0,0,0,0,0,0,0,0,0,0,0,0,0,0,0,0,0,0,0,0,0,0,0,0,0,0,0)';
      BIDIRECTIONAL='TRUE';
      INPUT_LOAD='(-0.01,0.01)';
      OUTPUT_LOAD='(1.0,-1.0)';
    'MJA_DATA25':
      PIN_NUMBER='(0,0,0,0,0,0,0,0,0,AD18,0,0,0,0,0,0,0,0,0,0,0,0,0,0,0,0,0,0,0,0,0,0,0,0,0,0,0,0,0,0)';
      BIDIRECTIONAL='TRUE';
      INPUT_LOAD='(-0.01,0.01)';
      OUTPUT_LOAD='(1.0,-1.0)';
    'MJA_DATA24':
      PIN_NUMBER='(0,0,0,0,0,0,0,0,0,AC16,0,0,0,0,0,0,0,0,0,0,0,0,0,0,0,0,0,0,0,0,0,0,0,0,0,0,0,0,0,0)';
      BIDIRECTIONAL='TRUE';
      INPUT_LOAD='(-0.01,0.01)';
      OUTPUT_LOAD='(1.0,-1.0)';
    'MJA_DATA23':
      PIN_NUMBER='(0,0,0,0,0,0,0,0,0,AC17,0,0,0,0,0,0,0,0,0,0,0,0,0,0,0,0,0,0,0,0,0,0,0,0,0,0,0,0,0,0)';
      BIDIRECTIONAL='TRUE';
      INPUT_LOAD='(-0.01,0.01)';
      OUTPUT_LOAD='(1.0,-1.0)';
    'MJA_DATA21':
      PIN_NUMBER='(0,0,0,0,0,0,0,0,0,AB18,0,0,0,0,0,0,0,0,0,0,0,0,0,0,0,0,0,0,0,0,0,0,0,0,0,0,0,0,0,0)';
      BIDIRECTIONAL='TRUE';
      INPUT_LOAD='(-0.01,0.01)';
      OUTPUT_LOAD='(1.0,-1.0)';
    'MJA_DATA20':
      PIN_NUMBER='(0,0,0,0,0,0,0,0,0,AA16,0,0,0,0,0,0,0,0,0,0,0,0,0,0,0,0,0,0,0,0,0,0,0,0,0,0,0,0,0,0)';
      BIDIRECTIONAL='TRUE';
      INPUT_LOAD='(-0.01,0.01)';
      OUTPUT_LOAD='(1.0,-1.0)';
    'MJA_DATA19':
      PIN_NUMBER='(0,0,0,0,0,0,0,0,0,W17,0,0,0,0,0,0,0,0,0,0,0,0,0,0,0,0,0,0,0,0,0,0,0,0,0,0,0,0,0,0)';
      BIDIRECTIONAL='TRUE';
      INPUT_LOAD='(-0.01,0.01)';
      OUTPUT_LOAD='(1.0,-1.0)';
    'MJA_DATA18':
      PIN_NUMBER='(0,0,0,0,0,0,0,0,0,V16,0,0,0,0,0,0,0,0,0,0,0,0,0,0,0,0,0,0,0,0,0,0,0,0,0,0,0,0,0,0)';
      BIDIRECTIONAL='TRUE';
      INPUT_LOAD='(-0.01,0.01)';
      OUTPUT_LOAD='(1.0,-1.0)';
    'MJA_DATA17':
      PIN_NUMBER='(0,0,0,0,0,0,0,0,0,V18,0,0,0,0,0,0,0,0,0,0,0,0,0,0,0,0,0,0,0,0,0,0,0,0,0,0,0,0,0,0)';
      BIDIRECTIONAL='TRUE';
      INPUT_LOAD='(-0.01,0.01)';
      OUTPUT_LOAD='(1.0,-1.0)';
    'MJA_DATA16':
      PIN_NUMBER='(0,0,0,0,0,0,0,0,0,U16,0,0,0,0,0,0,0,0,0,0,0,0,0,0,0,0,0,0,0,0,0,0,0,0,0,0,0,0,0,0)';
      BIDIRECTIONAL='TRUE';
      INPUT_LOAD='(-0.01,0.01)';
      OUTPUT_LOAD='(1.0,-1.0)';
    'MJA_DATA15':
      PIN_NUMBER='(0,0,0,0,0,0,0,0,0,U17,0,0,0,0,0,0,0,0,0,0,0,0,0,0,0,0,0,0,0,0,0,0,0,0,0,0,0,0,0,0)';
      BIDIRECTIONAL='TRUE';
      INPUT_LOAD='(-0.01,0.01)';
      OUTPUT_LOAD='(1.0,-1.0)';
    'MJA_DATA14':
      PIN_NUMBER='(0,0,0,0,0,0,0,0,0,T16,0,0,0,0,0,0,0,0,0,0,0,0,0,0,0,0,0,0,0,0,0,0,0,0,0,0,0,0,0,0)';
      BIDIRECTIONAL='TRUE';
      INPUT_LOAD='(-0.01,0.01)';
      OUTPUT_LOAD='(1.0,-1.0)';
    'MJA_DATA13':
      PIN_NUMBER='(0,0,0,0,0,0,0,0,0,T18,0,0,0,0,0,0,0,0,0,0,0,0,0,0,0,0,0,0,0,0,0,0,0,0,0,0,0,0,0,0)';
      BIDIRECTIONAL='TRUE';
      INPUT_LOAD='(-0.01,0.01)';
      OUTPUT_LOAD='(1.0,-1.0)';
    'MJA_DATA12':
      PIN_NUMBER='(0,0,0,0,0,0,0,0,0,R16,0,0,0,0,0,0,0,0,0,0,0,0,0,0,0,0,0,0,0,0,0,0,0,0,0,0,0,0,0,0)';
      BIDIRECTIONAL='TRUE';
      INPUT_LOAD='(-0.01,0.01)';
      OUTPUT_LOAD='(1.0,-1.0)';
    'MJA_DATA11':
      PIN_NUMBER='(0,0,0,0,0,0,0,0,0,N17,0,0,0,0,0,0,0,0,0,0,0,0,0,0,0,0,0,0,0,0,0,0,0,0,0,0,0,0,0,0)';
      BIDIRECTIONAL='TRUE';
      INPUT_LOAD='(-0.01,0.01)';
      OUTPUT_LOAD='(1.0,-1.0)';
    'MJA_DATA10':
      PIN_NUMBER='(0,0,0,0,0,0,0,0,0,M16,0,0,0,0,0,0,0,0,0,0,0,0,0,0,0,0,0,0,0,0,0,0,0,0,0,0,0,0,0,0)';
      BIDIRECTIONAL='TRUE';
      INPUT_LOAD='(-0.01,0.01)';
      OUTPUT_LOAD='(1.0,-1.0)';
    'MJA_DATA9':
      PIN_NUMBER='(0,0,0,0,0,0,0,0,0,M18,0,0,0,0,0,0,0,0,0,0,0,0,0,0,0,0,0,0,0,0,0,0,0,0,0,0,0,0,0,0)';
      BIDIRECTIONAL='TRUE';
      INPUT_LOAD='(-0.01,0.01)';
      OUTPUT_LOAD='(1.0,-1.0)';
    'MJA_DATA8':
      PIN_NUMBER='(0,0,0,0,0,0,0,0,0,L16,0,0,0,0,0,0,0,0,0,0,0,0,0,0,0,0,0,0,0,0,0,0,0,0,0,0,0,0,0,0)';
      BIDIRECTIONAL='TRUE';
      INPUT_LOAD='(-0.01,0.01)';
      OUTPUT_LOAD='(1.0,-1.0)';
    'MJA_DATA7':
      PIN_NUMBER='(0,0,0,0,0,0,0,0,0,L17,0,0,0,0,0,0,0,0,0,0,0,0,0,0,0,0,0,0,0,0,0,0,0,0,0,0,0,0,0,0)';
      BIDIRECTIONAL='TRUE';
      INPUT_LOAD='(-0.01,0.01)';
      OUTPUT_LOAD='(1.0,-1.0)';
    'MJA_DATA6':
      PIN_NUMBER='(0,0,0,0,0,0,0,0,0,K16,0,0,0,0,0,0,0,0,0,0,0,0,0,0,0,0,0,0,0,0,0,0,0,0,0,0,0,0,0,0)';
      BIDIRECTIONAL='TRUE';
      INPUT_LOAD='(-0.01,0.01)';
      OUTPUT_LOAD='(1.0,-1.0)';
    'MJA_DATA5':
      PIN_NUMBER='(0,0,0,0,0,0,0,0,0,K18,0,0,0,0,0,0,0,0,0,0,0,0,0,0,0,0,0,0,0,0,0,0,0,0,0,0,0,0,0,0)';
      BIDIRECTIONAL='TRUE';
      INPUT_LOAD='(-0.01,0.01)';
      OUTPUT_LOAD='(1.0,-1.0)';
    'MJA_DATA4':
      PIN_NUMBER='(0,0,0,0,0,0,0,0,0,J16,0,0,0,0,0,0,0,0,0,0,0,0,0,0,0,0,0,0,0,0,0,0,0,0,0,0,0,0,0,0)';
      BIDIRECTIONAL='TRUE';
      INPUT_LOAD='(-0.01,0.01)';
      OUTPUT_LOAD='(1.0,-1.0)';
    'MJA_DATA3':
      PIN_NUMBER='(0,0,0,0,0,0,0,0,0,G17,0,0,0,0,0,0,0,0,0,0,0,0,0,0,0,0,0,0,0,0,0,0,0,0,0,0,0,0,0,0)';
      BIDIRECTIONAL='TRUE';
      INPUT_LOAD='(-0.01,0.01)';
      OUTPUT_LOAD='(1.0,-1.0)';
    'MJA_DATA2':
      PIN_NUMBER='(0,0,0,0,0,0,0,0,0,F16,0,0,0,0,0,0,0,0,0,0,0,0,0,0,0,0,0,0,0,0,0,0,0,0,0,0,0,0,0,0)';
      BIDIRECTIONAL='TRUE';
      INPUT_LOAD='(-0.01,0.01)';
      OUTPUT_LOAD='(1.0,-1.0)';
    'MJA_DATA1':
      PIN_NUMBER='(0,0,0,0,0,0,0,0,0,F18,0,0,0,0,0,0,0,0,0,0,0,0,0,0,0,0,0,0,0,0,0,0,0,0,0,0,0,0,0,0)';
      BIDIRECTIONAL='TRUE';
      INPUT_LOAD='(-0.01,0.01)';
      OUTPUT_LOAD='(1.0,-1.0)';
    'MJA_DATA0':
      PIN_NUMBER='(0,0,0,0,0,0,0,0,0,E16,0,0,0,0,0,0,0,0,0,0,0,0,0,0,0,0,0,0,0,0,0,0,0,0,0,0,0,0,0,0)';
      BIDIRECTIONAL='TRUE';
      INPUT_LOAD='(-0.01,0.01)';
      OUTPUT_LOAD='(1.0,-1.0)';
    'MJA_CHECK7':
      PIN_NUMBER='(0,0,0,0,0,0,0,0,0,AR17,0,0,0,0,0,0,0,0,0,0,0,0,0,0,0,0,0,0,0,0,0,0,0,0,0,0,0,0,0,0)';
      BIDIRECTIONAL='TRUE';
      INPUT_LOAD='(-0.01,0.01)';
      OUTPUT_LOAD='(1.0,-1.0)';
    'MJA_CHECK6':
      PIN_NUMBER='(0,0,0,0,0,0,0,0,0,AP16,0,0,0,0,0,0,0,0,0,0,0,0,0,0,0,0,0,0,0,0,0,0,0,0,0,0,0,0,0,0)';
      BIDIRECTIONAL='TRUE';
      INPUT_LOAD='(-0.01,0.01)';
      OUTPUT_LOAD='(1.0,-1.0)';
    'MJA_CHECK5':
      PIN_NUMBER='(0,0,0,0,0,0,0,0,0,AP18,0,0,0,0,0,0,0,0,0,0,0,0,0,0,0,0,0,0,0,0,0,0,0,0,0,0,0,0,0,0)';
      BIDIRECTIONAL='TRUE';
      INPUT_LOAD='(-0.01,0.01)';
      OUTPUT_LOAD='(1.0,-1.0)';
    'MJA_CHECK4':
      PIN_NUMBER='(0,0,0,0,0,0,0,0,0,AN16,0,0,0,0,0,0,0,0,0,0,0,0,0,0,0,0,0,0,0,0,0,0,0,0,0,0,0,0,0,0)';
      BIDIRECTIONAL='TRUE';
      INPUT_LOAD='(-0.01,0.01)';
      OUTPUT_LOAD='(1.0,-1.0)';
    'MJA_CHECK3':
      PIN_NUMBER='(0,0,0,0,0,0,0,0,0,AL17,0,0,0,0,0,0,0,0,0,0,0,0,0,0,0,0,0,0,0,0,0,0,0,0,0,0,0,0,0,0)';
      BIDIRECTIONAL='TRUE';
      INPUT_LOAD='(-0.01,0.01)';
      OUTPUT_LOAD='(1.0,-1.0)';
    'MJA_CHECK2':
      PIN_NUMBER='(0,0,0,0,0,0,0,0,0,AK16,0,0,0,0,0,0,0,0,0,0,0,0,0,0,0,0,0,0,0,0,0,0,0,0,0,0,0,0,0,0)';
      BIDIRECTIONAL='TRUE';
      INPUT_LOAD='(-0.01,0.01)';
      OUTPUT_LOAD='(1.0,-1.0)';
    'MJA_CHECK1':
      PIN_NUMBER='(0,0,0,0,0,0,0,0,0,AK18,0,0,0,0,0,0,0,0,0,0,0,0,0,0,0,0,0,0,0,0,0,0,0,0,0,0,0,0,0,0)';
      BIDIRECTIONAL='TRUE';
      INPUT_LOAD='(-0.01,0.01)';
      OUTPUT_LOAD='(1.0,-1.0)';
    'MJA_CHECK0':
      PIN_NUMBER='(0,0,0,0,0,0,0,0,0,AJ16,0,0,0,0,0,0,0,0,0,0,0,0,0,0,0,0,0,0,0,0,0,0,0,0,0,0,0,0,0,0)';
      BIDIRECTIONAL='TRUE';
      INPUT_LOAD='(-0.01,0.01)';
      OUTPUT_LOAD='(1.0,-1.0)';
    'MJA_CA4':
      PIN_NUMBER='(0,0,0,0,0,0,0,0,0,BA16,0,0,0,0,0,0,0,0,0,0,0,0,0,0,0,0,0,0,0,0,0,0,0,0,0,0,0,0,0,0)';
      OUTPUT_LOAD='(1.0,-1.0)';
    'MJA_CA3':
      PIN_NUMBER='(0,0,0,0,0,0,0,0,0,BA17,0,0,0,0,0,0,0,0,0,0,0,0,0,0,0,0,0,0,0,0,0,0,0,0,0,0,0,0,0,0)';
      OUTPUT_LOAD='(1.0,-1.0)';
    'MJA_CA2':
      PIN_NUMBER='(0,0,0,0,0,0,0,0,0,AY18,0,0,0,0,0,0,0,0,0,0,0,0,0,0,0,0,0,0,0,0,0,0,0,0,0,0,0,0,0,0)';
      OUTPUT_LOAD='(1.0,-1.0)';
    'MJA_CA1':
      PIN_NUMBER='(0,0,0,0,0,0,0,0,0,AY16,0,0,0,0,0,0,0,0,0,0,0,0,0,0,0,0,0,0,0,0,0,0,0,0,0,0,0,0,0,0)';
      OUTPUT_LOAD='(1.0,-1.0)';
    'MJA_CA0':
      PIN_NUMBER='(0,0,0,0,0,0,0,0,0,AW16,0,0,0,0,0,0,0,0,0,0,0,0,0,0,0,0,0,0,0,0,0,0,0,0,0,0,0,0,0,0)';
      OUTPUT_LOAD='(1.0,-1.0)';
    'MJA1_RSP_L':
      PIN_NUMBER='(0,0,0,0,0,0,0,0,0,BP18,0,0,0,0,0,0,0,0,0,0,0,0,0,0,0,0,0,0,0,0,0,0,0,0,0,0,0,0,0,0)';
      INPUT_LOAD='(-0.01,0.01)';
    'MJA1_CS_L1':
      PIN_NUMBER='(0,0,0,0,0,0,0,0,0,AW17,0,0,0,0,0,0,0,0,0,0,0,0,0,0,0,0,0,0,0,0,0,0,0,0,0,0,0,0,0,0)';
      OUTPUT_LOAD='(1.0,-1.0)';
    'MJA1_CS_L0':
      PIN_NUMBER='(0,0,0,0,0,0,0,0,0,AV16,0,0,0,0,0,0,0,0,0,0,0,0,0,0,0,0,0,0,0,0,0,0,0,0,0,0,0,0,0,0)';
      OUTPUT_LOAD='(1.0,-1.0)';
    'MJA0_RSP_L':
      PIN_NUMBER='(0,0,0,0,0,0,0,0,0,BN17,0,0,0,0,0,0,0,0,0,0,0,0,0,0,0,0,0,0,0,0,0,0,0,0,0,0,0,0,0,0)';
      INPUT_LOAD='(-0.01,0.01)';
    'MJA0_CS_L1':
      PIN_NUMBER='(0,0,0,0,0,0,0,0,0,AV18,0,0,0,0,0,0,0,0,0,0,0,0,0,0,0,0,0,0,0,0,0,0,0,0,0,0,0,0,0,0)';
      OUTPUT_LOAD='(1.0,-1.0)';
    'MJA0_CS_L0':
      PIN_NUMBER='(0,0,0,0,0,0,0,0,0,AU16,0,0,0,0,0,0,0,0,0,0,0,0,0,0,0,0,0,0,0,0,0,0,0,0,0,0,0,0,0,0)';
      OUTPUT_LOAD='(1.0,-1.0)';
    'MJ1_CLK_L':
      PIN_NUMBER='(0,0,0,0,0,0,0,0,0,BG16,0,0,0,0,0,0,0,0,0,0,0,0,0,0,0,0,0,0,0,0,0,0,0,0,0,0,0,0,0,0)';
      OUTPUT_LOAD='(1.0,-1.0)';
    'MJ1_CLK_H':
      PIN_NUMBER='(0,0,0,0,0,0,0,0,0,BF16,0,0,0,0,0,0,0,0,0,0,0,0,0,0,0,0,0,0,0,0,0,0,0,0,0,0,0,0,0,0)';
      OUTPUT_LOAD='(1.0,-1.0)';
    'MJ0_CLK_L':
      PIN_NUMBER='(0,0,0,0,0,0,0,0,0,BD16,0,0,0,0,0,0,0,0,0,0,0,0,0,0,0,0,0,0,0,0,0,0,0,0,0,0,0,0,0,0)';
      OUTPUT_LOAD='(1.0,-1.0)';
    'MJ0_CLK_H':
      PIN_NUMBER='(0,0,0,0,0,0,0,0,0,BC16,0,0,0,0,0,0,0,0,0,0,0,0,0,0,0,0,0,0,0,0,0,0,0,0,0,0,0,0,0,0)';
      OUTPUT_LOAD='(1.0,-1.0)';
    'MJA_CA6':
      PIN_NUMBER='(0,0,0,0,0,0,0,0,0,BB18,0,0,0,0,0,0,0,0,0,0,0,0,0,0,0,0,0,0,0,0,0,0,0,0,0,0,0,0,0,0)';
      OUTPUT_LOAD='(1.0,-1.0)';
    'MJA_CA5':
      PIN_NUMBER='(0,0,0,0,0,0,0,0,0,BB16,0,0,0,0,0,0,0,0,0,0,0,0,0,0,0,0,0,0,0,0,0,0,0,0,0,0,0,0,0,0)';
      OUTPUT_LOAD='(1.0,-1.0)';
    'MJA_DATA22':
      PIN_NUMBER='(0,0,0,0,0,0,0,0,0,AB16,0,0,0,0,0,0,0,0,0,0,0,0,0,0,0,0,0,0,0,0,0,0,0,0,0,0,0,0,0,0)';
      BIDIRECTIONAL='TRUE';
      INPUT_LOAD='(-0.01,0.01)';
      OUTPUT_LOAD='(1.0,-1.0)';
    'MJA_DQS_L7':
      PIN_NUMBER='(0,0,0,0,0,0,0,0,0,Y18,0,0,0,0,0,0,0,0,0,0,0,0,0,0,0,0,0,0,0,0,0,0,0,0,0,0,0,0,0,0)';
      BIDIRECTIONAL='TRUE';
      INPUT_LOAD='(-0.01,0.01)';
      OUTPUT_LOAD='(1.0,-1.0)';
    'MJA_DQS_L5':
      PIN_NUMBER='(0,0,0,0,0,0,0,0,0,H18,0,0,0,0,0,0,0,0,0,0,0,0,0,0,0,0,0,0,0,0,0,0,0,0,0,0,0,0,0,0)';
      BIDIRECTIONAL='TRUE';
      INPUT_LOAD='(-0.01,0.01)';
      OUTPUT_LOAD='(1.0,-1.0)';
    'MJA_DQS_L4':
      PIN_NUMBER='(0,0,0,0,0,0,0,0,0,AM16,0,0,0,0,0,0,0,0,0,0,0,0,0,0,0,0,0,0,0,0,0,0,0,0,0,0,0,0,0,0)';
      BIDIRECTIONAL='TRUE';
      INPUT_LOAD='(-0.01,0.01)';
      OUTPUT_LOAD='(1.0,-1.0)';
    'MJA_DQS_H8':
      PIN_NUMBER='(0,0,0,0,0,0,0,0,0,AG17,0,0,0,0,0,0,0,0,0,0,0,0,0,0,0,0,0,0,0,0,0,0,0,0,0,0,0,0,0,0)';
      BIDIRECTIONAL='TRUE';
      INPUT_LOAD='(-0.01,0.01)';
      OUTPUT_LOAD='(1.0,-1.0)';
    'MJA_DQS_H4':
      PIN_NUMBER='(0,0,0,0,0,0,0,0,0,AL16,0,0,0,0,0,0,0,0,0,0,0,0,0,0,0,0,0,0,0,0,0,0,0,0,0,0,0,0,0,0)';
      BIDIRECTIONAL='TRUE';
      INPUT_LOAD='(-0.01,0.01)';
      OUTPUT_LOAD='(1.0,-1.0)';
    'MJB_DATA4':
      PIN_NUMBER='(0,0,0,0,0,0,0,0,0,CF16,0,0,0,0,0,0,0,0,0,0,0,0,0,0,0,0,0,0,0,0,0,0,0,0,0,0,0,0,0,0)';
      BIDIRECTIONAL='TRUE';
      INPUT_LOAD='(-0.01,0.01)';
      OUTPUT_LOAD='(1.0,-1.0)';
    'MJB_DATA3':
      PIN_NUMBER='(0,0,0,0,0,0,0,0,0,CD18,0,0,0,0,0,0,0,0,0,0,0,0,0,0,0,0,0,0,0,0,0,0,0,0,0,0,0,0,0,0)';
      BIDIRECTIONAL='TRUE';
      INPUT_LOAD='(-0.01,0.01)';
      OUTPUT_LOAD='(1.0,-1.0)';
    'MJB_DATA0':
      PIN_NUMBER='(0,0,0,0,0,0,0,0,0,CB16,0,0,0,0,0,0,0,0,0,0,0,0,0,0,0,0,0,0,0,0,0,0,0,0,0,0,0,0,0,0)';
      BIDIRECTIONAL='TRUE';
      INPUT_LOAD='(-0.01,0.01)';
      OUTPUT_LOAD='(1.0,-1.0)';
    'MJA_DATA31':
      PIN_NUMBER='(0,0,0,0,0,0,0,0,0,AJ17,0,0,0,0,0,0,0,0,0,0,0,0,0,0,0,0,0,0,0,0,0,0,0,0,0,0,0,0,0,0)';
      BIDIRECTIONAL='TRUE';
      INPUT_LOAD='(-0.01,0.01)';
      OUTPUT_LOAD='(1.0,-1.0)';
    'MJB_DQS_L0':
      PIN_NUMBER='(0,0,0,0,0,0,0,0,0,CE16,0,0,0,0,0,0,0,0,0,0,0,0,0,0,0,0,0,0,0,0,0,0,0,0,0,0,0,0,0,0)';
      BIDIRECTIONAL='TRUE';
      INPUT_LOAD='(-0.01,0.01)';
      OUTPUT_LOAD='(1.0,-1.0)';
    'MJB_DQS_L4':
      PIN_NUMBER='(0,0,0,0,0,0,0,0,0,BW17,0,0,0,0,0,0,0,0,0,0,0,0,0,0,0,0,0,0,0,0,0,0,0,0,0,0,0,0,0,0)';
      BIDIRECTIONAL='TRUE';
      INPUT_LOAD='(-0.01,0.01)';
      OUTPUT_LOAD='(1.0,-1.0)';
    'MJB_DQS_H5':
      PIN_NUMBER='(0,0,0,0,0,0,0,0,0,CF18,0,0,0,0,0,0,0,0,0,0,0,0,0,0,0,0,0,0,0,0,0,0,0,0,0,0,0,0,0,0)';
      BIDIRECTIONAL='TRUE';
      INPUT_LOAD='(-0.01,0.01)';
      OUTPUT_LOAD='(1.0,-1.0)';
    'MJB_DATA5':
      PIN_NUMBER='(0,0,0,0,0,0,0,0,0,CG17,0,0,0,0,0,0,0,0,0,0,0,0,0,0,0,0,0,0,0,0,0,0,0,0,0,0,0,0,0,0)';
      BIDIRECTIONAL='TRUE';
      INPUT_LOAD='(-0.01,0.01)';
      OUTPUT_LOAD='(1.0,-1.0)';
    'MJB_DATA6':
      PIN_NUMBER='(0,0,0,0,0,0,0,0,0,CG16,0,0,0,0,0,0,0,0,0,0,0,0,0,0,0,0,0,0,0,0,0,0,0,0,0,0,0,0,0,0)';
      BIDIRECTIONAL='TRUE';
      INPUT_LOAD='(-0.01,0.01)';
      OUTPUT_LOAD='(1.0,-1.0)';
    'MJB_DATA7':
      PIN_NUMBER='(0,0,0,0,0,0,0,0,0,CH18,0,0,0,0,0,0,0,0,0,0,0,0,0,0,0,0,0,0,0,0,0,0,0,0,0,0,0,0,0,0)';
      BIDIRECTIONAL='TRUE';
      INPUT_LOAD='(-0.01,0.01)';
      OUTPUT_LOAD='(1.0,-1.0)';
    'TEST39J':
      PIN_NUMBER='(0,0,0,0,0,0,0,0,0,BF18,0,0,0,0,0,0,0,0,0,0,0,0,0,0,0,0,0,0,0,0,0,0,0,0,0,0,0,0,0,0)';
      OUTPUT_LOAD='(1.0,-1.0)';
    'G0_RXN0':
      PIN_NUMBER='(0,0,0,0,0,0,0,0,0,0,M40,0,0,0,0,0,0,0,0,0,0,0,0,0,0,0,0,0,0,0,0,0,0,0,0,0,0,0,0,0)';
      INPUT_LOAD='(-0.01,0.01)';
    'G0_RXN1':
      PIN_NUMBER='(0,0,0,0,0,0,0,0,0,0,K40,0,0,0,0,0,0,0,0,0,0,0,0,0,0,0,0,0,0,0,0,0,0,0,0,0,0,0,0,0)';
      INPUT_LOAD='(-0.01,0.01)';
    'G0_RXN2':
      PIN_NUMBER='(0,0,0,0,0,0,0,0,0,0,H40,0,0,0,0,0,0,0,0,0,0,0,0,0,0,0,0,0,0,0,0,0,0,0,0,0,0,0,0,0)';
      INPUT_LOAD='(-0.01,0.01)';
    'G0_RXN3':
      PIN_NUMBER='(0,0,0,0,0,0,0,0,0,0,L43,0,0,0,0,0,0,0,0,0,0,0,0,0,0,0,0,0,0,0,0,0,0,0,0,0,0,0,0,0)';
      INPUT_LOAD='(-0.01,0.01)';
    'G0_RXN4':
      PIN_NUMBER='(0,0,0,0,0,0,0,0,0,0,G43,0,0,0,0,0,0,0,0,0,0,0,0,0,0,0,0,0,0,0,0,0,0,0,0,0,0,0,0,0)';
      INPUT_LOAD='(-0.01,0.01)';
    'G0_RXN5':
      PIN_NUMBER='(0,0,0,0,0,0,0,0,0,0,J43,0,0,0,0,0,0,0,0,0,0,0,0,0,0,0,0,0,0,0,0,0,0,0,0,0,0,0,0,0)';
      INPUT_LOAD='(-0.01,0.01)';
    'G0_RXN6':
      PIN_NUMBER='(0,0,0,0,0,0,0,0,0,0,L46,0,0,0,0,0,0,0,0,0,0,0,0,0,0,0,0,0,0,0,0,0,0,0,0,0,0,0,0,0)';
      INPUT_LOAD='(-0.01,0.01)';
    'G0_RXN7':
      PIN_NUMBER='(0,0,0,0,0,0,0,0,0,0,G46,0,0,0,0,0,0,0,0,0,0,0,0,0,0,0,0,0,0,0,0,0,0,0,0,0,0,0,0,0)';
      INPUT_LOAD='(-0.01,0.01)';
    'G0_RXN8':
      PIN_NUMBER='(0,0,0,0,0,0,0,0,0,0,J46,0,0,0,0,0,0,0,0,0,0,0,0,0,0,0,0,0,0,0,0,0,0,0,0,0,0,0,0,0)';
      INPUT_LOAD='(-0.01,0.01)';
    'G0_RXN9':
      PIN_NUMBER='(0,0,0,0,0,0,0,0,0,0,L49,0,0,0,0,0,0,0,0,0,0,0,0,0,0,0,0,0,0,0,0,0,0,0,0,0,0,0,0,0)';
      INPUT_LOAD='(-0.01,0.01)';
    'G0_RXN10':
      PIN_NUMBER='(0,0,0,0,0,0,0,0,0,0,G49,0,0,0,0,0,0,0,0,0,0,0,0,0,0,0,0,0,0,0,0,0,0,0,0,0,0,0,0,0)';
      INPUT_LOAD='(-0.01,0.01)';
    'G0_RXN11':
      PIN_NUMBER='(0,0,0,0,0,0,0,0,0,0,J49,0,0,0,0,0,0,0,0,0,0,0,0,0,0,0,0,0,0,0,0,0,0,0,0,0,0,0,0,0)';
      INPUT_LOAD='(-0.01,0.01)';
    'G0_RXN12':
      PIN_NUMBER='(0,0,0,0,0,0,0,0,0,0,L52,0,0,0,0,0,0,0,0,0,0,0,0,0,0,0,0,0,0,0,0,0,0,0,0,0,0,0,0,0)';
      INPUT_LOAD='(-0.01,0.01)';
    'G0_RXN13':
      PIN_NUMBER='(0,0,0,0,0,0,0,0,0,0,G52,0,0,0,0,0,0,0,0,0,0,0,0,0,0,0,0,0,0,0,0,0,0,0,0,0,0,0,0,0)';
      INPUT_LOAD='(-0.01,0.01)';
    'G0_RXN14':
      PIN_NUMBER='(0,0,0,0,0,0,0,0,0,0,J52,0,0,0,0,0,0,0,0,0,0,0,0,0,0,0,0,0,0,0,0,0,0,0,0,0,0,0,0,0)';
      INPUT_LOAD='(-0.01,0.01)';
    'G0_RXN15':
      PIN_NUMBER='(0,0,0,0,0,0,0,0,0,0,N52,0,0,0,0,0,0,0,0,0,0,0,0,0,0,0,0,0,0,0,0,0,0,0,0,0,0,0,0,0)';
      INPUT_LOAD='(-0.01,0.01)';
    'G0_RXP0':
      PIN_NUMBER='(0,0,0,0,0,0,0,0,0,0,M41,0,0,0,0,0,0,0,0,0,0,0,0,0,0,0,0,0,0,0,0,0,0,0,0,0,0,0,0,0)';
      INPUT_LOAD='(-0.01,0.01)';
    'G0_RXP1':
      PIN_NUMBER='(0,0,0,0,0,0,0,0,0,0,K41,0,0,0,0,0,0,0,0,0,0,0,0,0,0,0,0,0,0,0,0,0,0,0,0,0,0,0,0,0)';
      INPUT_LOAD='(-0.01,0.01)';
    'G0_RXP2':
      PIN_NUMBER='(0,0,0,0,0,0,0,0,0,0,H41,0,0,0,0,0,0,0,0,0,0,0,0,0,0,0,0,0,0,0,0,0,0,0,0,0,0,0,0,0)';
      INPUT_LOAD='(-0.01,0.01)';
    'G0_RXP3':
      PIN_NUMBER='(0,0,0,0,0,0,0,0,0,0,L44,0,0,0,0,0,0,0,0,0,0,0,0,0,0,0,0,0,0,0,0,0,0,0,0,0,0,0,0,0)';
      INPUT_LOAD='(-0.01,0.01)';
    'G0_RXP4':
      PIN_NUMBER='(0,0,0,0,0,0,0,0,0,0,G44,0,0,0,0,0,0,0,0,0,0,0,0,0,0,0,0,0,0,0,0,0,0,0,0,0,0,0,0,0)';
      INPUT_LOAD='(-0.01,0.01)';
    'G0_RXP5':
      PIN_NUMBER='(0,0,0,0,0,0,0,0,0,0,J44,0,0,0,0,0,0,0,0,0,0,0,0,0,0,0,0,0,0,0,0,0,0,0,0,0,0,0,0,0)';
      INPUT_LOAD='(-0.01,0.01)';
    'G0_RXP6':
      PIN_NUMBER='(0,0,0,0,0,0,0,0,0,0,L47,0,0,0,0,0,0,0,0,0,0,0,0,0,0,0,0,0,0,0,0,0,0,0,0,0,0,0,0,0)';
      INPUT_LOAD='(-0.01,0.01)';
    'G0_RXP7':
      PIN_NUMBER='(0,0,0,0,0,0,0,0,0,0,G47,0,0,0,0,0,0,0,0,0,0,0,0,0,0,0,0,0,0,0,0,0,0,0,0,0,0,0,0,0)';
      INPUT_LOAD='(-0.01,0.01)';
    'G0_RXP8':
      PIN_NUMBER='(0,0,0,0,0,0,0,0,0,0,J47,0,0,0,0,0,0,0,0,0,0,0,0,0,0,0,0,0,0,0,0,0,0,0,0,0,0,0,0,0)';
      INPUT_LOAD='(-0.01,0.01)';
    'G0_RXP9':
      PIN_NUMBER='(0,0,0,0,0,0,0,0,0,0,L50,0,0,0,0,0,0,0,0,0,0,0,0,0,0,0,0,0,0,0,0,0,0,0,0,0,0,0,0,0)';
      INPUT_LOAD='(-0.01,0.01)';
    'G0_RXP10':
      PIN_NUMBER='(0,0,0,0,0,0,0,0,0,0,G50,0,0,0,0,0,0,0,0,0,0,0,0,0,0,0,0,0,0,0,0,0,0,0,0,0,0,0,0,0)';
      INPUT_LOAD='(-0.01,0.01)';
    'G0_RXP11':
      PIN_NUMBER='(0,0,0,0,0,0,0,0,0,0,J50,0,0,0,0,0,0,0,0,0,0,0,0,0,0,0,0,0,0,0,0,0,0,0,0,0,0,0,0,0)';
      INPUT_LOAD='(-0.01,0.01)';
    'G0_RXP12':
      PIN_NUMBER='(0,0,0,0,0,0,0,0,0,0,L53,0,0,0,0,0,0,0,0,0,0,0,0,0,0,0,0,0,0,0,0,0,0,0,0,0,0,0,0,0)';
      INPUT_LOAD='(-0.01,0.01)';
    'G0_RXP13':
      PIN_NUMBER='(0,0,0,0,0,0,0,0,0,0,G53,0,0,0,0,0,0,0,0,0,0,0,0,0,0,0,0,0,0,0,0,0,0,0,0,0,0,0,0,0)';
      INPUT_LOAD='(-0.01,0.01)';
    'G0_RXP14':
      PIN_NUMBER='(0,0,0,0,0,0,0,0,0,0,J53,0,0,0,0,0,0,0,0,0,0,0,0,0,0,0,0,0,0,0,0,0,0,0,0,0,0,0,0,0)';
      INPUT_LOAD='(-0.01,0.01)';
    'G0_RXP15':
      PIN_NUMBER='(0,0,0,0,0,0,0,0,0,0,N53,0,0,0,0,0,0,0,0,0,0,0,0,0,0,0,0,0,0,0,0,0,0,0,0,0,0,0,0,0)';
      INPUT_LOAD='(-0.01,0.01)';
    'G0_TXN0':
      PIN_NUMBER='(0,0,0,0,0,0,0,0,0,0,AF41,0,0,0,0,0,0,0,0,0,0,0,0,0,0,0,0,0,0,0,0,0,0,0,0,0,0,0,0,0)';
      OUTPUT_LOAD='(1.0,-1.0)';
    'G0_TXN1':
      PIN_NUMBER='(0,0,0,0,0,0,0,0,0,0,AD41,0,0,0,0,0,0,0,0,0,0,0,0,0,0,0,0,0,0,0,0,0,0,0,0,0,0,0,0,0)';
      OUTPUT_LOAD='(1.0,-1.0)';
    'G0_TXN2':
      PIN_NUMBER='(0,0,0,0,0,0,0,0,0,0,AB41,0,0,0,0,0,0,0,0,0,0,0,0,0,0,0,0,0,0,0,0,0,0,0,0,0,0,0,0,0)';
      OUTPUT_LOAD='(1.0,-1.0)';
    'G0_TXN3':
      PIN_NUMBER='(0,0,0,0,0,0,0,0,0,0,AG44,0,0,0,0,0,0,0,0,0,0,0,0,0,0,0,0,0,0,0,0,0,0,0,0,0,0,0,0,0)';
      OUTPUT_LOAD='(1.0,-1.0)';
    'G0_TXN4':
      PIN_NUMBER='(0,0,0,0,0,0,0,0,0,0,AA44,0,0,0,0,0,0,0,0,0,0,0,0,0,0,0,0,0,0,0,0,0,0,0,0,0,0,0,0,0)';
      OUTPUT_LOAD='(1.0,-1.0)';
    'G0_TXN5':
      PIN_NUMBER='(0,0,0,0,0,0,0,0,0,0,AC44,0,0,0,0,0,0,0,0,0,0,0,0,0,0,0,0,0,0,0,0,0,0,0,0,0,0,0,0,0)';
      OUTPUT_LOAD='(1.0,-1.0)';
    'G0_TXN6':
      PIN_NUMBER='(0,0,0,0,0,0,0,0,0,0,AE44,0,0,0,0,0,0,0,0,0,0,0,0,0,0,0,0,0,0,0,0,0,0,0,0,0,0,0,0,0)';
      OUTPUT_LOAD='(1.0,-1.0)';
    'G0_TXN7':
      PIN_NUMBER='(0,0,0,0,0,0,0,0,0,0,AG47,0,0,0,0,0,0,0,0,0,0,0,0,0,0,0,0,0,0,0,0,0,0,0,0,0,0,0,0,0)';
      OUTPUT_LOAD='(1.0,-1.0)';
    'G0_TXN8':
      PIN_NUMBER='(0,0,0,0,0,0,0,0,0,0,AC47,0,0,0,0,0,0,0,0,0,0,0,0,0,0,0,0,0,0,0,0,0,0,0,0,0,0,0,0,0)';
      OUTPUT_LOAD='(1.0,-1.0)';
    'G0_TXN9':
      PIN_NUMBER='(0,0,0,0,0,0,0,0,0,0,AE47,0,0,0,0,0,0,0,0,0,0,0,0,0,0,0,0,0,0,0,0,0,0,0,0,0,0,0,0,0)';
      OUTPUT_LOAD='(1.0,-1.0)';
    'G0_TXN10':
      PIN_NUMBER='(0,0,0,0,0,0,0,0,0,0,AG50,0,0,0,0,0,0,0,0,0,0,0,0,0,0,0,0,0,0,0,0,0,0,0,0,0,0,0,0,0)';
      OUTPUT_LOAD='(1.0,-1.0)';
    'G0_TXN11':
      PIN_NUMBER='(0,0,0,0,0,0,0,0,0,0,AC50,0,0,0,0,0,0,0,0,0,0,0,0,0,0,0,0,0,0,0,0,0,0,0,0,0,0,0,0,0)';
      OUTPUT_LOAD='(1.0,-1.0)';
    'G0_TXN12':
      PIN_NUMBER='(0,0,0,0,0,0,0,0,0,0,AE50,0,0,0,0,0,0,0,0,0,0,0,0,0,0,0,0,0,0,0,0,0,0,0,0,0,0,0,0,0)';
      OUTPUT_LOAD='(1.0,-1.0)';
    'G0_TXN13':
      PIN_NUMBER='(0,0,0,0,0,0,0,0,0,0,AG53,0,0,0,0,0,0,0,0,0,0,0,0,0,0,0,0,0,0,0,0,0,0,0,0,0,0,0,0,0)';
      OUTPUT_LOAD='(1.0,-1.0)';
    'G0_TXN14':
      PIN_NUMBER='(0,0,0,0,0,0,0,0,0,0,AC53,0,0,0,0,0,0,0,0,0,0,0,0,0,0,0,0,0,0,0,0,0,0,0,0,0,0,0,0,0)';
      OUTPUT_LOAD='(1.0,-1.0)';
    'G0_TXN15':
      PIN_NUMBER='(0,0,0,0,0,0,0,0,0,0,AE53,0,0,0,0,0,0,0,0,0,0,0,0,0,0,0,0,0,0,0,0,0,0,0,0,0,0,0,0,0)';
      OUTPUT_LOAD='(1.0,-1.0)';
    'G0_TXP0':
      PIN_NUMBER='(0,0,0,0,0,0,0,0,0,0,AF40,0,0,0,0,0,0,0,0,0,0,0,0,0,0,0,0,0,0,0,0,0,0,0,0,0,0,0,0,0)';
      OUTPUT_LOAD='(1.0,-1.0)';
    'G0_TXP1':
      PIN_NUMBER='(0,0,0,0,0,0,0,0,0,0,AD40,0,0,0,0,0,0,0,0,0,0,0,0,0,0,0,0,0,0,0,0,0,0,0,0,0,0,0,0,0)';
      OUTPUT_LOAD='(1.0,-1.0)';
    'G0_TXP2':
      PIN_NUMBER='(0,0,0,0,0,0,0,0,0,0,AB40,0,0,0,0,0,0,0,0,0,0,0,0,0,0,0,0,0,0,0,0,0,0,0,0,0,0,0,0,0)';
      OUTPUT_LOAD='(1.0,-1.0)';
    'G0_TXP3':
      PIN_NUMBER='(0,0,0,0,0,0,0,0,0,0,AG43,0,0,0,0,0,0,0,0,0,0,0,0,0,0,0,0,0,0,0,0,0,0,0,0,0,0,0,0,0)';
      OUTPUT_LOAD='(1.0,-1.0)';
    'G0_TXP4':
      PIN_NUMBER='(0,0,0,0,0,0,0,0,0,0,AA43,0,0,0,0,0,0,0,0,0,0,0,0,0,0,0,0,0,0,0,0,0,0,0,0,0,0,0,0,0)';
      OUTPUT_LOAD='(1.0,-1.0)';
    'G0_TXP5':
      PIN_NUMBER='(0,0,0,0,0,0,0,0,0,0,AC43,0,0,0,0,0,0,0,0,0,0,0,0,0,0,0,0,0,0,0,0,0,0,0,0,0,0,0,0,0)';
      OUTPUT_LOAD='(1.0,-1.0)';
    'G0_TXP6':
      PIN_NUMBER='(0,0,0,0,0,0,0,0,0,0,AE43,0,0,0,0,0,0,0,0,0,0,0,0,0,0,0,0,0,0,0,0,0,0,0,0,0,0,0,0,0)';
      OUTPUT_LOAD='(1.0,-1.0)';
    'G0_TXP7':
      PIN_NUMBER='(0,0,0,0,0,0,0,0,0,0,AG46,0,0,0,0,0,0,0,0,0,0,0,0,0,0,0,0,0,0,0,0,0,0,0,0,0,0,0,0,0)';
      OUTPUT_LOAD='(1.0,-1.0)';
    'G0_TXP8':
      PIN_NUMBER='(0,0,0,0,0,0,0,0,0,0,AC46,0,0,0,0,0,0,0,0,0,0,0,0,0,0,0,0,0,0,0,0,0,0,0,0,0,0,0,0,0)';
      OUTPUT_LOAD='(1.0,-1.0)';
    'G0_TXP9':
      PIN_NUMBER='(0,0,0,0,0,0,0,0,0,0,AE46,0,0,0,0,0,0,0,0,0,0,0,0,0,0,0,0,0,0,0,0,0,0,0,0,0,0,0,0,0)';
      OUTPUT_LOAD='(1.0,-1.0)';
    'G0_TXP10':
      PIN_NUMBER='(0,0,0,0,0,0,0,0,0,0,AG49,0,0,0,0,0,0,0,0,0,0,0,0,0,0,0,0,0,0,0,0,0,0,0,0,0,0,0,0,0)';
      OUTPUT_LOAD='(1.0,-1.0)';
    'G0_TXP11':
      PIN_NUMBER='(0,0,0,0,0,0,0,0,0,0,AC49,0,0,0,0,0,0,0,0,0,0,0,0,0,0,0,0,0,0,0,0,0,0,0,0,0,0,0,0,0)';
      OUTPUT_LOAD='(1.0,-1.0)';
    'G0_TXP12':
      PIN_NUMBER='(0,0,0,0,0,0,0,0,0,0,AE49,0,0,0,0,0,0,0,0,0,0,0,0,0,0,0,0,0,0,0,0,0,0,0,0,0,0,0,0,0)';
      OUTPUT_LOAD='(1.0,-1.0)';
    'G0_TXP13':
      PIN_NUMBER='(0,0,0,0,0,0,0,0,0,0,AG52,0,0,0,0,0,0,0,0,0,0,0,0,0,0,0,0,0,0,0,0,0,0,0,0,0,0,0,0,0)';
      OUTPUT_LOAD='(1.0,-1.0)';
    'G0_TXP14':
      PIN_NUMBER='(0,0,0,0,0,0,0,0,0,0,AC52,0,0,0,0,0,0,0,0,0,0,0,0,0,0,0,0,0,0,0,0,0,0,0,0,0,0,0,0,0)';
      OUTPUT_LOAD='(1.0,-1.0)';
    'G0_TXP15':
      PIN_NUMBER='(0,0,0,0,0,0,0,0,0,0,AE52,0,0,0,0,0,0,0,0,0,0,0,0,0,0,0,0,0,0,0,0,0,0,0,0,0,0,0,0,0)';
      OUTPUT_LOAD='(1.0,-1.0)';
    'G1_TXP15':
      PIN_NUMBER='(0,0,0,0,0,0,0,0,0,0,0,AL52,0,0,0,0,0,0,0,0,0,0,0,0,0,0,0,0,0,0,0,0,0,0,0,0,0,0,0,0)';
      OUTPUT_LOAD='(1.0,-1.0)';
    'G1_TXP14':
      PIN_NUMBER='(0,0,0,0,0,0,0,0,0,0,0,AJ52,0,0,0,0,0,0,0,0,0,0,0,0,0,0,0,0,0,0,0,0,0,0,0,0,0,0,0,0)';
      OUTPUT_LOAD='(1.0,-1.0)';
    'G1_TXP13':
      PIN_NUMBER='(0,0,0,0,0,0,0,0,0,0,0,AN52,0,0,0,0,0,0,0,0,0,0,0,0,0,0,0,0,0,0,0,0,0,0,0,0,0,0,0,0)';
      OUTPUT_LOAD='(1.0,-1.0)';
    'G1_TXP12':
      PIN_NUMBER='(0,0,0,0,0,0,0,0,0,0,0,AL49,0,0,0,0,0,0,0,0,0,0,0,0,0,0,0,0,0,0,0,0,0,0,0,0,0,0,0,0)';
      OUTPUT_LOAD='(1.0,-1.0)';
    'G1_TXP11':
      PIN_NUMBER='(0,0,0,0,0,0,0,0,0,0,0,AJ49,0,0,0,0,0,0,0,0,0,0,0,0,0,0,0,0,0,0,0,0,0,0,0,0,0,0,0,0)';
      OUTPUT_LOAD='(1.0,-1.0)';
    'G1_TXP10':
      PIN_NUMBER='(0,0,0,0,0,0,0,0,0,0,0,AN49,0,0,0,0,0,0,0,0,0,0,0,0,0,0,0,0,0,0,0,0,0,0,0,0,0,0,0,0)';
      OUTPUT_LOAD='(1.0,-1.0)';
    'G1_TXP9':
      PIN_NUMBER='(0,0,0,0,0,0,0,0,0,0,0,AL46,0,0,0,0,0,0,0,0,0,0,0,0,0,0,0,0,0,0,0,0,0,0,0,0,0,0,0,0)';
      OUTPUT_LOAD='(1.0,-1.0)';
    'G1_TXP8':
      PIN_NUMBER='(0,0,0,0,0,0,0,0,0,0,0,AJ46,0,0,0,0,0,0,0,0,0,0,0,0,0,0,0,0,0,0,0,0,0,0,0,0,0,0,0,0)';
      OUTPUT_LOAD='(1.0,-1.0)';
    'G1_TXN15':
      PIN_NUMBER='(0,0,0,0,0,0,0,0,0,0,0,AL53,0,0,0,0,0,0,0,0,0,0,0,0,0,0,0,0,0,0,0,0,0,0,0,0,0,0,0,0)';
      OUTPUT_LOAD='(1.0,-1.0)';
    'G1_TXN14':
      PIN_NUMBER='(0,0,0,0,0,0,0,0,0,0,0,AJ53,0,0,0,0,0,0,0,0,0,0,0,0,0,0,0,0,0,0,0,0,0,0,0,0,0,0,0,0)';
      OUTPUT_LOAD='(1.0,-1.0)';
    'G1_TXN13':
      PIN_NUMBER='(0,0,0,0,0,0,0,0,0,0,0,AN53,0,0,0,0,0,0,0,0,0,0,0,0,0,0,0,0,0,0,0,0,0,0,0,0,0,0,0,0)';
      OUTPUT_LOAD='(1.0,-1.0)';
    'G1_TXN12':
      PIN_NUMBER='(0,0,0,0,0,0,0,0,0,0,0,AL50,0,0,0,0,0,0,0,0,0,0,0,0,0,0,0,0,0,0,0,0,0,0,0,0,0,0,0,0)';
      OUTPUT_LOAD='(1.0,-1.0)';
    'G1_TXN11':
      PIN_NUMBER='(0,0,0,0,0,0,0,0,0,0,0,AJ50,0,0,0,0,0,0,0,0,0,0,0,0,0,0,0,0,0,0,0,0,0,0,0,0,0,0,0,0)';
      OUTPUT_LOAD='(1.0,-1.0)';
    'G1_TXN10':
      PIN_NUMBER='(0,0,0,0,0,0,0,0,0,0,0,AN50,0,0,0,0,0,0,0,0,0,0,0,0,0,0,0,0,0,0,0,0,0,0,0,0,0,0,0,0)';
      OUTPUT_LOAD='(1.0,-1.0)';
    'G1_TXN9':
      PIN_NUMBER='(0,0,0,0,0,0,0,0,0,0,0,AL47,0,0,0,0,0,0,0,0,0,0,0,0,0,0,0,0,0,0,0,0,0,0,0,0,0,0,0,0)';
      OUTPUT_LOAD='(1.0,-1.0)';
    'G1_TXN8':
      PIN_NUMBER='(0,0,0,0,0,0,0,0,0,0,0,AJ47,0,0,0,0,0,0,0,0,0,0,0,0,0,0,0,0,0,0,0,0,0,0,0,0,0,0,0,0)';
      OUTPUT_LOAD='(1.0,-1.0)';
    'G1_RXP15':
      PIN_NUMBER='(0,0,0,0,0,0,0,0,0,0,0,U53,0,0,0,0,0,0,0,0,0,0,0,0,0,0,0,0,0,0,0,0,0,0,0,0,0,0,0,0)';
      INPUT_LOAD='(-0.01,0.01)';
    'G1_RXP14':
      PIN_NUMBER='(0,0,0,0,0,0,0,0,0,0,0,R53,0,0,0,0,0,0,0,0,0,0,0,0,0,0,0,0,0,0,0,0,0,0,0,0,0,0,0,0)';
      INPUT_LOAD='(-0.01,0.01)';
    'G1_RXP13':
      PIN_NUMBER='(0,0,0,0,0,0,0,0,0,0,0,W53,0,0,0,0,0,0,0,0,0,0,0,0,0,0,0,0,0,0,0,0,0,0,0,0,0,0,0,0)';
      INPUT_LOAD='(-0.01,0.01)';
    'G1_RXP12':
      PIN_NUMBER='(0,0,0,0,0,0,0,0,0,0,0,U50,0,0,0,0,0,0,0,0,0,0,0,0,0,0,0,0,0,0,0,0,0,0,0,0,0,0,0,0)';
      INPUT_LOAD='(-0.01,0.01)';
    'G1_RXP11':
      PIN_NUMBER='(0,0,0,0,0,0,0,0,0,0,0,R50,0,0,0,0,0,0,0,0,0,0,0,0,0,0,0,0,0,0,0,0,0,0,0,0,0,0,0,0)';
      INPUT_LOAD='(-0.01,0.01)';
    'G1_RXP10':
      PIN_NUMBER='(0,0,0,0,0,0,0,0,0,0,0,N50,0,0,0,0,0,0,0,0,0,0,0,0,0,0,0,0,0,0,0,0,0,0,0,0,0,0,0,0)';
      INPUT_LOAD='(-0.01,0.01)';
    'G1_RXP9':
      PIN_NUMBER='(0,0,0,0,0,0,0,0,0,0,0,W50,0,0,0,0,0,0,0,0,0,0,0,0,0,0,0,0,0,0,0,0,0,0,0,0,0,0,0,0)';
      INPUT_LOAD='(-0.01,0.01)';
    'G1_RXP8':
      PIN_NUMBER='(0,0,0,0,0,0,0,0,0,0,0,R47,0,0,0,0,0,0,0,0,0,0,0,0,0,0,0,0,0,0,0,0,0,0,0,0,0,0,0,0)';
      INPUT_LOAD='(-0.01,0.01)';
    'G1_RXN15':
      PIN_NUMBER='(0,0,0,0,0,0,0,0,0,0,0,U52,0,0,0,0,0,0,0,0,0,0,0,0,0,0,0,0,0,0,0,0,0,0,0,0,0,0,0,0)';
      INPUT_LOAD='(-0.01,0.01)';
    'G1_RXN14':
      PIN_NUMBER='(0,0,0,0,0,0,0,0,0,0,0,R52,0,0,0,0,0,0,0,0,0,0,0,0,0,0,0,0,0,0,0,0,0,0,0,0,0,0,0,0)';
      INPUT_LOAD='(-0.01,0.01)';
    'G1_RXN13':
      PIN_NUMBER='(0,0,0,0,0,0,0,0,0,0,0,W52,0,0,0,0,0,0,0,0,0,0,0,0,0,0,0,0,0,0,0,0,0,0,0,0,0,0,0,0)';
      INPUT_LOAD='(-0.01,0.01)';
    'G1_RXN12':
      PIN_NUMBER='(0,0,0,0,0,0,0,0,0,0,0,U49,0,0,0,0,0,0,0,0,0,0,0,0,0,0,0,0,0,0,0,0,0,0,0,0,0,0,0,0)';
      INPUT_LOAD='(-0.01,0.01)';
    'G1_RXN11':
      PIN_NUMBER='(0,0,0,0,0,0,0,0,0,0,0,R49,0,0,0,0,0,0,0,0,0,0,0,0,0,0,0,0,0,0,0,0,0,0,0,0,0,0,0,0)';
      INPUT_LOAD='(-0.01,0.01)';
    'G1_RXN10':
      PIN_NUMBER='(0,0,0,0,0,0,0,0,0,0,0,N49,0,0,0,0,0,0,0,0,0,0,0,0,0,0,0,0,0,0,0,0,0,0,0,0,0,0,0,0)';
      INPUT_LOAD='(-0.01,0.01)';
    'G1_RXN9':
      PIN_NUMBER='(0,0,0,0,0,0,0,0,0,0,0,W49,0,0,0,0,0,0,0,0,0,0,0,0,0,0,0,0,0,0,0,0,0,0,0,0,0,0,0,0)';
      INPUT_LOAD='(-0.01,0.01)';
    'G1_RXN8':
      PIN_NUMBER='(0,0,0,0,0,0,0,0,0,0,0,R46,0,0,0,0,0,0,0,0,0,0,0,0,0,0,0,0,0,0,0,0,0,0,0,0,0,0,0,0)';
      INPUT_LOAD='(-0.01,0.01)';
    'G1_TXP0':
      PIN_NUMBER='(0,0,0,0,0,0,0,0,0,0,0,AP40,0,0,0,0,0,0,0,0,0,0,0,0,0,0,0,0,0,0,0,0,0,0,0,0,0,0,0,0)';
      OUTPUT_LOAD='(1.0,-1.0)';
    'G1_TXP1':
      PIN_NUMBER='(0,0,0,0,0,0,0,0,0,0,0,AM40,0,0,0,0,0,0,0,0,0,0,0,0,0,0,0,0,0,0,0,0,0,0,0,0,0,0,0,0)';
      OUTPUT_LOAD='(1.0,-1.0)';
    'G1_TXP2':
      PIN_NUMBER='(0,0,0,0,0,0,0,0,0,0,0,AH40,0,0,0,0,0,0,0,0,0,0,0,0,0,0,0,0,0,0,0,0,0,0,0,0,0,0,0,0)';
      OUTPUT_LOAD='(1.0,-1.0)';
    'G1_TXN0':
      PIN_NUMBER='(0,0,0,0,0,0,0,0,0,0,0,AP41,0,0,0,0,0,0,0,0,0,0,0,0,0,0,0,0,0,0,0,0,0,0,0,0,0,0,0,0)';
      OUTPUT_LOAD='(1.0,-1.0)';
    'G1_RXP0':
      PIN_NUMBER='(0,0,0,0,0,0,0,0,0,0,0,V41,0,0,0,0,0,0,0,0,0,0,0,0,0,0,0,0,0,0,0,0,0,0,0,0,0,0,0,0)';
      INPUT_LOAD='(-0.01,0.01)';
    'G1_TXP3':
      PIN_NUMBER='(0,0,0,0,0,0,0,0,0,0,0,AK40,0,0,0,0,0,0,0,0,0,0,0,0,0,0,0,0,0,0,0,0,0,0,0,0,0,0,0,0)';
      OUTPUT_LOAD='(1.0,-1.0)';
    'G1_TXN1':
      PIN_NUMBER='(0,0,0,0,0,0,0,0,0,0,0,AM41,0,0,0,0,0,0,0,0,0,0,0,0,0,0,0,0,0,0,0,0,0,0,0,0,0,0,0,0)';
      OUTPUT_LOAD='(1.0,-1.0)';
    'G1_RXP1':
      PIN_NUMBER='(0,0,0,0,0,0,0,0,0,0,0,T41,0,0,0,0,0,0,0,0,0,0,0,0,0,0,0,0,0,0,0,0,0,0,0,0,0,0,0,0)';
      INPUT_LOAD='(-0.01,0.01)';
    'G1_TXP4':
      PIN_NUMBER='(0,0,0,0,0,0,0,0,0,0,0,AN43,0,0,0,0,0,0,0,0,0,0,0,0,0,0,0,0,0,0,0,0,0,0,0,0,0,0,0,0)';
      OUTPUT_LOAD='(1.0,-1.0)';
    'G1_TXN2':
      PIN_NUMBER='(0,0,0,0,0,0,0,0,0,0,0,AH41,0,0,0,0,0,0,0,0,0,0,0,0,0,0,0,0,0,0,0,0,0,0,0,0,0,0,0,0)';
      OUTPUT_LOAD='(1.0,-1.0)';
    'G1_RXP2':
      PIN_NUMBER='(0,0,0,0,0,0,0,0,0,0,0,P41,0,0,0,0,0,0,0,0,0,0,0,0,0,0,0,0,0,0,0,0,0,0,0,0,0,0,0,0)';
      INPUT_LOAD='(-0.01,0.01)';
    'G1_RXN0':
      PIN_NUMBER='(0,0,0,0,0,0,0,0,0,0,0,V40,0,0,0,0,0,0,0,0,0,0,0,0,0,0,0,0,0,0,0,0,0,0,0,0,0,0,0,0)';
      INPUT_LOAD='(-0.01,0.01)';
    'G1_TXP5':
      PIN_NUMBER='(0,0,0,0,0,0,0,0,0,0,0,AJ43,0,0,0,0,0,0,0,0,0,0,0,0,0,0,0,0,0,0,0,0,0,0,0,0,0,0,0,0)';
      OUTPUT_LOAD='(1.0,-1.0)';
    'G1_TXN3':
      PIN_NUMBER='(0,0,0,0,0,0,0,0,0,0,0,AK41,0,0,0,0,0,0,0,0,0,0,0,0,0,0,0,0,0,0,0,0,0,0,0,0,0,0,0,0)';
      OUTPUT_LOAD='(1.0,-1.0)';
    'G1_RXP3':
      PIN_NUMBER='(0,0,0,0,0,0,0,0,0,0,0,U44,0,0,0,0,0,0,0,0,0,0,0,0,0,0,0,0,0,0,0,0,0,0,0,0,0,0,0,0)';
      INPUT_LOAD='(-0.01,0.01)';
    'G1_RXN1':
      PIN_NUMBER='(0,0,0,0,0,0,0,0,0,0,0,T40,0,0,0,0,0,0,0,0,0,0,0,0,0,0,0,0,0,0,0,0,0,0,0,0,0,0,0,0)';
      INPUT_LOAD='(-0.01,0.01)';
    'G1_TXP6':
      PIN_NUMBER='(0,0,0,0,0,0,0,0,0,0,0,AL43,0,0,0,0,0,0,0,0,0,0,0,0,0,0,0,0,0,0,0,0,0,0,0,0,0,0,0,0)';
      OUTPUT_LOAD='(1.0,-1.0)';
    'G1_TXN4':
      PIN_NUMBER='(0,0,0,0,0,0,0,0,0,0,0,AN44,0,0,0,0,0,0,0,0,0,0,0,0,0,0,0,0,0,0,0,0,0,0,0,0,0,0,0,0)';
      OUTPUT_LOAD='(1.0,-1.0)';
    'G1_RXP4':
      PIN_NUMBER='(0,0,0,0,0,0,0,0,0,0,0,N44,0,0,0,0,0,0,0,0,0,0,0,0,0,0,0,0,0,0,0,0,0,0,0,0,0,0,0,0)';
      INPUT_LOAD='(-0.01,0.01)';
    'G1_RXN2':
      PIN_NUMBER='(0,0,0,0,0,0,0,0,0,0,0,P40,0,0,0,0,0,0,0,0,0,0,0,0,0,0,0,0,0,0,0,0,0,0,0,0,0,0,0,0)';
      INPUT_LOAD='(-0.01,0.01)';
    'G1_TXP7':
      PIN_NUMBER='(0,0,0,0,0,0,0,0,0,0,0,AN46,0,0,0,0,0,0,0,0,0,0,0,0,0,0,0,0,0,0,0,0,0,0,0,0,0,0,0,0)';
      OUTPUT_LOAD='(1.0,-1.0)';
    'G1_TXN5':
      PIN_NUMBER='(0,0,0,0,0,0,0,0,0,0,0,AJ44,0,0,0,0,0,0,0,0,0,0,0,0,0,0,0,0,0,0,0,0,0,0,0,0,0,0,0,0)';
      OUTPUT_LOAD='(1.0,-1.0)';
    'G1_RXP5':
      PIN_NUMBER='(0,0,0,0,0,0,0,0,0,0,0,R44,0,0,0,0,0,0,0,0,0,0,0,0,0,0,0,0,0,0,0,0,0,0,0,0,0,0,0,0)';
      INPUT_LOAD='(-0.01,0.01)';
    'G1_RXN3':
      PIN_NUMBER='(0,0,0,0,0,0,0,0,0,0,0,U43,0,0,0,0,0,0,0,0,0,0,0,0,0,0,0,0,0,0,0,0,0,0,0,0,0,0,0,0)';
      INPUT_LOAD='(-0.01,0.01)';
    'G1_TXN6':
      PIN_NUMBER='(0,0,0,0,0,0,0,0,0,0,0,AL44,0,0,0,0,0,0,0,0,0,0,0,0,0,0,0,0,0,0,0,0,0,0,0,0,0,0,0,0)';
      OUTPUT_LOAD='(1.0,-1.0)';
    'G1_RXP6':
      PIN_NUMBER='(0,0,0,0,0,0,0,0,0,0,0,U47,0,0,0,0,0,0,0,0,0,0,0,0,0,0,0,0,0,0,0,0,0,0,0,0,0,0,0,0)';
      INPUT_LOAD='(-0.01,0.01)';
    'G1_RXN4':
      PIN_NUMBER='(0,0,0,0,0,0,0,0,0,0,0,N43,0,0,0,0,0,0,0,0,0,0,0,0,0,0,0,0,0,0,0,0,0,0,0,0,0,0,0,0)';
      INPUT_LOAD='(-0.01,0.01)';
    'G1_TXN7':
      PIN_NUMBER='(0,0,0,0,0,0,0,0,0,0,0,AN47,0,0,0,0,0,0,0,0,0,0,0,0,0,0,0,0,0,0,0,0,0,0,0,0,0,0,0,0)';
      OUTPUT_LOAD='(1.0,-1.0)';
    'G1_RXP7':
      PIN_NUMBER='(0,0,0,0,0,0,0,0,0,0,0,N47,0,0,0,0,0,0,0,0,0,0,0,0,0,0,0,0,0,0,0,0,0,0,0,0,0,0,0,0)';
      INPUT_LOAD='(-0.01,0.01)';
    'G1_RXN5':
      PIN_NUMBER='(0,0,0,0,0,0,0,0,0,0,0,R43,0,0,0,0,0,0,0,0,0,0,0,0,0,0,0,0,0,0,0,0,0,0,0,0,0,0,0,0)';
      INPUT_LOAD='(-0.01,0.01)';
    'G1_RXN6':
      PIN_NUMBER='(0,0,0,0,0,0,0,0,0,0,0,U46,0,0,0,0,0,0,0,0,0,0,0,0,0,0,0,0,0,0,0,0,0,0,0,0,0,0,0,0)';
      INPUT_LOAD='(-0.01,0.01)';
    'G1_RXN7':
      PIN_NUMBER='(0,0,0,0,0,0,0,0,0,0,0,N46,0,0,0,0,0,0,0,0,0,0,0,0,0,0,0,0,0,0,0,0,0,0,0,0,0,0,0,0)';
      INPUT_LOAD='(-0.01,0.01)';
    'G2_TXP8':
      PIN_NUMBER='(0,0,0,0,0,0,0,0,0,0,0,0,G29,0,0,0,0,0,0,0,0,0,0,0,0,0,0,0,0,0,0,0,0,0,0,0,0,0,0,0)';
      OUTPUT_LOAD='(1.0,-1.0)';
    'G2_TXN8':
      PIN_NUMBER='(0,0,0,0,0,0,0,0,0,0,0,0,G30,0,0,0,0,0,0,0,0,0,0,0,0,0,0,0,0,0,0,0,0,0,0,0,0,0,0,0)';
      OUTPUT_LOAD='(1.0,-1.0)';
    'G2_TXP10':
      PIN_NUMBER='(0,0,0,0,0,0,0,0,0,0,0,0,J32,0,0,0,0,0,0,0,0,0,0,0,0,0,0,0,0,0,0,0,0,0,0,0,0,0,0,0)';
      OUTPUT_LOAD='(1.0,-1.0)';
    'G2_TXN10':
      PIN_NUMBER='(0,0,0,0,0,0,0,0,0,0,0,0,J33,0,0,0,0,0,0,0,0,0,0,0,0,0,0,0,0,0,0,0,0,0,0,0,0,0,0,0)';
      OUTPUT_LOAD='(1.0,-1.0)';
    'G2_TXP12':
      PIN_NUMBER='(0,0,0,0,0,0,0,0,0,0,0,0,L32,0,0,0,0,0,0,0,0,0,0,0,0,0,0,0,0,0,0,0,0,0,0,0,0,0,0,0)';
      OUTPUT_LOAD='(1.0,-1.0)';
    'G2_TXN12':
      PIN_NUMBER='(0,0,0,0,0,0,0,0,0,0,0,0,L33,0,0,0,0,0,0,0,0,0,0,0,0,0,0,0,0,0,0,0,0,0,0,0,0,0,0,0)';
      OUTPUT_LOAD='(1.0,-1.0)';
    'G2_TXP14':
      PIN_NUMBER='(0,0,0,0,0,0,0,0,0,0,0,0,K35,0,0,0,0,0,0,0,0,0,0,0,0,0,0,0,0,0,0,0,0,0,0,0,0,0,0,0)';
      OUTPUT_LOAD='(1.0,-1.0)';
    'G2_TXN14':
      PIN_NUMBER='(0,0,0,0,0,0,0,0,0,0,0,0,K36,0,0,0,0,0,0,0,0,0,0,0,0,0,0,0,0,0,0,0,0,0,0,0,0,0,0,0)';
      OUTPUT_LOAD='(1.0,-1.0)';
    'G2_TXP9':
      PIN_NUMBER='(0,0,0,0,0,0,0,0,0,0,0,0,L29,0,0,0,0,0,0,0,0,0,0,0,0,0,0,0,0,0,0,0,0,0,0,0,0,0,0,0)';
      OUTPUT_LOAD='(1.0,-1.0)';
    'G2_TXN9':
      PIN_NUMBER='(0,0,0,0,0,0,0,0,0,0,0,0,L30,0,0,0,0,0,0,0,0,0,0,0,0,0,0,0,0,0,0,0,0,0,0,0,0,0,0,0)';
      OUTPUT_LOAD='(1.0,-1.0)';
    'G2_TXP11':
      PIN_NUMBER='(0,0,0,0,0,0,0,0,0,0,0,0,G32,0,0,0,0,0,0,0,0,0,0,0,0,0,0,0,0,0,0,0,0,0,0,0,0,0,0,0)';
      OUTPUT_LOAD='(1.0,-1.0)';
    'G2_TXN11':
      PIN_NUMBER='(0,0,0,0,0,0,0,0,0,0,0,0,G33,0,0,0,0,0,0,0,0,0,0,0,0,0,0,0,0,0,0,0,0,0,0,0,0,0,0,0)';
      OUTPUT_LOAD='(1.0,-1.0)';
    'G2_TXP13':
      PIN_NUMBER='(0,0,0,0,0,0,0,0,0,0,0,0,H35,0,0,0,0,0,0,0,0,0,0,0,0,0,0,0,0,0,0,0,0,0,0,0,0,0,0,0)';
      OUTPUT_LOAD='(1.0,-1.0)';
    'G2_TXN13':
      PIN_NUMBER='(0,0,0,0,0,0,0,0,0,0,0,0,H36,0,0,0,0,0,0,0,0,0,0,0,0,0,0,0,0,0,0,0,0,0,0,0,0,0,0,0)';
      OUTPUT_LOAD='(1.0,-1.0)';
    'G2_TXP15':
      PIN_NUMBER='(0,0,0,0,0,0,0,0,0,0,0,0,M35,0,0,0,0,0,0,0,0,0,0,0,0,0,0,0,0,0,0,0,0,0,0,0,0,0,0,0)';
      OUTPUT_LOAD='(1.0,-1.0)';
    'G2_TXN15':
      PIN_NUMBER='(0,0,0,0,0,0,0,0,0,0,0,0,M36,0,0,0,0,0,0,0,0,0,0,0,0,0,0,0,0,0,0,0,0,0,0,0,0,0,0,0)';
      OUTPUT_LOAD='(1.0,-1.0)';
    'G2_RXP8':
      PIN_NUMBER='(0,0,0,0,0,0,0,0,0,0,0,0,AG30,0,0,0,0,0,0,0,0,0,0,0,0,0,0,0,0,0,0,0,0,0,0,0,0,0,0,0)';
      INPUT_LOAD='(-0.01,0.01)';
    'G2_RXN8':
      PIN_NUMBER='(0,0,0,0,0,0,0,0,0,0,0,0,AG29,0,0,0,0,0,0,0,0,0,0,0,0,0,0,0,0,0,0,0,0,0,0,0,0,0,0,0)';
      INPUT_LOAD='(-0.01,0.01)';
    'G2_RXP10':
      PIN_NUMBER='(0,0,0,0,0,0,0,0,0,0,0,0,AC33,0,0,0,0,0,0,0,0,0,0,0,0,0,0,0,0,0,0,0,0,0,0,0,0,0,0,0)';
      INPUT_LOAD='(-0.01,0.01)';
    'G2_RXN10':
      PIN_NUMBER='(0,0,0,0,0,0,0,0,0,0,0,0,AC32,0,0,0,0,0,0,0,0,0,0,0,0,0,0,0,0,0,0,0,0,0,0,0,0,0,0,0)';
      INPUT_LOAD='(-0.01,0.01)';
    'G2_RXP12':
      PIN_NUMBER='(0,0,0,0,0,0,0,0,0,0,0,0,AG33,0,0,0,0,0,0,0,0,0,0,0,0,0,0,0,0,0,0,0,0,0,0,0,0,0,0,0)';
      INPUT_LOAD='(-0.01,0.01)';
    'G2_RXN12':
      PIN_NUMBER='(0,0,0,0,0,0,0,0,0,0,0,0,AG32,0,0,0,0,0,0,0,0,0,0,0,0,0,0,0,0,0,0,0,0,0,0,0,0,0,0,0)';
      INPUT_LOAD='(-0.01,0.01)';
    'G2_RXP14':
      PIN_NUMBER='(0,0,0,0,0,0,0,0,0,0,0,0,AD36,0,0,0,0,0,0,0,0,0,0,0,0,0,0,0,0,0,0,0,0,0,0,0,0,0,0,0)';
      INPUT_LOAD='(-0.01,0.01)';
    'G2_RXN14':
      PIN_NUMBER='(0,0,0,0,0,0,0,0,0,0,0,0,AD35,0,0,0,0,0,0,0,0,0,0,0,0,0,0,0,0,0,0,0,0,0,0,0,0,0,0,0)';
      INPUT_LOAD='(-0.01,0.01)';
    'G2_RXP9':
      PIN_NUMBER='(0,0,0,0,0,0,0,0,0,0,0,0,AE33,0,0,0,0,0,0,0,0,0,0,0,0,0,0,0,0,0,0,0,0,0,0,0,0,0,0,0)';
      INPUT_LOAD='(-0.01,0.01)';
    'G2_RXN9':
      PIN_NUMBER='(0,0,0,0,0,0,0,0,0,0,0,0,AE32,0,0,0,0,0,0,0,0,0,0,0,0,0,0,0,0,0,0,0,0,0,0,0,0,0,0,0)';
      INPUT_LOAD='(-0.01,0.01)';
    'G2_RXP11':
      PIN_NUMBER='(0,0,0,0,0,0,0,0,0,0,0,0,AA33,0,0,0,0,0,0,0,0,0,0,0,0,0,0,0,0,0,0,0,0,0,0,0,0,0,0,0)';
      INPUT_LOAD='(-0.01,0.01)';
    'G2_RXN11':
      PIN_NUMBER='(0,0,0,0,0,0,0,0,0,0,0,0,AA32,0,0,0,0,0,0,0,0,0,0,0,0,0,0,0,0,0,0,0,0,0,0,0,0,0,0,0)';
      INPUT_LOAD='(-0.01,0.01)';
    'G2_RXP13':
      PIN_NUMBER='(0,0,0,0,0,0,0,0,0,0,0,0,AB36,0,0,0,0,0,0,0,0,0,0,0,0,0,0,0,0,0,0,0,0,0,0,0,0,0,0,0)';
      INPUT_LOAD='(-0.01,0.01)';
    'G2_RXN13':
      PIN_NUMBER='(0,0,0,0,0,0,0,0,0,0,0,0,AB35,0,0,0,0,0,0,0,0,0,0,0,0,0,0,0,0,0,0,0,0,0,0,0,0,0,0,0)';
      INPUT_LOAD='(-0.01,0.01)';
    'G2_RXP15':
      PIN_NUMBER='(0,0,0,0,0,0,0,0,0,0,0,0,AF36,0,0,0,0,0,0,0,0,0,0,0,0,0,0,0,0,0,0,0,0,0,0,0,0,0,0,0)';
      INPUT_LOAD='(-0.01,0.01)';
    'G2_RXN15':
      PIN_NUMBER='(0,0,0,0,0,0,0,0,0,0,0,0,AF35,0,0,0,0,0,0,0,0,0,0,0,0,0,0,0,0,0,0,0,0,0,0,0,0,0,0,0)';
      INPUT_LOAD='(-0.01,0.01)';
    'G2_TXP1':
      PIN_NUMBER='(0,0,0,0,0,0,0,0,0,0,0,0,J23,0,0,0,0,0,0,0,0,0,0,0,0,0,0,0,0,0,0,0,0,0,0,0,0,0,0,0)';
      OUTPUT_LOAD='(1.0,-1.0)';
    'G2_TXP2':
      PIN_NUMBER='(0,0,0,0,0,0,0,0,0,0,0,0,G23,0,0,0,0,0,0,0,0,0,0,0,0,0,0,0,0,0,0,0,0,0,0,0,0,0,0,0)';
      OUTPUT_LOAD='(1.0,-1.0)';
    'G2_TXN0':
      PIN_NUMBER='(0,0,0,0,0,0,0,0,0,0,0,0,N24,0,0,0,0,0,0,0,0,0,0,0,0,0,0,0,0,0,0,0,0,0,0,0,0,0,0,0)';
      OUTPUT_LOAD='(1.0,-1.0)';
    'G2_RXP0':
      PIN_NUMBER='(0,0,0,0,0,0,0,0,0,0,0,0,AE24,0,0,0,0,0,0,0,0,0,0,0,0,0,0,0,0,0,0,0,0,0,0,0,0,0,0,0)';
      INPUT_LOAD='(-0.01,0.01)';
    'G2_TXP3':
      PIN_NUMBER='(0,0,0,0,0,0,0,0,0,0,0,0,L23,0,0,0,0,0,0,0,0,0,0,0,0,0,0,0,0,0,0,0,0,0,0,0,0,0,0,0)';
      OUTPUT_LOAD='(1.0,-1.0)';
    'G2_TXN1':
      PIN_NUMBER='(0,0,0,0,0,0,0,0,0,0,0,0,J24,0,0,0,0,0,0,0,0,0,0,0,0,0,0,0,0,0,0,0,0,0,0,0,0,0,0,0)';
      OUTPUT_LOAD='(1.0,-1.0)';
    'G2_RXP1':
      PIN_NUMBER='(0,0,0,0,0,0,0,0,0,0,0,0,AC24,0,0,0,0,0,0,0,0,0,0,0,0,0,0,0,0,0,0,0,0,0,0,0,0,0,0,0)';
      INPUT_LOAD='(-0.01,0.01)';
    'G2_TXP4':
      PIN_NUMBER='(0,0,0,0,0,0,0,0,0,0,0,0,J26,0,0,0,0,0,0,0,0,0,0,0,0,0,0,0,0,0,0,0,0,0,0,0,0,0,0,0)';
      OUTPUT_LOAD='(1.0,-1.0)';
    'G2_TXN2':
      PIN_NUMBER='(0,0,0,0,0,0,0,0,0,0,0,0,G24,0,0,0,0,0,0,0,0,0,0,0,0,0,0,0,0,0,0,0,0,0,0,0,0,0,0,0)';
      OUTPUT_LOAD='(1.0,-1.0)';
    'G2_RXP2':
      PIN_NUMBER='(0,0,0,0,0,0,0,0,0,0,0,0,AG24,0,0,0,0,0,0,0,0,0,0,0,0,0,0,0,0,0,0,0,0,0,0,0,0,0,0,0)';
      INPUT_LOAD='(-0.01,0.01)';
    'G2_RXN0':
      PIN_NUMBER='(0,0,0,0,0,0,0,0,0,0,0,0,AE23,0,0,0,0,0,0,0,0,0,0,0,0,0,0,0,0,0,0,0,0,0,0,0,0,0,0,0)';
      INPUT_LOAD='(-0.01,0.01)';
    'G2_TXP5':
      PIN_NUMBER='(0,0,0,0,0,0,0,0,0,0,0,0,G26,0,0,0,0,0,0,0,0,0,0,0,0,0,0,0,0,0,0,0,0,0,0,0,0,0,0,0)';
      OUTPUT_LOAD='(1.0,-1.0)';
    'G2_TXN3':
      PIN_NUMBER='(0,0,0,0,0,0,0,0,0,0,0,0,L24,0,0,0,0,0,0,0,0,0,0,0,0,0,0,0,0,0,0,0,0,0,0,0,0,0,0,0)';
      OUTPUT_LOAD='(1.0,-1.0)';
    'G2_RXP3':
      PIN_NUMBER='(0,0,0,0,0,0,0,0,0,0,0,0,AE27,0,0,0,0,0,0,0,0,0,0,0,0,0,0,0,0,0,0,0,0,0,0,0,0,0,0,0)';
      INPUT_LOAD='(-0.01,0.01)';
    'G2_RXN1':
      PIN_NUMBER='(0,0,0,0,0,0,0,0,0,0,0,0,AC23,0,0,0,0,0,0,0,0,0,0,0,0,0,0,0,0,0,0,0,0,0,0,0,0,0,0,0)';
      INPUT_LOAD='(-0.01,0.01)';
    'G2_TXP6':
      PIN_NUMBER='(0,0,0,0,0,0,0,0,0,0,0,0,L26,0,0,0,0,0,0,0,0,0,0,0,0,0,0,0,0,0,0,0,0,0,0,0,0,0,0,0)';
      OUTPUT_LOAD='(1.0,-1.0)';
    'G2_TXN4':
      PIN_NUMBER='(0,0,0,0,0,0,0,0,0,0,0,0,J27,0,0,0,0,0,0,0,0,0,0,0,0,0,0,0,0,0,0,0,0,0,0,0,0,0,0,0)';
      OUTPUT_LOAD='(1.0,-1.0)';
    'G2_RXP4':
      PIN_NUMBER='(0,0,0,0,0,0,0,0,0,0,0,0,AC27,0,0,0,0,0,0,0,0,0,0,0,0,0,0,0,0,0,0,0,0,0,0,0,0,0,0,0)';
      INPUT_LOAD='(-0.01,0.01)';
    'G2_RXN2':
      PIN_NUMBER='(0,0,0,0,0,0,0,0,0,0,0,0,AG23,0,0,0,0,0,0,0,0,0,0,0,0,0,0,0,0,0,0,0,0,0,0,0,0,0,0,0)';
      INPUT_LOAD='(-0.01,0.01)';
    'G2_TXP7':
      PIN_NUMBER='(0,0,0,0,0,0,0,0,0,0,0,0,J29,0,0,0,0,0,0,0,0,0,0,0,0,0,0,0,0,0,0,0,0,0,0,0,0,0,0,0)';
      OUTPUT_LOAD='(1.0,-1.0)';
    'G2_TXN5':
      PIN_NUMBER='(0,0,0,0,0,0,0,0,0,0,0,0,G27,0,0,0,0,0,0,0,0,0,0,0,0,0,0,0,0,0,0,0,0,0,0,0,0,0,0,0)';
      OUTPUT_LOAD='(1.0,-1.0)';
    'G2_RXP5':
      PIN_NUMBER='(0,0,0,0,0,0,0,0,0,0,0,0,AG27,0,0,0,0,0,0,0,0,0,0,0,0,0,0,0,0,0,0,0,0,0,0,0,0,0,0,0)';
      INPUT_LOAD='(-0.01,0.01)';
    'G2_RXN3':
      PIN_NUMBER='(0,0,0,0,0,0,0,0,0,0,0,0,AE26,0,0,0,0,0,0,0,0,0,0,0,0,0,0,0,0,0,0,0,0,0,0,0,0,0,0,0)';
      INPUT_LOAD='(-0.01,0.01)';
    'G2_TXN6':
      PIN_NUMBER='(0,0,0,0,0,0,0,0,0,0,0,0,L27,0,0,0,0,0,0,0,0,0,0,0,0,0,0,0,0,0,0,0,0,0,0,0,0,0,0,0)';
      OUTPUT_LOAD='(1.0,-1.0)';
    'G2_RXP6':
      PIN_NUMBER='(0,0,0,0,0,0,0,0,0,0,0,0,AE30,0,0,0,0,0,0,0,0,0,0,0,0,0,0,0,0,0,0,0,0,0,0,0,0,0,0,0)';
      INPUT_LOAD='(-0.01,0.01)';
    'G2_RXN4':
      PIN_NUMBER='(0,0,0,0,0,0,0,0,0,0,0,0,AC26,0,0,0,0,0,0,0,0,0,0,0,0,0,0,0,0,0,0,0,0,0,0,0,0,0,0,0)';
      INPUT_LOAD='(-0.01,0.01)';
    'G2_TXN7':
      PIN_NUMBER='(0,0,0,0,0,0,0,0,0,0,0,0,J30,0,0,0,0,0,0,0,0,0,0,0,0,0,0,0,0,0,0,0,0,0,0,0,0,0,0,0)';
      OUTPUT_LOAD='(1.0,-1.0)';
    'G2_RXP7':
      PIN_NUMBER='(0,0,0,0,0,0,0,0,0,0,0,0,AC30,0,0,0,0,0,0,0,0,0,0,0,0,0,0,0,0,0,0,0,0,0,0,0,0,0,0,0)';
      INPUT_LOAD='(-0.01,0.01)';
    'G2_RXN5':
      PIN_NUMBER='(0,0,0,0,0,0,0,0,0,0,0,0,AG26,0,0,0,0,0,0,0,0,0,0,0,0,0,0,0,0,0,0,0,0,0,0,0,0,0,0,0)';
      INPUT_LOAD='(-0.01,0.01)';
    'G2_RXN6':
      PIN_NUMBER='(0,0,0,0,0,0,0,0,0,0,0,0,AE29,0,0,0,0,0,0,0,0,0,0,0,0,0,0,0,0,0,0,0,0,0,0,0,0,0,0,0)';
      INPUT_LOAD='(-0.01,0.01)';
    'G2_RXN7':
      PIN_NUMBER='(0,0,0,0,0,0,0,0,0,0,0,0,AC29,0,0,0,0,0,0,0,0,0,0,0,0,0,0,0,0,0,0,0,0,0,0,0,0,0,0,0)';
      INPUT_LOAD='(-0.01,0.01)';
    'G2_TXP0':
      PIN_NUMBER='(0,0,0,0,0,0,0,0,0,0,0,0,N23,0,0,0,0,0,0,0,0,0,0,0,0,0,0,0,0,0,0,0,0,0,0,0,0,0,0,0)';
      OUTPUT_LOAD='(1.0,-1.0)';
    'G3_TXP13||SATA35_TXP':
      PIN_NUMBER='(0,0,0,0,0,0,0,0,0,0,0,0,0,P35,0,0,0,0,0,0,0,0,0,0,0,0,0,0,0,0,0,0,0,0,0,0,0,0,0,0)';
      OUTPUT_LOAD='(1.0,-1.0)';
    'G3_TXP10||SATA32_TXP':
      PIN_NUMBER='(0,0,0,0,0,0,0,0,0,0,0,0,0,R32,0,0,0,0,0,0,0,0,0,0,0,0,0,0,0,0,0,0,0,0,0,0,0,0,0,0)';
      OUTPUT_LOAD='(1.0,-1.0)';
    'G3_RXN5||SATA25_RXN':
      PIN_NUMBER='(0,0,0,0,0,0,0,0,0,0,0,0,0,AN26,0,0,0,0,0,0,0,0,0,0,0,0,0,0,0,0,0,0,0,0,0,0,0,0,0,0)';
      INPUT_LOAD='(-0.01,0.01)';
    'G3_TXN2||SATA22_TXN':
      PIN_NUMBER='(0,0,0,0,0,0,0,0,0,0,0,0,0,W24,0,0,0,0,0,0,0,0,0,0,0,0,0,0,0,0,0,0,0,0,0,0,0,0,0,0)';
      OUTPUT_LOAD='(1.0,-1.0)';
    'G3_RXP12||SATA34_RXP':
      PIN_NUMBER='(0,0,0,0,0,0,0,0,0,0,0,0,0,AK36,0,0,0,0,0,0,0,0,0,0,0,0,0,0,0,0,0,0,0,0,0,0,0,0,0,0)';
      INPUT_LOAD='(-0.01,0.01)';
    'G3_RXP0||SATA20_RXP':
      PIN_NUMBER='(0,0,0,0,0,0,0,0,0,0,0,0,0,AL24,0,0,0,0,0,0,0,0,0,0,0,0,0,0,0,0,0,0,0,0,0,0,0,0,0,0)';
      INPUT_LOAD='(-0.01,0.01)';
    'G3_TXN14||SATA36_TXN':
      PIN_NUMBER='(0,0,0,0,0,0,0,0,0,0,0,0,0,T36,0,0,0,0,0,0,0,0,0,0,0,0,0,0,0,0,0,0,0,0,0,0,0,0,0,0)';
      OUTPUT_LOAD='(1.0,-1.0)';
    'G3_TXN11||SATA33_TXN':
      PIN_NUMBER='(0,0,0,0,0,0,0,0,0,0,0,0,0,N33,0,0,0,0,0,0,0,0,0,0,0,0,0,0,0,0,0,0,0,0,0,0,0,0,0,0)';
      OUTPUT_LOAD='(1.0,-1.0)';
    'G3_TXN5||SATA25_TXN':
      PIN_NUMBER='(0,0,0,0,0,0,0,0,0,0,0,0,0,N27,0,0,0,0,0,0,0,0,0,0,0,0,0,0,0,0,0,0,0,0,0,0,0,0,0,0)';
      OUTPUT_LOAD='(1.0,-1.0)';
    'G3_RXP15||SATA37_RXP':
      PIN_NUMBER='(0,0,0,0,0,0,0,0,0,0,0,0,0,AP36,0,0,0,0,0,0,0,0,0,0,0,0,0,0,0,0,0,0,0,0,0,0,0,0,0,0)';
      INPUT_LOAD='(-0.01,0.01)';
    'G3_RXP6||SATA26_RXP':
      PIN_NUMBER='(0,0,0,0,0,0,0,0,0,0,0,0,0,AL30,0,0,0,0,0,0,0,0,0,0,0,0,0,0,0,0,0,0,0,0,0,0,0,0,0,0)';
      INPUT_LOAD='(-0.01,0.01)';
    'G3_RXP3||SATA23_RXP':
      PIN_NUMBER='(0,0,0,0,0,0,0,0,0,0,0,0,0,AL27,0,0,0,0,0,0,0,0,0,0,0,0,0,0,0,0,0,0,0,0,0,0,0,0,0,0)';
      INPUT_LOAD='(-0.01,0.01)';
    'G3_TXP3||SATA23_TXP':
      PIN_NUMBER='(0,0,0,0,0,0,0,0,0,0,0,0,0,U26,0,0,0,0,0,0,0,0,0,0,0,0,0,0,0,0,0,0,0,0,0,0,0,0,0,0)';
      OUTPUT_LOAD='(1.0,-1.0)';
    'G3_TXP0||SATA20_TXP':
      PIN_NUMBER='(0,0,0,0,0,0,0,0,0,0,0,0,0,U23,0,0,0,0,0,0,0,0,0,0,0,0,0,0,0,0,0,0,0,0,0,0,0,0,0,0)';
      OUTPUT_LOAD='(1.0,-1.0)';
    'G3_RXN10||SATA32_RXN':
      PIN_NUMBER='(0,0,0,0,0,0,0,0,0,0,0,0,0,AJ32,0,0,0,0,0,0,0,0,0,0,0,0,0,0,0,0,0,0,0,0,0,0,0,0,0,0)';
      INPUT_LOAD='(-0.01,0.01)';
    'G3_TXP6||SATA26_TXP':
      PIN_NUMBER='(0,0,0,0,0,0,0,0,0,0,0,0,0,W26,0,0,0,0,0,0,0,0,0,0,0,0,0,0,0,0,0,0,0,0,0,0,0,0,0,0)';
      OUTPUT_LOAD='(1.0,-1.0)';
    'G3_RXN13||SATA35_RXN':
      PIN_NUMBER='(0,0,0,0,0,0,0,0,0,0,0,0,0,AH35,0,0,0,0,0,0,0,0,0,0,0,0,0,0,0,0,0,0,0,0,0,0,0,0,0,0)';
      INPUT_LOAD='(-0.01,0.01)';
    'G3_TXP11||SATA33_TXP':
      PIN_NUMBER='(0,0,0,0,0,0,0,0,0,0,0,0,0,N32,0,0,0,0,0,0,0,0,0,0,0,0,0,0,0,0,0,0,0,0,0,0,0,0,0,0)';
      OUTPUT_LOAD='(1.0,-1.0)';
    'G3_RXP8||SATA30_RXP':
      PIN_NUMBER='(0,0,0,0,0,0,0,0,0,0,0,0,0,AN30,0,0,0,0,0,0,0,0,0,0,0,0,0,0,0,0,0,0,0,0,0,0,0,0,0,0)';
      INPUT_LOAD='(-0.01,0.01)';
    'G3_RXN3||SATA23_RXN':
      PIN_NUMBER='(0,0,0,0,0,0,0,0,0,0,0,0,0,AL26,0,0,0,0,0,0,0,0,0,0,0,0,0,0,0,0,0,0,0,0,0,0,0,0,0,0)';
      INPUT_LOAD='(-0.01,0.01)';
    'G3_RXN0||SATA20_RXN':
      PIN_NUMBER='(0,0,0,0,0,0,0,0,0,0,0,0,0,AL23,0,0,0,0,0,0,0,0,0,0,0,0,0,0,0,0,0,0,0,0,0,0,0,0,0,0)';
      INPUT_LOAD='(-0.01,0.01)';
    'G3_TXP14||SATA36_TXP':
      PIN_NUMBER='(0,0,0,0,0,0,0,0,0,0,0,0,0,T35,0,0,0,0,0,0,0,0,0,0,0,0,0,0,0,0,0,0,0,0,0,0,0,0,0,0)';
      OUTPUT_LOAD='(1.0,-1.0)';
    'G3_TXP8||SATA30_TXP':
      PIN_NUMBER='(0,0,0,0,0,0,0,0,0,0,0,0,0,N29,0,0,0,0,0,0,0,0,0,0,0,0,0,0,0,0,0,0,0,0,0,0,0,0,0,0)';
      OUTPUT_LOAD='(1.0,-1.0)';
    'G3_TXN0||SATA20_TXN':
      PIN_NUMBER='(0,0,0,0,0,0,0,0,0,0,0,0,0,U24,0,0,0,0,0,0,0,0,0,0,0,0,0,0,0,0,0,0,0,0,0,0,0,0,0,0)';
      OUTPUT_LOAD='(1.0,-1.0)';
    'G3_RXN6||SATA26_RXN':
      PIN_NUMBER='(0,0,0,0,0,0,0,0,0,0,0,0,0,AL29,0,0,0,0,0,0,0,0,0,0,0,0,0,0,0,0,0,0,0,0,0,0,0,0,0,0)';
      INPUT_LOAD='(-0.01,0.01)';
    'G3_TXN6||SATA26_TXN':
      PIN_NUMBER='(0,0,0,0,0,0,0,0,0,0,0,0,0,W27,0,0,0,0,0,0,0,0,0,0,0,0,0,0,0,0,0,0,0,0,0,0,0,0,0,0)';
      OUTPUT_LOAD='(1.0,-1.0)';
    'G3_TXN3||SATA23_TXN':
      PIN_NUMBER='(0,0,0,0,0,0,0,0,0,0,0,0,0,U27,0,0,0,0,0,0,0,0,0,0,0,0,0,0,0,0,0,0,0,0,0,0,0,0,0,0)';
      OUTPUT_LOAD='(1.0,-1.0)';
    'G3_RXP13||SATA35_RXP':
      PIN_NUMBER='(0,0,0,0,0,0,0,0,0,0,0,0,0,AH36,0,0,0,0,0,0,0,0,0,0,0,0,0,0,0,0,0,0,0,0,0,0,0,0,0,0)';
      INPUT_LOAD='(-0.01,0.01)';
    'G3_RXP10||SATA32_RXP':
      PIN_NUMBER='(0,0,0,0,0,0,0,0,0,0,0,0,0,AJ33,0,0,0,0,0,0,0,0,0,0,0,0,0,0,0,0,0,0,0,0,0,0,0,0,0,0)';
      INPUT_LOAD='(-0.01,0.01)';
    'G3_RXP4||SATA24_RXP':
      PIN_NUMBER='(0,0,0,0,0,0,0,0,0,0,0,0,0,AJ27,0,0,0,0,0,0,0,0,0,0,0,0,0,0,0,0,0,0,0,0,0,0,0,0,0,0)';
      INPUT_LOAD='(-0.01,0.01)';
    'G3_RXP1||SATA21_RXP':
      PIN_NUMBER='(0,0,0,0,0,0,0,0,0,0,0,0,0,AJ24,0,0,0,0,0,0,0,0,0,0,0,0,0,0,0,0,0,0,0,0,0,0,0,0,0,0)';
      INPUT_LOAD='(-0.01,0.01)';
    'G3_TXN15||SATA37_TXN':
      PIN_NUMBER='(0,0,0,0,0,0,0,0,0,0,0,0,0,V36,0,0,0,0,0,0,0,0,0,0,0,0,0,0,0,0,0,0,0,0,0,0,0,0,0,0)';
      OUTPUT_LOAD='(1.0,-1.0)';
    'G3_TXN12||SATA34_TXN':
      PIN_NUMBER='(0,0,0,0,0,0,0,0,0,0,0,0,0,U33,0,0,0,0,0,0,0,0,0,0,0,0,0,0,0,0,0,0,0,0,0,0,0,0,0,0)';
      OUTPUT_LOAD='(1.0,-1.0)';
    'G3_RXN8||SATA30_RXN':
      PIN_NUMBER='(0,0,0,0,0,0,0,0,0,0,0,0,0,AN29,0,0,0,0,0,0,0,0,0,0,0,0,0,0,0,0,0,0,0,0,0,0,0,0,0,0)';
      INPUT_LOAD='(-0.01,0.01)';
    'G3_RXP7||SATA27_RXP':
      PIN_NUMBER='(0,0,0,0,0,0,0,0,0,0,0,0,0,AJ30,0,0,0,0,0,0,0,0,0,0,0,0,0,0,0,0,0,0,0,0,0,0,0,0,0,0)';
      INPUT_LOAD='(-0.01,0.01)';
    'G3_TXP4||SATA24_TXP':
      PIN_NUMBER='(0,0,0,0,0,0,0,0,0,0,0,0,0,R26,0,0,0,0,0,0,0,0,0,0,0,0,0,0,0,0,0,0,0,0,0,0,0,0,0,0)';
      OUTPUT_LOAD='(1.0,-1.0)';
    'G3_TXP1||SATA21_TXP':
      PIN_NUMBER='(0,0,0,0,0,0,0,0,0,0,0,0,0,R23,0,0,0,0,0,0,0,0,0,0,0,0,0,0,0,0,0,0,0,0,0,0,0,0,0,0)';
      OUTPUT_LOAD='(1.0,-1.0)';
    'G3_RXN14||SATA36_RXN':
      PIN_NUMBER='(0,0,0,0,0,0,0,0,0,0,0,0,0,AM35,0,0,0,0,0,0,0,0,0,0,0,0,0,0,0,0,0,0,0,0,0,0,0,0,0,0)';
      INPUT_LOAD='(-0.01,0.01)';
    'G3_RXN11||SATA33_RXN':
      PIN_NUMBER='(0,0,0,0,0,0,0,0,0,0,0,0,0,AN32,0,0,0,0,0,0,0,0,0,0,0,0,0,0,0,0,0,0,0,0,0,0,0,0,0,0)';
      INPUT_LOAD='(-0.01,0.01)';
    'G3_TXN8||SATA30_TXN':
      PIN_NUMBER='(0,0,0,0,0,0,0,0,0,0,0,0,0,N30,0,0,0,0,0,0,0,0,0,0,0,0,0,0,0,0,0,0,0,0,0,0,0,0,0,0)';
      OUTPUT_LOAD='(1.0,-1.0)';
    'G3_TXP7||SATA27_TXP':
      PIN_NUMBER='(0,0,0,0,0,0,0,0,0,0,0,0,0,R29,0,0,0,0,0,0,0,0,0,0,0,0,0,0,0,0,0,0,0,0,0,0,0,0,0,0)';
      OUTPUT_LOAD='(1.0,-1.0)';
    'G3_RXP9||SATA31_RXP':
      PIN_NUMBER='(0,0,0,0,0,0,0,0,0,0,0,0,0,AL33,0,0,0,0,0,0,0,0,0,0,0,0,0,0,0,0,0,0,0,0,0,0,0,0,0,0)';
      INPUT_LOAD='(-0.01,0.01)';
    'G3_TXP12||SATA34_TXP':
      PIN_NUMBER='(0,0,0,0,0,0,0,0,0,0,0,0,0,U32,0,0,0,0,0,0,0,0,0,0,0,0,0,0,0,0,0,0,0,0,0,0,0,0,0,0)';
      OUTPUT_LOAD='(1.0,-1.0)';
    'G3_RXN7||SATA27_RXN':
      PIN_NUMBER='(0,0,0,0,0,0,0,0,0,0,0,0,0,AJ29,0,0,0,0,0,0,0,0,0,0,0,0,0,0,0,0,0,0,0,0,0,0,0,0,0,0)';
      INPUT_LOAD='(-0.01,0.01)';
    'G3_RXN4||SATA24_RXN':
      PIN_NUMBER='(0,0,0,0,0,0,0,0,0,0,0,0,0,AJ26,0,0,0,0,0,0,0,0,0,0,0,0,0,0,0,0,0,0,0,0,0,0,0,0,0,0)';
      INPUT_LOAD='(-0.01,0.01)';
    'G3_RXN1||SATA21_RXN':
      PIN_NUMBER='(0,0,0,0,0,0,0,0,0,0,0,0,0,AJ23,0,0,0,0,0,0,0,0,0,0,0,0,0,0,0,0,0,0,0,0,0,0,0,0,0,0)';
      INPUT_LOAD='(-0.01,0.01)';
    'G3_TXP15||SATA37_TXP':
      PIN_NUMBER='(0,0,0,0,0,0,0,0,0,0,0,0,0,V35,0,0,0,0,0,0,0,0,0,0,0,0,0,0,0,0,0,0,0,0,0,0,0,0,0,0)';
      OUTPUT_LOAD='(1.0,-1.0)';
    'G3_TXP9||SATA31_TXP':
      PIN_NUMBER='(0,0,0,0,0,0,0,0,0,0,0,0,0,U29,0,0,0,0,0,0,0,0,0,0,0,0,0,0,0,0,0,0,0,0,0,0,0,0,0,0)';
      OUTPUT_LOAD='(1.0,-1.0)';
    'G3_TXN1||SATA21_TXN':
      PIN_NUMBER='(0,0,0,0,0,0,0,0,0,0,0,0,0,R24,0,0,0,0,0,0,0,0,0,0,0,0,0,0,0,0,0,0,0,0,0,0,0,0,0,0)';
      OUTPUT_LOAD='(1.0,-1.0)';
    'G3_RXP11||SATA33_RXP':
      PIN_NUMBER='(0,0,0,0,0,0,0,0,0,0,0,0,0,AN33,0,0,0,0,0,0,0,0,0,0,0,0,0,0,0,0,0,0,0,0,0,0,0,0,0,0)';
      INPUT_LOAD='(-0.01,0.01)';
    'G3_TXN13||SATA35_TXN':
      PIN_NUMBER='(0,0,0,0,0,0,0,0,0,0,0,0,0,P36,0,0,0,0,0,0,0,0,0,0,0,0,0,0,0,0,0,0,0,0,0,0,0,0,0,0)';
      OUTPUT_LOAD='(1.0,-1.0)';
    'G3_TXN10||SATA32_TXN':
      PIN_NUMBER='(0,0,0,0,0,0,0,0,0,0,0,0,0,R33,0,0,0,0,0,0,0,0,0,0,0,0,0,0,0,0,0,0,0,0,0,0,0,0,0,0)';
      OUTPUT_LOAD='(1.0,-1.0)';
    'G3_TXN7||SATA27_TXN':
      PIN_NUMBER='(0,0,0,0,0,0,0,0,0,0,0,0,0,R30,0,0,0,0,0,0,0,0,0,0,0,0,0,0,0,0,0,0,0,0,0,0,0,0,0,0)';
      OUTPUT_LOAD='(1.0,-1.0)';
    'G3_TXN4||SATA24_TXN':
      PIN_NUMBER='(0,0,0,0,0,0,0,0,0,0,0,0,0,R27,0,0,0,0,0,0,0,0,0,0,0,0,0,0,0,0,0,0,0,0,0,0,0,0,0,0)';
      OUTPUT_LOAD='(1.0,-1.0)';
    'G3_RXP14||SATA36_RXP':
      PIN_NUMBER='(0,0,0,0,0,0,0,0,0,0,0,0,0,AM36,0,0,0,0,0,0,0,0,0,0,0,0,0,0,0,0,0,0,0,0,0,0,0,0,0,0)';
      INPUT_LOAD='(-0.01,0.01)';
    'G3_RXP5||SATA25_RXP':
      PIN_NUMBER='(0,0,0,0,0,0,0,0,0,0,0,0,0,AN27,0,0,0,0,0,0,0,0,0,0,0,0,0,0,0,0,0,0,0,0,0,0,0,0,0,0)';
      INPUT_LOAD='(-0.01,0.01)';
    'G3_RXP2||SATA22_RXP':
      PIN_NUMBER='(0,0,0,0,0,0,0,0,0,0,0,0,0,AN24,0,0,0,0,0,0,0,0,0,0,0,0,0,0,0,0,0,0,0,0,0,0,0,0,0,0)';
      INPUT_LOAD='(-0.01,0.01)';
    'G3_TXP2||SATA22_TXP':
      PIN_NUMBER='(0,0,0,0,0,0,0,0,0,0,0,0,0,W23,0,0,0,0,0,0,0,0,0,0,0,0,0,0,0,0,0,0,0,0,0,0,0,0,0,0)';
      OUTPUT_LOAD='(1.0,-1.0)';
    'G3_RXN9||SATA31_RXN':
      PIN_NUMBER='(0,0,0,0,0,0,0,0,0,0,0,0,0,AL32,0,0,0,0,0,0,0,0,0,0,0,0,0,0,0,0,0,0,0,0,0,0,0,0,0,0)';
      INPUT_LOAD='(-0.01,0.01)';
    'G3_TXP5||SATA25_TXP':
      PIN_NUMBER='(0,0,0,0,0,0,0,0,0,0,0,0,0,N26,0,0,0,0,0,0,0,0,0,0,0,0,0,0,0,0,0,0,0,0,0,0,0,0,0,0)';
      OUTPUT_LOAD='(1.0,-1.0)';
    'G3_RXN15||SATA37_RXN':
      PIN_NUMBER='(0,0,0,0,0,0,0,0,0,0,0,0,0,AP35,0,0,0,0,0,0,0,0,0,0,0,0,0,0,0,0,0,0,0,0,0,0,0,0,0,0)';
      INPUT_LOAD='(-0.01,0.01)';
    'G3_RXN12||SATA34_RXN':
      PIN_NUMBER='(0,0,0,0,0,0,0,0,0,0,0,0,0,AK35,0,0,0,0,0,0,0,0,0,0,0,0,0,0,0,0,0,0,0,0,0,0,0,0,0,0)';
      INPUT_LOAD='(-0.01,0.01)';
    'G3_TXN9||SATA31_TXN':
      PIN_NUMBER='(0,0,0,0,0,0,0,0,0,0,0,0,0,U30,0,0,0,0,0,0,0,0,0,0,0,0,0,0,0,0,0,0,0,0,0,0,0,0,0,0)';
      OUTPUT_LOAD='(1.0,-1.0)';
    'G3_RXN2||SATA22_RXN':
      PIN_NUMBER='(0,0,0,0,0,0,0,0,0,0,0,0,0,AN23,0,0,0,0,0,0,0,0,0,0,0,0,0,0,0,0,0,0,0,0,0,0,0,0,0,0)';
      INPUT_LOAD='(-0.01,0.01)';
    'P0_RXN0||SATA00_RXN':
      PIN_NUMBER='(0,0,0,0,0,0,0,0,0,0,0,0,0,0,BW53,0,0,0,0,0,0,0,0,0,0,0,0,0,0,0,0,0,0,0,0,0,0,0,0,0)';
      INPUT_LOAD='(-0.01,0.01)';
    'P0_RXN6||SATA06_RXN':
      PIN_NUMBER='(0,0,0,0,0,0,0,0,0,0,0,0,0,0,BW47,0,0,0,0,0,0,0,0,0,0,0,0,0,0,0,0,0,0,0,0,0,0,0,0,0)';
      INPUT_LOAD='(-0.01,0.01)';
    'P0_RXN3||SATA03_RXN':
      PIN_NUMBER='(0,0,0,0,0,0,0,0,0,0,0,0,0,0,BW50,0,0,0,0,0,0,0,0,0,0,0,0,0,0,0,0,0,0,0,0,0,0,0,0,0)';
      INPUT_LOAD='(-0.01,0.01)';
    'P0_TXN3||SATA03_TXN':
      PIN_NUMBER='(0,0,0,0,0,0,0,0,0,0,0,0,0,0,CN49,0,0,0,0,0,0,0,0,0,0,0,0,0,0,0,0,0,0,0,0,0,0,0,0,0)';
      OUTPUT_LOAD='(1.0,-1.0)';
    'P0_TXN0||SATA00_TXN':
      PIN_NUMBER='(0,0,0,0,0,0,0,0,0,0,0,0,0,0,CN52,0,0,0,0,0,0,0,0,0,0,0,0,0,0,0,0,0,0,0,0,0,0,0,0,0)';
      OUTPUT_LOAD='(1.0,-1.0)';
    'P0_RXP1||SATA01_RXP':
      PIN_NUMBER='(0,0,0,0,0,0,0,0,0,0,0,0,0,0,CA52,0,0,0,0,0,0,0,0,0,0,0,0,0,0,0,0,0,0,0,0,0,0,0,0,0)';
      INPUT_LOAD='(-0.01,0.01)';
    'P0_TXN6||SATA06_TXN':
      PIN_NUMBER='(0,0,0,0,0,0,0,0,0,0,0,0,0,0,CL49,0,0,0,0,0,0,0,0,0,0,0,0,0,0,0,0,0,0,0,0,0,0,0,0,0)';
      OUTPUT_LOAD='(1.0,-1.0)';
    'P0_RXP7||SATA07_RXP':
      PIN_NUMBER='(0,0,0,0,0,0,0,0,0,0,0,0,0,0,CA46,0,0,0,0,0,0,0,0,0,0,0,0,0,0,0,0,0,0,0,0,0,0,0,0,0)';
      INPUT_LOAD='(-0.01,0.01)';
    'P0_RXP4||SATA04_RXP':
      PIN_NUMBER='(0,0,0,0,0,0,0,0,0,0,0,0,0,0,CA49,0,0,0,0,0,0,0,0,0,0,0,0,0,0,0,0,0,0,0,0,0,0,0,0,0)';
      INPUT_LOAD='(-0.01,0.01)';
    'P0_TXP4||SATA04_TXP':
      PIN_NUMBER='(0,0,0,0,0,0,0,0,0,0,0,0,0,0,CR50,0,0,0,0,0,0,0,0,0,0,0,0,0,0,0,0,0,0,0,0,0,0,0,0,0)';
      OUTPUT_LOAD='(1.0,-1.0)';
    'P0_TXP1||SATA01_TXP':
      PIN_NUMBER='(0,0,0,0,0,0,0,0,0,0,0,0,0,0,CR53,0,0,0,0,0,0,0,0,0,0,0,0,0,0,0,0,0,0,0,0,0,0,0,0,0)';
      OUTPUT_LOAD='(1.0,-1.0)';
    'P0_TXP7||SATA07_TXP':
      PIN_NUMBER='(0,0,0,0,0,0,0,0,0,0,0,0,0,0,CR47,0,0,0,0,0,0,0,0,0,0,0,0,0,0,0,0,0,0,0,0,0,0,0,0,0)';
      OUTPUT_LOAD='(1.0,-1.0)';
    'P0_RXN4||SATA04_RXN':
      PIN_NUMBER='(0,0,0,0,0,0,0,0,0,0,0,0,0,0,CA50,0,0,0,0,0,0,0,0,0,0,0,0,0,0,0,0,0,0,0,0,0,0,0,0,0)';
      INPUT_LOAD='(-0.01,0.01)';
    'P0_RXN1||SATA01_RXN':
      PIN_NUMBER='(0,0,0,0,0,0,0,0,0,0,0,0,0,0,CA53,0,0,0,0,0,0,0,0,0,0,0,0,0,0,0,0,0,0,0,0,0,0,0,0,0)';
      INPUT_LOAD='(-0.01,0.01)';
    'P0_RXN7||SATA07_RXN':
      PIN_NUMBER='(0,0,0,0,0,0,0,0,0,0,0,0,0,0,CA47,0,0,0,0,0,0,0,0,0,0,0,0,0,0,0,0,0,0,0,0,0,0,0,0,0)';
      INPUT_LOAD='(-0.01,0.01)';
    'P0_TXN4||SATA04_TXN':
      PIN_NUMBER='(0,0,0,0,0,0,0,0,0,0,0,0,0,0,CR49,0,0,0,0,0,0,0,0,0,0,0,0,0,0,0,0,0,0,0,0,0,0,0,0,0)';
      OUTPUT_LOAD='(1.0,-1.0)';
    'P0_TXN7||SATA07_TXN':
      PIN_NUMBER='(0,0,0,0,0,0,0,0,0,0,0,0,0,0,CR46,0,0,0,0,0,0,0,0,0,0,0,0,0,0,0,0,0,0,0,0,0,0,0,0,0)';
      OUTPUT_LOAD='(1.0,-1.0)';
    'P0_TXN1||SATA01_TXN':
      PIN_NUMBER='(0,0,0,0,0,0,0,0,0,0,0,0,0,0,CR52,0,0,0,0,0,0,0,0,0,0,0,0,0,0,0,0,0,0,0,0,0,0,0,0,0)';
      OUTPUT_LOAD='(1.0,-1.0)';
    'P0_RXP2||SATA02_RXP':
      PIN_NUMBER='(0,0,0,0,0,0,0,0,0,0,0,0,0,0,BU52,0,0,0,0,0,0,0,0,0,0,0,0,0,0,0,0,0,0,0,0,0,0,0,0,0)';
      INPUT_LOAD='(-0.01,0.01)';
    'P0_RXP5||SATA05_RXP':
      PIN_NUMBER='(0,0,0,0,0,0,0,0,0,0,0,0,0,0,BU49,0,0,0,0,0,0,0,0,0,0,0,0,0,0,0,0,0,0,0,0,0,0,0,0,0)';
      INPUT_LOAD='(-0.01,0.01)';
    'P0_TXP5||SATA05_TXP':
      PIN_NUMBER='(0,0,0,0,0,0,0,0,0,0,0,0,0,0,CU50,0,0,0,0,0,0,0,0,0,0,0,0,0,0,0,0,0,0,0,0,0,0,0,0,0)';
      OUTPUT_LOAD='(1.0,-1.0)';
    'P0_TXP2||SATA02_TXP':
      PIN_NUMBER='(0,0,0,0,0,0,0,0,0,0,0,0,0,0,CL53,0,0,0,0,0,0,0,0,0,0,0,0,0,0,0,0,0,0,0,0,0,0,0,0,0)';
      OUTPUT_LOAD='(1.0,-1.0)';
    'P0_RXN5||SATA05_RXN':
      PIN_NUMBER='(0,0,0,0,0,0,0,0,0,0,0,0,0,0,BU50,0,0,0,0,0,0,0,0,0,0,0,0,0,0,0,0,0,0,0,0,0,0,0,0,0)';
      INPUT_LOAD='(-0.01,0.01)';
    'P0_RXN2||SATA02_RXN':
      PIN_NUMBER='(0,0,0,0,0,0,0,0,0,0,0,0,0,0,BU53,0,0,0,0,0,0,0,0,0,0,0,0,0,0,0,0,0,0,0,0,0,0,0,0,0)';
      INPUT_LOAD='(-0.01,0.01)';
    'P0_TXN2||SATA02_TXN':
      PIN_NUMBER='(0,0,0,0,0,0,0,0,0,0,0,0,0,0,CL52,0,0,0,0,0,0,0,0,0,0,0,0,0,0,0,0,0,0,0,0,0,0,0,0,0)';
      OUTPUT_LOAD='(1.0,-1.0)';
    'P0_RXP0||SATA00_RXP':
      PIN_NUMBER='(0,0,0,0,0,0,0,0,0,0,0,0,0,0,BW52,0,0,0,0,0,0,0,0,0,0,0,0,0,0,0,0,0,0,0,0,0,0,0,0,0)';
      INPUT_LOAD='(-0.01,0.01)';
    'P0_TXN5||SATA05_TXN':
      PIN_NUMBER='(0,0,0,0,0,0,0,0,0,0,0,0,0,0,CU49,0,0,0,0,0,0,0,0,0,0,0,0,0,0,0,0,0,0,0,0,0,0,0,0,0)';
      OUTPUT_LOAD='(1.0,-1.0)';
    'P0_RXP6||SATA06_RXP':
      PIN_NUMBER='(0,0,0,0,0,0,0,0,0,0,0,0,0,0,BW46,0,0,0,0,0,0,0,0,0,0,0,0,0,0,0,0,0,0,0,0,0,0,0,0,0)';
      INPUT_LOAD='(-0.01,0.01)';
    'P0_RXP3||SATA03_RXP':
      PIN_NUMBER='(0,0,0,0,0,0,0,0,0,0,0,0,0,0,BW49,0,0,0,0,0,0,0,0,0,0,0,0,0,0,0,0,0,0,0,0,0,0,0,0,0)';
      INPUT_LOAD='(-0.01,0.01)';
    'P0_TXP0||SATA00_TXP':
      PIN_NUMBER='(0,0,0,0,0,0,0,0,0,0,0,0,0,0,CN53,0,0,0,0,0,0,0,0,0,0,0,0,0,0,0,0,0,0,0,0,0,0,0,0,0)';
      OUTPUT_LOAD='(1.0,-1.0)';
    'P0_TXP6||SATA06_TXP':
      PIN_NUMBER='(0,0,0,0,0,0,0,0,0,0,0,0,0,0,CL50,0,0,0,0,0,0,0,0,0,0,0,0,0,0,0,0,0,0,0,0,0,0,0,0,0)';
      OUTPUT_LOAD='(1.0,-1.0)';
    'P0_TXP3||SATA03_TXP':
      PIN_NUMBER='(0,0,0,0,0,0,0,0,0,0,0,0,0,0,CN50,0,0,0,0,0,0,0,0,0,0,0,0,0,0,0,0,0,0,0,0,0,0,0,0,0)';
      OUTPUT_LOAD='(1.0,-1.0)';
    'P0_TXN13||SATA15_TXN':
      PIN_NUMBER='(0,0,0,0,0,0,0,0,0,0,0,0,0,0,CT40,0,0,0,0,0,0,0,0,0,0,0,0,0,0,0,0,0,0,0,0,0,0,0,0,0)';
      OUTPUT_LOAD='(1.0,-1.0)';
    'P0_TXN10||SATA12_TXN':
      PIN_NUMBER='(0,0,0,0,0,0,0,0,0,0,0,0,0,0,CR43,0,0,0,0,0,0,0,0,0,0,0,0,0,0,0,0,0,0,0,0,0,0,0,0,0)';
      OUTPUT_LOAD='(1.0,-1.0)';
    'P0_RXP14||SATA16_RXP':
      PIN_NUMBER='(0,0,0,0,0,0,0,0,0,0,0,0,0,0,BV40,0,0,0,0,0,0,0,0,0,0,0,0,0,0,0,0,0,0,0,0,0,0,0,0,0)';
      INPUT_LOAD='(-0.01,0.01)';
    'P0_RXP8||SATA10_RXP':
      PIN_NUMBER='(0,0,0,0,0,0,0,0,0,0,0,0,0,0,BU46,0,0,0,0,0,0,0,0,0,0,0,0,0,0,0,0,0,0,0,0,0,0,0,0,0)';
      INPUT_LOAD='(-0.01,0.01)';
    'P0_RXN12||SATA14_RXN':
      PIN_NUMBER='(0,0,0,0,0,0,0,0,0,0,0,0,0,0,BY41,0,0,0,0,0,0,0,0,0,0,0,0,0,0,0,0,0,0,0,0,0,0,0,0,0)';
      INPUT_LOAD='(-0.01,0.01)';
    'P0_TXP8||SATA10_TXP':
      PIN_NUMBER='(0,0,0,0,0,0,0,0,0,0,0,0,0,0,CU47,0,0,0,0,0,0,0,0,0,0,0,0,0,0,0,0,0,0,0,0,0,0,0,0,0)';
      OUTPUT_LOAD='(1.0,-1.0)';
    'P0_RXN15||SATA17_RXN':
      PIN_NUMBER='(0,0,0,0,0,0,0,0,0,0,0,0,0,0,BT41,0,0,0,0,0,0,0,0,0,0,0,0,0,0,0,0,0,0,0,0,0,0,0,0,0)';
      INPUT_LOAD='(-0.01,0.01)';
    'P0_TXP10||SATA12_TXP':
      PIN_NUMBER='(0,0,0,0,0,0,0,0,0,0,0,0,0,0,CR44,0,0,0,0,0,0,0,0,0,0,0,0,0,0,0,0,0,0,0,0,0,0,0,0,0)';
      OUTPUT_LOAD='(1.0,-1.0)';
    'P0_TXP13||SATA15_TXP':
      PIN_NUMBER='(0,0,0,0,0,0,0,0,0,0,0,0,0,0,CT41,0,0,0,0,0,0,0,0,0,0,0,0,0,0,0,0,0,0,0,0,0,0,0,0,0)';
      OUTPUT_LOAD='(1.0,-1.0)';
    'P0_RXN8||SATA10_RXN':
      PIN_NUMBER='(0,0,0,0,0,0,0,0,0,0,0,0,0,0,BU47,0,0,0,0,0,0,0,0,0,0,0,0,0,0,0,0,0,0,0,0,0,0,0,0,0)';
      INPUT_LOAD='(-0.01,0.01)';
    'P0_TXN11||SATA13_TXN':
      PIN_NUMBER='(0,0,0,0,0,0,0,0,0,0,0,0,0,0,CU43,0,0,0,0,0,0,0,0,0,0,0,0,0,0,0,0,0,0,0,0,0,0,0,0,0)';
      OUTPUT_LOAD='(1.0,-1.0)';
    'P0_TXN8||SATA10_TXN':
      PIN_NUMBER='(0,0,0,0,0,0,0,0,0,0,0,0,0,0,CU46,0,0,0,0,0,0,0,0,0,0,0,0,0,0,0,0,0,0,0,0,0,0,0,0,0)';
      OUTPUT_LOAD='(1.0,-1.0)';
    'P0_RXP15||SATA17_RXP':
      PIN_NUMBER='(0,0,0,0,0,0,0,0,0,0,0,0,0,0,BT40,0,0,0,0,0,0,0,0,0,0,0,0,0,0,0,0,0,0,0,0,0,0,0,0,0)';
      INPUT_LOAD='(-0.01,0.01)';
    'P0_RXP12||SATA14_RXP':
      PIN_NUMBER='(0,0,0,0,0,0,0,0,0,0,0,0,0,0,BY40,0,0,0,0,0,0,0,0,0,0,0,0,0,0,0,0,0,0,0,0,0,0,0,0,0)';
      INPUT_LOAD='(-0.01,0.01)';
    'P0_TXN14||SATA16_TXN':
      PIN_NUMBER='(0,0,0,0,0,0,0,0,0,0,0,0,0,0,CP40,0,0,0,0,0,0,0,0,0,0,0,0,0,0,0,0,0,0,0,0,0,0,0,0,0)';
      OUTPUT_LOAD='(1.0,-1.0)';
    'P0_RXP9||SATA11_RXP':
      PIN_NUMBER='(0,0,0,0,0,0,0,0,0,0,0,0,0,0,BW43,0,0,0,0,0,0,0,0,0,0,0,0,0,0,0,0,0,0,0,0,0,0,0,0,0)';
      INPUT_LOAD='(-0.01,0.01)';
    'P0_TXP9||SATA11_TXP':
      PIN_NUMBER='(0,0,0,0,0,0,0,0,0,0,0,0,0,0,CN47,0,0,0,0,0,0,0,0,0,0,0,0,0,0,0,0,0,0,0,0,0,0,0,0,0)';
      OUTPUT_LOAD='(1.0,-1.0)';
    'P0_RXN13||SATA15_RXN':
      PIN_NUMBER='(0,0,0,0,0,0,0,0,0,0,0,0,0,0,CB41,0,0,0,0,0,0,0,0,0,0,0,0,0,0,0,0,0,0,0,0,0,0,0,0,0)';
      INPUT_LOAD='(-0.01,0.01)';
    'P0_RXN10||SATA12_RXN':
      PIN_NUMBER='(0,0,0,0,0,0,0,0,0,0,0,0,0,0,CA44,0,0,0,0,0,0,0,0,0,0,0,0,0,0,0,0,0,0,0,0,0,0,0,0,0)';
      INPUT_LOAD='(-0.01,0.01)';
    'P0_TXP14||SATA16_TXP':
      PIN_NUMBER='(0,0,0,0,0,0,0,0,0,0,0,0,0,0,CP41,0,0,0,0,0,0,0,0,0,0,0,0,0,0,0,0,0,0,0,0,0,0,0,0,0)';
      OUTPUT_LOAD='(1.0,-1.0)';
    'P0_TXP11||SATA13_TXP':
      PIN_NUMBER='(0,0,0,0,0,0,0,0,0,0,0,0,0,0,CU44,0,0,0,0,0,0,0,0,0,0,0,0,0,0,0,0,0,0,0,0,0,0,0,0,0)';
      OUTPUT_LOAD='(1.0,-1.0)';
    'P0_RXN9||SATA11_RXN':
      PIN_NUMBER='(0,0,0,0,0,0,0,0,0,0,0,0,0,0,BW44,0,0,0,0,0,0,0,0,0,0,0,0,0,0,0,0,0,0,0,0,0,0,0,0,0)';
      INPUT_LOAD='(-0.01,0.01)';
    'P0_RXP10||SATA12_RXP':
      PIN_NUMBER='(0,0,0,0,0,0,0,0,0,0,0,0,0,0,CA43,0,0,0,0,0,0,0,0,0,0,0,0,0,0,0,0,0,0,0,0,0,0,0,0,0)';
      INPUT_LOAD='(-0.01,0.01)';
    'P0_TXN12||SATA14_TXN':
      PIN_NUMBER='(0,0,0,0,0,0,0,0,0,0,0,0,0,0,CN43,0,0,0,0,0,0,0,0,0,0,0,0,0,0,0,0,0,0,0,0,0,0,0,0,0)';
      OUTPUT_LOAD='(1.0,-1.0)';
    'P0_TXN9||SATA11_TXN':
      PIN_NUMBER='(0,0,0,0,0,0,0,0,0,0,0,0,0,0,CN46,0,0,0,0,0,0,0,0,0,0,0,0,0,0,0,0,0,0,0,0,0,0,0,0,0)';
      OUTPUT_LOAD='(1.0,-1.0)';
    'P0_RXP13||SATA15_RXP':
      PIN_NUMBER='(0,0,0,0,0,0,0,0,0,0,0,0,0,0,CB40,0,0,0,0,0,0,0,0,0,0,0,0,0,0,0,0,0,0,0,0,0,0,0,0,0)';
      INPUT_LOAD='(-0.01,0.01)';
    'P0_TXN15||SATA17_TXN':
      PIN_NUMBER='(0,0,0,0,0,0,0,0,0,0,0,0,0,0,CM40,0,0,0,0,0,0,0,0,0,0,0,0,0,0,0,0,0,0,0,0,0,0,0,0,0)';
      OUTPUT_LOAD='(1.0,-1.0)';
    'P0_RXN14||SATA16_RXN':
      PIN_NUMBER='(0,0,0,0,0,0,0,0,0,0,0,0,0,0,BV41,0,0,0,0,0,0,0,0,0,0,0,0,0,0,0,0,0,0,0,0,0,0,0,0,0)';
      INPUT_LOAD='(-0.01,0.01)';
    'P0_RXN11||SATA13_RXN':
      PIN_NUMBER='(0,0,0,0,0,0,0,0,0,0,0,0,0,0,BU44,0,0,0,0,0,0,0,0,0,0,0,0,0,0,0,0,0,0,0,0,0,0,0,0,0)';
      INPUT_LOAD='(-0.01,0.01)';
    'P0_TXP15||SATA17_TXP':
      PIN_NUMBER='(0,0,0,0,0,0,0,0,0,0,0,0,0,0,CM41,0,0,0,0,0,0,0,0,0,0,0,0,0,0,0,0,0,0,0,0,0,0,0,0,0)';
      OUTPUT_LOAD='(1.0,-1.0)';
    'P0_TXP12||SATA14_TXP':
      PIN_NUMBER='(0,0,0,0,0,0,0,0,0,0,0,0,0,0,CN44,0,0,0,0,0,0,0,0,0,0,0,0,0,0,0,0,0,0,0,0,0,0,0,0,0)';
      OUTPUT_LOAD='(1.0,-1.0)';
    'P0_RXP11||SATA13_RXP':
      PIN_NUMBER='(0,0,0,0,0,0,0,0,0,0,0,0,0,0,BU43,0,0,0,0,0,0,0,0,0,0,0,0,0,0,0,0,0,0,0,0,0,0,0,0,0)';
      INPUT_LOAD='(-0.01,0.01)';
    'P1_RXP8':
      PIN_NUMBER='(0,0,0,0,0,0,0,0,0,0,0,0,0,0,0,CC46,0,0,0,0,0,0,0,0,0,0,0,0,0,0,0,0,0,0,0,0,0,0,0,0)';
      INPUT_LOAD='(-0.01,0.01)';
    'P1_RXN8':
      PIN_NUMBER='(0,0,0,0,0,0,0,0,0,0,0,0,0,0,0,CC47,0,0,0,0,0,0,0,0,0,0,0,0,0,0,0,0,0,0,0,0,0,0,0,0)';
      INPUT_LOAD='(-0.01,0.01)';
    'P1_RXP9':
      PIN_NUMBER='(0,0,0,0,0,0,0,0,0,0,0,0,0,0,0,CE43,0,0,0,0,0,0,0,0,0,0,0,0,0,0,0,0,0,0,0,0,0,0,0,0)';
      INPUT_LOAD='(-0.01,0.01)';
    'P1_RXN9':
      PIN_NUMBER='(0,0,0,0,0,0,0,0,0,0,0,0,0,0,0,CE44,0,0,0,0,0,0,0,0,0,0,0,0,0,0,0,0,0,0,0,0,0,0,0,0)';
      INPUT_LOAD='(-0.01,0.01)';
    'P1_RXP10':
      PIN_NUMBER='(0,0,0,0,0,0,0,0,0,0,0,0,0,0,0,CG43,0,0,0,0,0,0,0,0,0,0,0,0,0,0,0,0,0,0,0,0,0,0,0,0)';
      INPUT_LOAD='(-0.01,0.01)';
    'P1_RXN10':
      PIN_NUMBER='(0,0,0,0,0,0,0,0,0,0,0,0,0,0,0,CG44,0,0,0,0,0,0,0,0,0,0,0,0,0,0,0,0,0,0,0,0,0,0,0,0)';
      INPUT_LOAD='(-0.01,0.01)';
    'P1_RXP11':
      PIN_NUMBER='(0,0,0,0,0,0,0,0,0,0,0,0,0,0,0,CJ43,0,0,0,0,0,0,0,0,0,0,0,0,0,0,0,0,0,0,0,0,0,0,0,0)';
      INPUT_LOAD='(-0.01,0.01)';
    'P1_RXN11':
      PIN_NUMBER='(0,0,0,0,0,0,0,0,0,0,0,0,0,0,0,CJ44,0,0,0,0,0,0,0,0,0,0,0,0,0,0,0,0,0,0,0,0,0,0,0,0)';
      INPUT_LOAD='(-0.01,0.01)';
    'P1_RXP12':
      PIN_NUMBER='(0,0,0,0,0,0,0,0,0,0,0,0,0,0,0,CC43,0,0,0,0,0,0,0,0,0,0,0,0,0,0,0,0,0,0,0,0,0,0,0,0)';
      INPUT_LOAD='(-0.01,0.01)';
    'P1_RXN12':
      PIN_NUMBER='(0,0,0,0,0,0,0,0,0,0,0,0,0,0,0,CC44,0,0,0,0,0,0,0,0,0,0,0,0,0,0,0,0,0,0,0,0,0,0,0,0)';
      INPUT_LOAD='(-0.01,0.01)';
    'P1_RXP13':
      PIN_NUMBER='(0,0,0,0,0,0,0,0,0,0,0,0,0,0,0,CH40,0,0,0,0,0,0,0,0,0,0,0,0,0,0,0,0,0,0,0,0,0,0,0,0)';
      INPUT_LOAD='(-0.01,0.01)';
    'P1_RXN13':
      PIN_NUMBER='(0,0,0,0,0,0,0,0,0,0,0,0,0,0,0,CH41,0,0,0,0,0,0,0,0,0,0,0,0,0,0,0,0,0,0,0,0,0,0,0,0)';
      INPUT_LOAD='(-0.01,0.01)';
    'P1_RXP14':
      PIN_NUMBER='(0,0,0,0,0,0,0,0,0,0,0,0,0,0,0,CF40,0,0,0,0,0,0,0,0,0,0,0,0,0,0,0,0,0,0,0,0,0,0,0,0)';
      INPUT_LOAD='(-0.01,0.01)';
    'P1_RXN14':
      PIN_NUMBER='(0,0,0,0,0,0,0,0,0,0,0,0,0,0,0,CF41,0,0,0,0,0,0,0,0,0,0,0,0,0,0,0,0,0,0,0,0,0,0,0,0)';
      INPUT_LOAD='(-0.01,0.01)';
    'P1_RXP15':
      PIN_NUMBER='(0,0,0,0,0,0,0,0,0,0,0,0,0,0,0,CD40,0,0,0,0,0,0,0,0,0,0,0,0,0,0,0,0,0,0,0,0,0,0,0,0)';
      INPUT_LOAD='(-0.01,0.01)';
    'P1_RXN15':
      PIN_NUMBER='(0,0,0,0,0,0,0,0,0,0,0,0,0,0,0,CD41,0,0,0,0,0,0,0,0,0,0,0,0,0,0,0,0,0,0,0,0,0,0,0,0)';
      INPUT_LOAD='(-0.01,0.01)';
    'P1_TXP8':
      PIN_NUMBER='(0,0,0,0,0,0,0,0,0,0,0,0,0,0,0,DC47,0,0,0,0,0,0,0,0,0,0,0,0,0,0,0,0,0,0,0,0,0,0,0,0)';
      OUTPUT_LOAD='(1.0,-1.0)';
    'P1_TXN8':
      PIN_NUMBER='(0,0,0,0,0,0,0,0,0,0,0,0,0,0,0,DC46,0,0,0,0,0,0,0,0,0,0,0,0,0,0,0,0,0,0,0,0,0,0,0,0)';
      OUTPUT_LOAD='(1.0,-1.0)';
    'P1_TXP9':
      PIN_NUMBER='(0,0,0,0,0,0,0,0,0,0,0,0,0,0,0,CW47,0,0,0,0,0,0,0,0,0,0,0,0,0,0,0,0,0,0,0,0,0,0,0,0)';
      OUTPUT_LOAD='(1.0,-1.0)';
    'P1_TXN9':
      PIN_NUMBER='(0,0,0,0,0,0,0,0,0,0,0,0,0,0,0,CW46,0,0,0,0,0,0,0,0,0,0,0,0,0,0,0,0,0,0,0,0,0,0,0,0)';
      OUTPUT_LOAD='(1.0,-1.0)';
    'P1_TXP10':
      PIN_NUMBER='(0,0,0,0,0,0,0,0,0,0,0,0,0,0,0,DA44,0,0,0,0,0,0,0,0,0,0,0,0,0,0,0,0,0,0,0,0,0,0,0,0)';
      OUTPUT_LOAD='(1.0,-1.0)';
    'P1_TXN10':
      PIN_NUMBER='(0,0,0,0,0,0,0,0,0,0,0,0,0,0,0,DA43,0,0,0,0,0,0,0,0,0,0,0,0,0,0,0,0,0,0,0,0,0,0,0,0)';
      OUTPUT_LOAD='(1.0,-1.0)';
    'P1_TXP11':
      PIN_NUMBER='(0,0,0,0,0,0,0,0,0,0,0,0,0,0,0,DC44,0,0,0,0,0,0,0,0,0,0,0,0,0,0,0,0,0,0,0,0,0,0,0,0)';
      OUTPUT_LOAD='(1.0,-1.0)';
    'P1_TXN11':
      PIN_NUMBER='(0,0,0,0,0,0,0,0,0,0,0,0,0,0,0,DC43,0,0,0,0,0,0,0,0,0,0,0,0,0,0,0,0,0,0,0,0,0,0,0,0)';
      OUTPUT_LOAD='(1.0,-1.0)';
    'P1_TXP12':
      PIN_NUMBER='(0,0,0,0,0,0,0,0,0,0,0,0,0,0,0,CW44,0,0,0,0,0,0,0,0,0,0,0,0,0,0,0,0,0,0,0,0,0,0,0,0)';
      OUTPUT_LOAD='(1.0,-1.0)';
    'P1_TXN12':
      PIN_NUMBER='(0,0,0,0,0,0,0,0,0,0,0,0,0,0,0,CW43,0,0,0,0,0,0,0,0,0,0,0,0,0,0,0,0,0,0,0,0,0,0,0,0)';
      OUTPUT_LOAD='(1.0,-1.0)';
    'P1_TXP13':
      PIN_NUMBER='(0,0,0,0,0,0,0,0,0,0,0,0,0,0,0,DB41,0,0,0,0,0,0,0,0,0,0,0,0,0,0,0,0,0,0,0,0,0,0,0,0)';
      OUTPUT_LOAD='(1.0,-1.0)';
    'P1_TXN13':
      PIN_NUMBER='(0,0,0,0,0,0,0,0,0,0,0,0,0,0,0,DB40,0,0,0,0,0,0,0,0,0,0,0,0,0,0,0,0,0,0,0,0,0,0,0,0)';
      OUTPUT_LOAD='(1.0,-1.0)';
    'P1_TXP14':
      PIN_NUMBER='(0,0,0,0,0,0,0,0,0,0,0,0,0,0,0,CY41,0,0,0,0,0,0,0,0,0,0,0,0,0,0,0,0,0,0,0,0,0,0,0,0)';
      OUTPUT_LOAD='(1.0,-1.0)';
    'P1_TXN14':
      PIN_NUMBER='(0,0,0,0,0,0,0,0,0,0,0,0,0,0,0,CY40,0,0,0,0,0,0,0,0,0,0,0,0,0,0,0,0,0,0,0,0,0,0,0,0)';
      OUTPUT_LOAD='(1.0,-1.0)';
    'P1_TXP15':
      PIN_NUMBER='(0,0,0,0,0,0,0,0,0,0,0,0,0,0,0,CV41,0,0,0,0,0,0,0,0,0,0,0,0,0,0,0,0,0,0,0,0,0,0,0,0)';
      OUTPUT_LOAD='(1.0,-1.0)';
    'P1_TXN15':
      PIN_NUMBER='(0,0,0,0,0,0,0,0,0,0,0,0,0,0,0,CV40,0,0,0,0,0,0,0,0,0,0,0,0,0,0,0,0,0,0,0,0,0,0,0,0)';
      OUTPUT_LOAD='(1.0,-1.0)';
    'P1_RXN7':
      PIN_NUMBER='(0,0,0,0,0,0,0,0,0,0,0,0,0,0,0,CG47,0,0,0,0,0,0,0,0,0,0,0,0,0,0,0,0,0,0,0,0,0,0,0,0)';
      INPUT_LOAD='(-0.01,0.01)';
    'P1_TXP0':
      PIN_NUMBER='(0,0,0,0,0,0,0,0,0,0,0,0,0,0,0,CU53,0,0,0,0,0,0,0,0,0,0,0,0,0,0,0,0,0,0,0,0,0,0,0,0)';
      OUTPUT_LOAD='(1.0,-1.0)';
    'P1_TXP1':
      PIN_NUMBER='(0,0,0,0,0,0,0,0,0,0,0,0,0,0,0,DA53,0,0,0,0,0,0,0,0,0,0,0,0,0,0,0,0,0,0,0,0,0,0,0,0)';
      OUTPUT_LOAD='(1.0,-1.0)';
    'P1_TXP2':
      PIN_NUMBER='(0,0,0,0,0,0,0,0,0,0,0,0,0,0,0,DC53,0,0,0,0,0,0,0,0,0,0,0,0,0,0,0,0,0,0,0,0,0,0,0,0)';
      OUTPUT_LOAD='(1.0,-1.0)';
    'P1_TXN0':
      PIN_NUMBER='(0,0,0,0,0,0,0,0,0,0,0,0,0,0,0,CU52,0,0,0,0,0,0,0,0,0,0,0,0,0,0,0,0,0,0,0,0,0,0,0,0)';
      OUTPUT_LOAD='(1.0,-1.0)';
    'P1_RXP0':
      PIN_NUMBER='(0,0,0,0,0,0,0,0,0,0,0,0,0,0,0,CE52,0,0,0,0,0,0,0,0,0,0,0,0,0,0,0,0,0,0,0,0,0,0,0,0)';
      INPUT_LOAD='(-0.01,0.01)';
    'P1_TXP3':
      PIN_NUMBER='(0,0,0,0,0,0,0,0,0,0,0,0,0,0,0,CW53,0,0,0,0,0,0,0,0,0,0,0,0,0,0,0,0,0,0,0,0,0,0,0,0)';
      OUTPUT_LOAD='(1.0,-1.0)';
    'P1_TXN1':
      PIN_NUMBER='(0,0,0,0,0,0,0,0,0,0,0,0,0,0,0,DA52,0,0,0,0,0,0,0,0,0,0,0,0,0,0,0,0,0,0,0,0,0,0,0,0)';
      OUTPUT_LOAD='(1.0,-1.0)';
    'P1_RXP1':
      PIN_NUMBER='(0,0,0,0,0,0,0,0,0,0,0,0,0,0,0,CG52,0,0,0,0,0,0,0,0,0,0,0,0,0,0,0,0,0,0,0,0,0,0,0,0)';
      INPUT_LOAD='(-0.01,0.01)';
    'P1_TXP4':
      PIN_NUMBER='(0,0,0,0,0,0,0,0,0,0,0,0,0,0,0,DA50,0,0,0,0,0,0,0,0,0,0,0,0,0,0,0,0,0,0,0,0,0,0,0,0)';
      OUTPUT_LOAD='(1.0,-1.0)';
    'P1_TXN2':
      PIN_NUMBER='(0,0,0,0,0,0,0,0,0,0,0,0,0,0,0,DC52,0,0,0,0,0,0,0,0,0,0,0,0,0,0,0,0,0,0,0,0,0,0,0,0)';
      OUTPUT_LOAD='(1.0,-1.0)';
    'P1_RXP2':
      PIN_NUMBER='(0,0,0,0,0,0,0,0,0,0,0,0,0,0,0,CC52,0,0,0,0,0,0,0,0,0,0,0,0,0,0,0,0,0,0,0,0,0,0,0,0)';
      INPUT_LOAD='(-0.01,0.01)';
    'P1_RXN0':
      PIN_NUMBER='(0,0,0,0,0,0,0,0,0,0,0,0,0,0,0,CE53,0,0,0,0,0,0,0,0,0,0,0,0,0,0,0,0,0,0,0,0,0,0,0,0)';
      INPUT_LOAD='(-0.01,0.01)';
    'P1_TXP5':
      PIN_NUMBER='(0,0,0,0,0,0,0,0,0,0,0,0,0,0,0,DC50,0,0,0,0,0,0,0,0,0,0,0,0,0,0,0,0,0,0,0,0,0,0,0,0)';
      OUTPUT_LOAD='(1.0,-1.0)';
    'P1_TXN3':
      PIN_NUMBER='(0,0,0,0,0,0,0,0,0,0,0,0,0,0,0,CW52,0,0,0,0,0,0,0,0,0,0,0,0,0,0,0,0,0,0,0,0,0,0,0,0)';
      OUTPUT_LOAD='(1.0,-1.0)';
    'P1_RXP3':
      PIN_NUMBER='(0,0,0,0,0,0,0,0,0,0,0,0,0,0,0,CE49,0,0,0,0,0,0,0,0,0,0,0,0,0,0,0,0,0,0,0,0,0,0,0,0)';
      INPUT_LOAD='(-0.01,0.01)';
    'P1_RXN1':
      PIN_NUMBER='(0,0,0,0,0,0,0,0,0,0,0,0,0,0,0,CG53,0,0,0,0,0,0,0,0,0,0,0,0,0,0,0,0,0,0,0,0,0,0,0,0)';
      INPUT_LOAD='(-0.01,0.01)';
    'P1_TXP6':
      PIN_NUMBER='(0,0,0,0,0,0,0,0,0,0,0,0,0,0,0,CW50,0,0,0,0,0,0,0,0,0,0,0,0,0,0,0,0,0,0,0,0,0,0,0,0)';
      OUTPUT_LOAD='(1.0,-1.0)';
    'P1_TXN4':
      PIN_NUMBER='(0,0,0,0,0,0,0,0,0,0,0,0,0,0,0,DA49,0,0,0,0,0,0,0,0,0,0,0,0,0,0,0,0,0,0,0,0,0,0,0,0)';
      OUTPUT_LOAD='(1.0,-1.0)';
    'P1_RXP4':
      PIN_NUMBER='(0,0,0,0,0,0,0,0,0,0,0,0,0,0,0,CG49,0,0,0,0,0,0,0,0,0,0,0,0,0,0,0,0,0,0,0,0,0,0,0,0)';
      INPUT_LOAD='(-0.01,0.01)';
    'P1_RXN2':
      PIN_NUMBER='(0,0,0,0,0,0,0,0,0,0,0,0,0,0,0,CC53,0,0,0,0,0,0,0,0,0,0,0,0,0,0,0,0,0,0,0,0,0,0,0,0)';
      INPUT_LOAD='(-0.01,0.01)';
    'P1_TXP7':
      PIN_NUMBER='(0,0,0,0,0,0,0,0,0,0,0,0,0,0,0,DA47,0,0,0,0,0,0,0,0,0,0,0,0,0,0,0,0,0,0,0,0,0,0,0,0)';
      OUTPUT_LOAD='(1.0,-1.0)';
    'P1_TXN5':
      PIN_NUMBER='(0,0,0,0,0,0,0,0,0,0,0,0,0,0,0,DC49,0,0,0,0,0,0,0,0,0,0,0,0,0,0,0,0,0,0,0,0,0,0,0,0)';
      OUTPUT_LOAD='(1.0,-1.0)';
    'P1_RXP5':
      PIN_NUMBER='(0,0,0,0,0,0,0,0,0,0,0,0,0,0,0,CC49,0,0,0,0,0,0,0,0,0,0,0,0,0,0,0,0,0,0,0,0,0,0,0,0)';
      INPUT_LOAD='(-0.01,0.01)';
    'P1_RXN3':
      PIN_NUMBER='(0,0,0,0,0,0,0,0,0,0,0,0,0,0,0,CE50,0,0,0,0,0,0,0,0,0,0,0,0,0,0,0,0,0,0,0,0,0,0,0,0)';
      INPUT_LOAD='(-0.01,0.01)';
    'P1_TXN6':
      PIN_NUMBER='(0,0,0,0,0,0,0,0,0,0,0,0,0,0,0,CW49,0,0,0,0,0,0,0,0,0,0,0,0,0,0,0,0,0,0,0,0,0,0,0,0)';
      OUTPUT_LOAD='(1.0,-1.0)';
    'P1_RXP6':
      PIN_NUMBER='(0,0,0,0,0,0,0,0,0,0,0,0,0,0,0,CE46,0,0,0,0,0,0,0,0,0,0,0,0,0,0,0,0,0,0,0,0,0,0,0,0)';
      INPUT_LOAD='(-0.01,0.01)';
    'P1_RXN4':
      PIN_NUMBER='(0,0,0,0,0,0,0,0,0,0,0,0,0,0,0,CG50,0,0,0,0,0,0,0,0,0,0,0,0,0,0,0,0,0,0,0,0,0,0,0,0)';
      INPUT_LOAD='(-0.01,0.01)';
    'P1_TXN7':
      PIN_NUMBER='(0,0,0,0,0,0,0,0,0,0,0,0,0,0,0,DA46,0,0,0,0,0,0,0,0,0,0,0,0,0,0,0,0,0,0,0,0,0,0,0,0)';
      OUTPUT_LOAD='(1.0,-1.0)';
    'P1_RXP7':
      PIN_NUMBER='(0,0,0,0,0,0,0,0,0,0,0,0,0,0,0,CG46,0,0,0,0,0,0,0,0,0,0,0,0,0,0,0,0,0,0,0,0,0,0,0,0)';
      INPUT_LOAD='(-0.01,0.01)';
    'P1_RXN5':
      PIN_NUMBER='(0,0,0,0,0,0,0,0,0,0,0,0,0,0,0,CC50,0,0,0,0,0,0,0,0,0,0,0,0,0,0,0,0,0,0,0,0,0,0,0,0)';
      INPUT_LOAD='(-0.01,0.01)';
    'P1_RXN6':
      PIN_NUMBER='(0,0,0,0,0,0,0,0,0,0,0,0,0,0,0,CE47,0,0,0,0,0,0,0,0,0,0,0,0,0,0,0,0,0,0,0,0,0,0,0,0)';
      INPUT_LOAD='(-0.01,0.01)';
    'P2_RXP8':
      PIN_NUMBER='(0,0,0,0,0,0,0,0,0,0,0,0,0,0,0,0,CR29,0,0,0,0,0,0,0,0,0,0,0,0,0,0,0,0,0,0,0,0,0,0,0)';
      INPUT_LOAD='(-0.01,0.01)';
    'P2_RXN8':
      PIN_NUMBER='(0,0,0,0,0,0,0,0,0,0,0,0,0,0,0,0,CR30,0,0,0,0,0,0,0,0,0,0,0,0,0,0,0,0,0,0,0,0,0,0,0)';
      INPUT_LOAD='(-0.01,0.01)';
    'P2_RXP9':
      PIN_NUMBER='(0,0,0,0,0,0,0,0,0,0,0,0,0,0,0,0,CL26,0,0,0,0,0,0,0,0,0,0,0,0,0,0,0,0,0,0,0,0,0,0,0)';
      INPUT_LOAD='(-0.01,0.01)';
    'P2_RXN9':
      PIN_NUMBER='(0,0,0,0,0,0,0,0,0,0,0,0,0,0,0,0,CL27,0,0,0,0,0,0,0,0,0,0,0,0,0,0,0,0,0,0,0,0,0,0,0)';
      INPUT_LOAD='(-0.01,0.01)';
    'P2_RXP10':
      PIN_NUMBER='(0,0,0,0,0,0,0,0,0,0,0,0,0,0,0,0,CU26,0,0,0,0,0,0,0,0,0,0,0,0,0,0,0,0,0,0,0,0,0,0,0)';
      INPUT_LOAD='(-0.01,0.01)';
    'P2_RXN10':
      PIN_NUMBER='(0,0,0,0,0,0,0,0,0,0,0,0,0,0,0,0,CU27,0,0,0,0,0,0,0,0,0,0,0,0,0,0,0,0,0,0,0,0,0,0,0)';
      INPUT_LOAD='(-0.01,0.01)';
    'P2_RXP11':
      PIN_NUMBER='(0,0,0,0,0,0,0,0,0,0,0,0,0,0,0,0,CR26,0,0,0,0,0,0,0,0,0,0,0,0,0,0,0,0,0,0,0,0,0,0,0)';
      INPUT_LOAD='(-0.01,0.01)';
    'P2_RXN11':
      PIN_NUMBER='(0,0,0,0,0,0,0,0,0,0,0,0,0,0,0,0,CR27,0,0,0,0,0,0,0,0,0,0,0,0,0,0,0,0,0,0,0,0,0,0,0)';
      INPUT_LOAD='(-0.01,0.01)';
    'P2_RXP12':
      PIN_NUMBER='(0,0,0,0,0,0,0,0,0,0,0,0,0,0,0,0,CN26,0,0,0,0,0,0,0,0,0,0,0,0,0,0,0,0,0,0,0,0,0,0,0)';
      INPUT_LOAD='(-0.01,0.01)';
    'P2_RXN12':
      PIN_NUMBER='(0,0,0,0,0,0,0,0,0,0,0,0,0,0,0,0,CN27,0,0,0,0,0,0,0,0,0,0,0,0,0,0,0,0,0,0,0,0,0,0,0)';
      INPUT_LOAD='(-0.01,0.01)';
    'P2_RXP13':
      PIN_NUMBER='(0,0,0,0,0,0,0,0,0,0,0,0,0,0,0,0,CL23,0,0,0,0,0,0,0,0,0,0,0,0,0,0,0,0,0,0,0,0,0,0,0)';
      INPUT_LOAD='(-0.01,0.01)';
    'P2_RXN13':
      PIN_NUMBER='(0,0,0,0,0,0,0,0,0,0,0,0,0,0,0,0,CL24,0,0,0,0,0,0,0,0,0,0,0,0,0,0,0,0,0,0,0,0,0,0,0)';
      INPUT_LOAD='(-0.01,0.01)';
    'P2_RXP14':
      PIN_NUMBER='(0,0,0,0,0,0,0,0,0,0,0,0,0,0,0,0,CR23,0,0,0,0,0,0,0,0,0,0,0,0,0,0,0,0,0,0,0,0,0,0,0)';
      INPUT_LOAD='(-0.01,0.01)';
    'P2_RXN14':
      PIN_NUMBER='(0,0,0,0,0,0,0,0,0,0,0,0,0,0,0,0,CR24,0,0,0,0,0,0,0,0,0,0,0,0,0,0,0,0,0,0,0,0,0,0,0)';
      INPUT_LOAD='(-0.01,0.01)';
    'P2_RXP15':
      PIN_NUMBER='(0,0,0,0,0,0,0,0,0,0,0,0,0,0,0,0,CN23,0,0,0,0,0,0,0,0,0,0,0,0,0,0,0,0,0,0,0,0,0,0,0)';
      INPUT_LOAD='(-0.01,0.01)';
    'P2_RXN15':
      PIN_NUMBER='(0,0,0,0,0,0,0,0,0,0,0,0,0,0,0,0,CN24,0,0,0,0,0,0,0,0,0,0,0,0,0,0,0,0,0,0,0,0,0,0,0)';
      INPUT_LOAD='(-0.01,0.01)';
    'P2_TXP8':
      PIN_NUMBER='(0,0,0,0,0,0,0,0,0,0,0,0,0,0,0,0,CA30,0,0,0,0,0,0,0,0,0,0,0,0,0,0,0,0,0,0,0,0,0,0,0)';
      OUTPUT_LOAD='(1.0,-1.0)';
    'P2_TXN8':
      PIN_NUMBER='(0,0,0,0,0,0,0,0,0,0,0,0,0,0,0,0,CA29,0,0,0,0,0,0,0,0,0,0,0,0,0,0,0,0,0,0,0,0,0,0,0)';
      OUTPUT_LOAD='(1.0,-1.0)';
    'P2_TXP9':
      PIN_NUMBER='(0,0,0,0,0,0,0,0,0,0,0,0,0,0,0,0,BW30,0,0,0,0,0,0,0,0,0,0,0,0,0,0,0,0,0,0,0,0,0,0,0)';
      OUTPUT_LOAD='(1.0,-1.0)';
    'P2_TXN9':
      PIN_NUMBER='(0,0,0,0,0,0,0,0,0,0,0,0,0,0,0,0,BW29,0,0,0,0,0,0,0,0,0,0,0,0,0,0,0,0,0,0,0,0,0,0,0)';
      OUTPUT_LOAD='(1.0,-1.0)';
    'P2_TXP10':
      PIN_NUMBER='(0,0,0,0,0,0,0,0,0,0,0,0,0,0,0,0,BU27,0,0,0,0,0,0,0,0,0,0,0,0,0,0,0,0,0,0,0,0,0,0,0)';
      OUTPUT_LOAD='(1.0,-1.0)';
    'P2_TXN10':
      PIN_NUMBER='(0,0,0,0,0,0,0,0,0,0,0,0,0,0,0,0,BU26,0,0,0,0,0,0,0,0,0,0,0,0,0,0,0,0,0,0,0,0,0,0,0)';
      OUTPUT_LOAD='(1.0,-1.0)';
    'P2_TXP11':
      PIN_NUMBER='(0,0,0,0,0,0,0,0,0,0,0,0,0,0,0,0,CA27,0,0,0,0,0,0,0,0,0,0,0,0,0,0,0,0,0,0,0,0,0,0,0)';
      OUTPUT_LOAD='(1.0,-1.0)';
    'P2_TXN11':
      PIN_NUMBER='(0,0,0,0,0,0,0,0,0,0,0,0,0,0,0,0,CA26,0,0,0,0,0,0,0,0,0,0,0,0,0,0,0,0,0,0,0,0,0,0,0)';
      OUTPUT_LOAD='(1.0,-1.0)';
    'P2_TXP12':
      PIN_NUMBER='(0,0,0,0,0,0,0,0,0,0,0,0,0,0,0,0,BW27,0,0,0,0,0,0,0,0,0,0,0,0,0,0,0,0,0,0,0,0,0,0,0)';
      OUTPUT_LOAD='(1.0,-1.0)';
    'P2_TXN12':
      PIN_NUMBER='(0,0,0,0,0,0,0,0,0,0,0,0,0,0,0,0,BW26,0,0,0,0,0,0,0,0,0,0,0,0,0,0,0,0,0,0,0,0,0,0,0)';
      OUTPUT_LOAD='(1.0,-1.0)';
    'P2_TXP13':
      PIN_NUMBER='(0,0,0,0,0,0,0,0,0,0,0,0,0,0,0,0,BU24,0,0,0,0,0,0,0,0,0,0,0,0,0,0,0,0,0,0,0,0,0,0,0)';
      OUTPUT_LOAD='(1.0,-1.0)';
    'P2_TXN13':
      PIN_NUMBER='(0,0,0,0,0,0,0,0,0,0,0,0,0,0,0,0,BU23,0,0,0,0,0,0,0,0,0,0,0,0,0,0,0,0,0,0,0,0,0,0,0)';
      OUTPUT_LOAD='(1.0,-1.0)';
    'P2_TXP14':
      PIN_NUMBER='(0,0,0,0,0,0,0,0,0,0,0,0,0,0,0,0,CA24,0,0,0,0,0,0,0,0,0,0,0,0,0,0,0,0,0,0,0,0,0,0,0)';
      OUTPUT_LOAD='(1.0,-1.0)';
    'P2_TXN14':
      PIN_NUMBER='(0,0,0,0,0,0,0,0,0,0,0,0,0,0,0,0,CA23,0,0,0,0,0,0,0,0,0,0,0,0,0,0,0,0,0,0,0,0,0,0,0)';
      OUTPUT_LOAD='(1.0,-1.0)';
    'P2_TXP15':
      PIN_NUMBER='(0,0,0,0,0,0,0,0,0,0,0,0,0,0,0,0,BW24,0,0,0,0,0,0,0,0,0,0,0,0,0,0,0,0,0,0,0,0,0,0,0)';
      OUTPUT_LOAD='(1.0,-1.0)';
    'P2_TXN15':
      PIN_NUMBER='(0,0,0,0,0,0,0,0,0,0,0,0,0,0,0,0,BW23,0,0,0,0,0,0,0,0,0,0,0,0,0,0,0,0,0,0,0,0,0,0,0)';
      OUTPUT_LOAD='(1.0,-1.0)';
    'P2_TXP0':
      PIN_NUMBER='(0,0,0,0,0,0,0,0,0,0,0,0,0,0,0,0,BT36,0,0,0,0,0,0,0,0,0,0,0,0,0,0,0,0,0,0,0,0,0,0,0)';
      OUTPUT_LOAD='(1.0,-1.0)';
    'P2_TXP1':
      PIN_NUMBER='(0,0,0,0,0,0,0,0,0,0,0,0,0,0,0,0,BV36,0,0,0,0,0,0,0,0,0,0,0,0,0,0,0,0,0,0,0,0,0,0,0)';
      OUTPUT_LOAD='(1.0,-1.0)';
    'P2_TXP2':
      PIN_NUMBER='(0,0,0,0,0,0,0,0,0,0,0,0,0,0,0,0,CB36,0,0,0,0,0,0,0,0,0,0,0,0,0,0,0,0,0,0,0,0,0,0,0)';
      OUTPUT_LOAD='(1.0,-1.0)';
    'P2_TXN0':
      PIN_NUMBER='(0,0,0,0,0,0,0,0,0,0,0,0,0,0,0,0,BT35,0,0,0,0,0,0,0,0,0,0,0,0,0,0,0,0,0,0,0,0,0,0,0)';
      OUTPUT_LOAD='(1.0,-1.0)';
    'P2_RXP0':
      PIN_NUMBER='(0,0,0,0,0,0,0,0,0,0,0,0,0,0,0,0,CM35,0,0,0,0,0,0,0,0,0,0,0,0,0,0,0,0,0,0,0,0,0,0,0)';
      INPUT_LOAD='(-0.01,0.01)';
    'P2_TXP3':
      PIN_NUMBER='(0,0,0,0,0,0,0,0,0,0,0,0,0,0,0,0,BY36,0,0,0,0,0,0,0,0,0,0,0,0,0,0,0,0,0,0,0,0,0,0,0)';
      OUTPUT_LOAD='(1.0,-1.0)';
    'P2_TXN1':
      PIN_NUMBER='(0,0,0,0,0,0,0,0,0,0,0,0,0,0,0,0,BV35,0,0,0,0,0,0,0,0,0,0,0,0,0,0,0,0,0,0,0,0,0,0,0)';
      OUTPUT_LOAD='(1.0,-1.0)';
    'P2_RXP1':
      PIN_NUMBER='(0,0,0,0,0,0,0,0,0,0,0,0,0,0,0,0,CP35,0,0,0,0,0,0,0,0,0,0,0,0,0,0,0,0,0,0,0,0,0,0,0)';
      INPUT_LOAD='(-0.01,0.01)';
    'P2_TXP4':
      PIN_NUMBER='(0,0,0,0,0,0,0,0,0,0,0,0,0,0,0,0,BU33,0,0,0,0,0,0,0,0,0,0,0,0,0,0,0,0,0,0,0,0,0,0,0)';
      OUTPUT_LOAD='(1.0,-1.0)';
    'P2_TXN2':
      PIN_NUMBER='(0,0,0,0,0,0,0,0,0,0,0,0,0,0,0,0,CB35,0,0,0,0,0,0,0,0,0,0,0,0,0,0,0,0,0,0,0,0,0,0,0)';
      OUTPUT_LOAD='(1.0,-1.0)';
    'P2_RXP2':
      PIN_NUMBER='(0,0,0,0,0,0,0,0,0,0,0,0,0,0,0,0,CT35,0,0,0,0,0,0,0,0,0,0,0,0,0,0,0,0,0,0,0,0,0,0,0)';
      INPUT_LOAD='(-0.01,0.01)';
    'P2_RXN0':
      PIN_NUMBER='(0,0,0,0,0,0,0,0,0,0,0,0,0,0,0,0,CM36,0,0,0,0,0,0,0,0,0,0,0,0,0,0,0,0,0,0,0,0,0,0,0)';
      INPUT_LOAD='(-0.01,0.01)';
    'P2_TXP5':
      PIN_NUMBER='(0,0,0,0,0,0,0,0,0,0,0,0,0,0,0,0,CA33,0,0,0,0,0,0,0,0,0,0,0,0,0,0,0,0,0,0,0,0,0,0,0)';
      OUTPUT_LOAD='(1.0,-1.0)';
    'P2_TXN3':
      PIN_NUMBER='(0,0,0,0,0,0,0,0,0,0,0,0,0,0,0,0,BY35,0,0,0,0,0,0,0,0,0,0,0,0,0,0,0,0,0,0,0,0,0,0,0)';
      OUTPUT_LOAD='(1.0,-1.0)';
    'P2_RXP3':
      PIN_NUMBER='(0,0,0,0,0,0,0,0,0,0,0,0,0,0,0,0,CN32,0,0,0,0,0,0,0,0,0,0,0,0,0,0,0,0,0,0,0,0,0,0,0)';
      INPUT_LOAD='(-0.01,0.01)';
    'P2_RXN1':
      PIN_NUMBER='(0,0,0,0,0,0,0,0,0,0,0,0,0,0,0,0,CP36,0,0,0,0,0,0,0,0,0,0,0,0,0,0,0,0,0,0,0,0,0,0,0)';
      INPUT_LOAD='(-0.01,0.01)';
    'P2_TXP6':
      PIN_NUMBER='(0,0,0,0,0,0,0,0,0,0,0,0,0,0,0,0,BW33,0,0,0,0,0,0,0,0,0,0,0,0,0,0,0,0,0,0,0,0,0,0,0)';
      OUTPUT_LOAD='(1.0,-1.0)';
    'P2_TXN4':
      PIN_NUMBER='(0,0,0,0,0,0,0,0,0,0,0,0,0,0,0,0,BU32,0,0,0,0,0,0,0,0,0,0,0,0,0,0,0,0,0,0,0,0,0,0,0)';
      OUTPUT_LOAD='(1.0,-1.0)';
    'P2_RXP4':
      PIN_NUMBER='(0,0,0,0,0,0,0,0,0,0,0,0,0,0,0,0,CU32,0,0,0,0,0,0,0,0,0,0,0,0,0,0,0,0,0,0,0,0,0,0,0)';
      INPUT_LOAD='(-0.01,0.01)';
    'P2_RXN2':
      PIN_NUMBER='(0,0,0,0,0,0,0,0,0,0,0,0,0,0,0,0,CT36,0,0,0,0,0,0,0,0,0,0,0,0,0,0,0,0,0,0,0,0,0,0,0)';
      INPUT_LOAD='(-0.01,0.01)';
    'P2_TXP7':
      PIN_NUMBER='(0,0,0,0,0,0,0,0,0,0,0,0,0,0,0,0,BU30,0,0,0,0,0,0,0,0,0,0,0,0,0,0,0,0,0,0,0,0,0,0,0)';
      OUTPUT_LOAD='(1.0,-1.0)';
    'P2_TXN5':
      PIN_NUMBER='(0,0,0,0,0,0,0,0,0,0,0,0,0,0,0,0,CA32,0,0,0,0,0,0,0,0,0,0,0,0,0,0,0,0,0,0,0,0,0,0,0)';
      OUTPUT_LOAD='(1.0,-1.0)';
    'P2_RXP5':
      PIN_NUMBER='(0,0,0,0,0,0,0,0,0,0,0,0,0,0,0,0,CR32,0,0,0,0,0,0,0,0,0,0,0,0,0,0,0,0,0,0,0,0,0,0,0)';
      INPUT_LOAD='(-0.01,0.01)';
    'P2_RXN3':
      PIN_NUMBER='(0,0,0,0,0,0,0,0,0,0,0,0,0,0,0,0,CN33,0,0,0,0,0,0,0,0,0,0,0,0,0,0,0,0,0,0,0,0,0,0,0)';
      INPUT_LOAD='(-0.01,0.01)';
    'P2_TXN6':
      PIN_NUMBER='(0,0,0,0,0,0,0,0,0,0,0,0,0,0,0,0,BW32,0,0,0,0,0,0,0,0,0,0,0,0,0,0,0,0,0,0,0,0,0,0,0)';
      OUTPUT_LOAD='(1.0,-1.0)';
    'P2_RXP6':
      PIN_NUMBER='(0,0,0,0,0,0,0,0,0,0,0,0,0,0,0,0,CN29,0,0,0,0,0,0,0,0,0,0,0,0,0,0,0,0,0,0,0,0,0,0,0)';
      INPUT_LOAD='(-0.01,0.01)';
    'P2_RXN4':
      PIN_NUMBER='(0,0,0,0,0,0,0,0,0,0,0,0,0,0,0,0,CU33,0,0,0,0,0,0,0,0,0,0,0,0,0,0,0,0,0,0,0,0,0,0,0)';
      INPUT_LOAD='(-0.01,0.01)';
    'P2_TXN7':
      PIN_NUMBER='(0,0,0,0,0,0,0,0,0,0,0,0,0,0,0,0,BU29,0,0,0,0,0,0,0,0,0,0,0,0,0,0,0,0,0,0,0,0,0,0,0)';
      OUTPUT_LOAD='(1.0,-1.0)';
    'P2_RXP7':
      PIN_NUMBER='(0,0,0,0,0,0,0,0,0,0,0,0,0,0,0,0,CU29,0,0,0,0,0,0,0,0,0,0,0,0,0,0,0,0,0,0,0,0,0,0,0)';
      INPUT_LOAD='(-0.01,0.01)';
    'P2_RXN5':
      PIN_NUMBER='(0,0,0,0,0,0,0,0,0,0,0,0,0,0,0,0,CR33,0,0,0,0,0,0,0,0,0,0,0,0,0,0,0,0,0,0,0,0,0,0,0)';
      INPUT_LOAD='(-0.01,0.01)';
    'P2_RXN6':
      PIN_NUMBER='(0,0,0,0,0,0,0,0,0,0,0,0,0,0,0,0,CN30,0,0,0,0,0,0,0,0,0,0,0,0,0,0,0,0,0,0,0,0,0,0,0)';
      INPUT_LOAD='(-0.01,0.01)';
    'P2_RXN7':
      PIN_NUMBER='(0,0,0,0,0,0,0,0,0,0,0,0,0,0,0,0,CU30,0,0,0,0,0,0,0,0,0,0,0,0,0,0,0,0,0,0,0,0,0,0,0)';
      INPUT_LOAD='(-0.01,0.01)';
    'P3_RXP0':
      PIN_NUMBER='(0,0,0,0,0,0,0,0,0,0,0,0,0,0,0,0,0,CV35,0,0,0,0,0,0,0,0,0,0,0,0,0,0,0,0,0,0,0,0,0,0)';
      INPUT_LOAD='(-0.01,0.01)';
    'P3_RXN0':
      PIN_NUMBER='(0,0,0,0,0,0,0,0,0,0,0,0,0,0,0,0,0,CV36,0,0,0,0,0,0,0,0,0,0,0,0,0,0,0,0,0,0,0,0,0,0)';
      INPUT_LOAD='(-0.01,0.01)';
    'P3_RXP1':
      PIN_NUMBER='(0,0,0,0,0,0,0,0,0,0,0,0,0,0,0,0,0,CY35,0,0,0,0,0,0,0,0,0,0,0,0,0,0,0,0,0,0,0,0,0,0)';
      INPUT_LOAD='(-0.01,0.01)';
    'P3_RXN1':
      PIN_NUMBER='(0,0,0,0,0,0,0,0,0,0,0,0,0,0,0,0,0,CY36,0,0,0,0,0,0,0,0,0,0,0,0,0,0,0,0,0,0,0,0,0,0)';
      INPUT_LOAD='(-0.01,0.01)';
    'P3_RXP2':
      PIN_NUMBER='(0,0,0,0,0,0,0,0,0,0,0,0,0,0,0,0,0,DB35,0,0,0,0,0,0,0,0,0,0,0,0,0,0,0,0,0,0,0,0,0,0)';
      INPUT_LOAD='(-0.01,0.01)';
    'P3_RXN2':
      PIN_NUMBER='(0,0,0,0,0,0,0,0,0,0,0,0,0,0,0,0,0,DB36,0,0,0,0,0,0,0,0,0,0,0,0,0,0,0,0,0,0,0,0,0,0)';
      INPUT_LOAD='(-0.01,0.01)';
    'P3_RXP3':
      PIN_NUMBER='(0,0,0,0,0,0,0,0,0,0,0,0,0,0,0,0,0,CW32,0,0,0,0,0,0,0,0,0,0,0,0,0,0,0,0,0,0,0,0,0,0)';
      INPUT_LOAD='(-0.01,0.01)';
    'P3_RXN3':
      PIN_NUMBER='(0,0,0,0,0,0,0,0,0,0,0,0,0,0,0,0,0,CW33,0,0,0,0,0,0,0,0,0,0,0,0,0,0,0,0,0,0,0,0,0,0)';
      INPUT_LOAD='(-0.01,0.01)';
    'P3_RXP4':
      PIN_NUMBER='(0,0,0,0,0,0,0,0,0,0,0,0,0,0,0,0,0,DC32,0,0,0,0,0,0,0,0,0,0,0,0,0,0,0,0,0,0,0,0,0,0)';
      INPUT_LOAD='(-0.01,0.01)';
    'P3_RXN4':
      PIN_NUMBER='(0,0,0,0,0,0,0,0,0,0,0,0,0,0,0,0,0,DC33,0,0,0,0,0,0,0,0,0,0,0,0,0,0,0,0,0,0,0,0,0,0)';
      INPUT_LOAD='(-0.01,0.01)';
    'P3_RXP5':
      PIN_NUMBER='(0,0,0,0,0,0,0,0,0,0,0,0,0,0,0,0,0,DA32,0,0,0,0,0,0,0,0,0,0,0,0,0,0,0,0,0,0,0,0,0,0)';
      INPUT_LOAD='(-0.01,0.01)';
    'P3_RXN5':
      PIN_NUMBER='(0,0,0,0,0,0,0,0,0,0,0,0,0,0,0,0,0,DA33,0,0,0,0,0,0,0,0,0,0,0,0,0,0,0,0,0,0,0,0,0,0)';
      INPUT_LOAD='(-0.01,0.01)';
    'P3_RXP6':
      PIN_NUMBER='(0,0,0,0,0,0,0,0,0,0,0,0,0,0,0,0,0,CW29,0,0,0,0,0,0,0,0,0,0,0,0,0,0,0,0,0,0,0,0,0,0)';
      INPUT_LOAD='(-0.01,0.01)';
    'P3_RXN6':
      PIN_NUMBER='(0,0,0,0,0,0,0,0,0,0,0,0,0,0,0,0,0,CW30,0,0,0,0,0,0,0,0,0,0,0,0,0,0,0,0,0,0,0,0,0,0)';
      INPUT_LOAD='(-0.01,0.01)';
    'P3_RXP7':
      PIN_NUMBER='(0,0,0,0,0,0,0,0,0,0,0,0,0,0,0,0,0,DC29,0,0,0,0,0,0,0,0,0,0,0,0,0,0,0,0,0,0,0,0,0,0)';
      INPUT_LOAD='(-0.01,0.01)';
    'P3_RXN7':
      PIN_NUMBER='(0,0,0,0,0,0,0,0,0,0,0,0,0,0,0,0,0,DC30,0,0,0,0,0,0,0,0,0,0,0,0,0,0,0,0,0,0,0,0,0,0)';
      INPUT_LOAD='(-0.01,0.01)';
    'P3_RXP8':
      PIN_NUMBER='(0,0,0,0,0,0,0,0,0,0,0,0,0,0,0,0,0,DA29,0,0,0,0,0,0,0,0,0,0,0,0,0,0,0,0,0,0,0,0,0,0)';
      INPUT_LOAD='(-0.01,0.01)';
    'P3_RXN8':
      PIN_NUMBER='(0,0,0,0,0,0,0,0,0,0,0,0,0,0,0,0,0,DA30,0,0,0,0,0,0,0,0,0,0,0,0,0,0,0,0,0,0,0,0,0,0)';
      INPUT_LOAD='(-0.01,0.01)';
    'P3_RXP9':
      PIN_NUMBER='(0,0,0,0,0,0,0,0,0,0,0,0,0,0,0,0,0,CW26,0,0,0,0,0,0,0,0,0,0,0,0,0,0,0,0,0,0,0,0,0,0)';
      INPUT_LOAD='(-0.01,0.01)';
    'P3_RXN9':
      PIN_NUMBER='(0,0,0,0,0,0,0,0,0,0,0,0,0,0,0,0,0,CW27,0,0,0,0,0,0,0,0,0,0,0,0,0,0,0,0,0,0,0,0,0,0)';
      INPUT_LOAD='(-0.01,0.01)';
    'P3_RXP10':
      PIN_NUMBER='(0,0,0,0,0,0,0,0,0,0,0,0,0,0,0,0,0,DC26,0,0,0,0,0,0,0,0,0,0,0,0,0,0,0,0,0,0,0,0,0,0)';
      INPUT_LOAD='(-0.01,0.01)';
    'P3_RXN10':
      PIN_NUMBER='(0,0,0,0,0,0,0,0,0,0,0,0,0,0,0,0,0,DC27,0,0,0,0,0,0,0,0,0,0,0,0,0,0,0,0,0,0,0,0,0,0)';
      INPUT_LOAD='(-0.01,0.01)';
    'P3_RXP11':
      PIN_NUMBER='(0,0,0,0,0,0,0,0,0,0,0,0,0,0,0,0,0,DA26,0,0,0,0,0,0,0,0,0,0,0,0,0,0,0,0,0,0,0,0,0,0)';
      INPUT_LOAD='(-0.01,0.01)';
    'P3_RXN11':
      PIN_NUMBER='(0,0,0,0,0,0,0,0,0,0,0,0,0,0,0,0,0,DA27,0,0,0,0,0,0,0,0,0,0,0,0,0,0,0,0,0,0,0,0,0,0)';
      INPUT_LOAD='(-0.01,0.01)';
    'P3_RXP12':
      PIN_NUMBER='(0,0,0,0,0,0,0,0,0,0,0,0,0,0,0,0,0,CW23,0,0,0,0,0,0,0,0,0,0,0,0,0,0,0,0,0,0,0,0,0,0)';
      INPUT_LOAD='(-0.01,0.01)';
    'P3_RXN12':
      PIN_NUMBER='(0,0,0,0,0,0,0,0,0,0,0,0,0,0,0,0,0,CW24,0,0,0,0,0,0,0,0,0,0,0,0,0,0,0,0,0,0,0,0,0,0)';
      INPUT_LOAD='(-0.01,0.01)';
    'P3_RXP13':
      PIN_NUMBER='(0,0,0,0,0,0,0,0,0,0,0,0,0,0,0,0,0,DC23,0,0,0,0,0,0,0,0,0,0,0,0,0,0,0,0,0,0,0,0,0,0)';
      INPUT_LOAD='(-0.01,0.01)';
    'P3_RXN13':
      PIN_NUMBER='(0,0,0,0,0,0,0,0,0,0,0,0,0,0,0,0,0,DC24,0,0,0,0,0,0,0,0,0,0,0,0,0,0,0,0,0,0,0,0,0,0)';
      INPUT_LOAD='(-0.01,0.01)';
    'P3_RXP14':
      PIN_NUMBER='(0,0,0,0,0,0,0,0,0,0,0,0,0,0,0,0,0,DA23,0,0,0,0,0,0,0,0,0,0,0,0,0,0,0,0,0,0,0,0,0,0)';
      INPUT_LOAD='(-0.01,0.01)';
    'P3_RXN14':
      PIN_NUMBER='(0,0,0,0,0,0,0,0,0,0,0,0,0,0,0,0,0,DA24,0,0,0,0,0,0,0,0,0,0,0,0,0,0,0,0,0,0,0,0,0,0)';
      INPUT_LOAD='(-0.01,0.01)';
    'P3_RXP15':
      PIN_NUMBER='(0,0,0,0,0,0,0,0,0,0,0,0,0,0,0,0,0,CU23,0,0,0,0,0,0,0,0,0,0,0,0,0,0,0,0,0,0,0,0,0,0)';
      INPUT_LOAD='(-0.01,0.01)';
    'P3_RXN15':
      PIN_NUMBER='(0,0,0,0,0,0,0,0,0,0,0,0,0,0,0,0,0,CU24,0,0,0,0,0,0,0,0,0,0,0,0,0,0,0,0,0,0,0,0,0,0)';
      INPUT_LOAD='(-0.01,0.01)';
    'P3_TXP0':
      PIN_NUMBER='(0,0,0,0,0,0,0,0,0,0,0,0,0,0,0,0,0,CD36,0,0,0,0,0,0,0,0,0,0,0,0,0,0,0,0,0,0,0,0,0,0)';
      OUTPUT_LOAD='(1.0,-1.0)';
    'P3_TXN0':
      PIN_NUMBER='(0,0,0,0,0,0,0,0,0,0,0,0,0,0,0,0,0,CD35,0,0,0,0,0,0,0,0,0,0,0,0,0,0,0,0,0,0,0,0,0,0)';
      OUTPUT_LOAD='(1.0,-1.0)';
    'P3_TXP1':
      PIN_NUMBER='(0,0,0,0,0,0,0,0,0,0,0,0,0,0,0,0,0,CF36,0,0,0,0,0,0,0,0,0,0,0,0,0,0,0,0,0,0,0,0,0,0)';
      OUTPUT_LOAD='(1.0,-1.0)';
    'P3_TXN1':
      PIN_NUMBER='(0,0,0,0,0,0,0,0,0,0,0,0,0,0,0,0,0,CF35,0,0,0,0,0,0,0,0,0,0,0,0,0,0,0,0,0,0,0,0,0,0)';
      OUTPUT_LOAD='(1.0,-1.0)';
    'P3_TXP2':
      PIN_NUMBER='(0,0,0,0,0,0,0,0,0,0,0,0,0,0,0,0,0,CH36,0,0,0,0,0,0,0,0,0,0,0,0,0,0,0,0,0,0,0,0,0,0)';
      OUTPUT_LOAD='(1.0,-1.0)';
    'P3_TXN2':
      PIN_NUMBER='(0,0,0,0,0,0,0,0,0,0,0,0,0,0,0,0,0,CH35,0,0,0,0,0,0,0,0,0,0,0,0,0,0,0,0,0,0,0,0,0,0)';
      OUTPUT_LOAD='(1.0,-1.0)';
    'P3_TXP3':
      PIN_NUMBER='(0,0,0,0,0,0,0,0,0,0,0,0,0,0,0,0,0,CC33,0,0,0,0,0,0,0,0,0,0,0,0,0,0,0,0,0,0,0,0,0,0)';
      OUTPUT_LOAD='(1.0,-1.0)';
    'P3_TXN3':
      PIN_NUMBER='(0,0,0,0,0,0,0,0,0,0,0,0,0,0,0,0,0,CC32,0,0,0,0,0,0,0,0,0,0,0,0,0,0,0,0,0,0,0,0,0,0)';
      OUTPUT_LOAD='(1.0,-1.0)';
    'P3_TXP4':
      PIN_NUMBER='(0,0,0,0,0,0,0,0,0,0,0,0,0,0,0,0,0,CJ33,0,0,0,0,0,0,0,0,0,0,0,0,0,0,0,0,0,0,0,0,0,0)';
      OUTPUT_LOAD='(1.0,-1.0)';
    'P3_TXN4':
      PIN_NUMBER='(0,0,0,0,0,0,0,0,0,0,0,0,0,0,0,0,0,CJ32,0,0,0,0,0,0,0,0,0,0,0,0,0,0,0,0,0,0,0,0,0,0)';
      OUTPUT_LOAD='(1.0,-1.0)';
    'P3_TXP5':
      PIN_NUMBER='(0,0,0,0,0,0,0,0,0,0,0,0,0,0,0,0,0,CG33,0,0,0,0,0,0,0,0,0,0,0,0,0,0,0,0,0,0,0,0,0,0)';
      OUTPUT_LOAD='(1.0,-1.0)';
    'P3_TXN5':
      PIN_NUMBER='(0,0,0,0,0,0,0,0,0,0,0,0,0,0,0,0,0,CG32,0,0,0,0,0,0,0,0,0,0,0,0,0,0,0,0,0,0,0,0,0,0)';
      OUTPUT_LOAD='(1.0,-1.0)';
    'P3_TXP6':
      PIN_NUMBER='(0,0,0,0,0,0,0,0,0,0,0,0,0,0,0,0,0,CE33,0,0,0,0,0,0,0,0,0,0,0,0,0,0,0,0,0,0,0,0,0,0)';
      OUTPUT_LOAD='(1.0,-1.0)';
    'P3_TXN6':
      PIN_NUMBER='(0,0,0,0,0,0,0,0,0,0,0,0,0,0,0,0,0,CE32,0,0,0,0,0,0,0,0,0,0,0,0,0,0,0,0,0,0,0,0,0,0)';
      OUTPUT_LOAD='(1.0,-1.0)';
    'P3_TXP7':
      PIN_NUMBER='(0,0,0,0,0,0,0,0,0,0,0,0,0,0,0,0,0,CC30,0,0,0,0,0,0,0,0,0,0,0,0,0,0,0,0,0,0,0,0,0,0)';
      OUTPUT_LOAD='(1.0,-1.0)';
    'P3_TXN7':
      PIN_NUMBER='(0,0,0,0,0,0,0,0,0,0,0,0,0,0,0,0,0,CC29,0,0,0,0,0,0,0,0,0,0,0,0,0,0,0,0,0,0,0,0,0,0)';
      OUTPUT_LOAD='(1.0,-1.0)';
    'P3_TXP8':
      PIN_NUMBER='(0,0,0,0,0,0,0,0,0,0,0,0,0,0,0,0,0,CG30,0,0,0,0,0,0,0,0,0,0,0,0,0,0,0,0,0,0,0,0,0,0)';
      OUTPUT_LOAD='(1.0,-1.0)';
    'P3_TXN8':
      PIN_NUMBER='(0,0,0,0,0,0,0,0,0,0,0,0,0,0,0,0,0,CG29,0,0,0,0,0,0,0,0,0,0,0,0,0,0,0,0,0,0,0,0,0,0)';
      OUTPUT_LOAD='(1.0,-1.0)';
    'P3_TXP9':
      PIN_NUMBER='(0,0,0,0,0,0,0,0,0,0,0,0,0,0,0,0,0,CE30,0,0,0,0,0,0,0,0,0,0,0,0,0,0,0,0,0,0,0,0,0,0)';
      OUTPUT_LOAD='(1.0,-1.0)';
    'P3_TXN9':
      PIN_NUMBER='(0,0,0,0,0,0,0,0,0,0,0,0,0,0,0,0,0,CE29,0,0,0,0,0,0,0,0,0,0,0,0,0,0,0,0,0,0,0,0,0,0)';
      OUTPUT_LOAD='(1.0,-1.0)';
    'P3_TXP10':
      PIN_NUMBER='(0,0,0,0,0,0,0,0,0,0,0,0,0,0,0,0,0,CC27,0,0,0,0,0,0,0,0,0,0,0,0,0,0,0,0,0,0,0,0,0,0)';
      OUTPUT_LOAD='(1.0,-1.0)';
    'P3_TXN10':
      PIN_NUMBER='(0,0,0,0,0,0,0,0,0,0,0,0,0,0,0,0,0,CC26,0,0,0,0,0,0,0,0,0,0,0,0,0,0,0,0,0,0,0,0,0,0)';
      OUTPUT_LOAD='(1.0,-1.0)';
    'P3_TXP11':
      PIN_NUMBER='(0,0,0,0,0,0,0,0,0,0,0,0,0,0,0,0,0,CG27,0,0,0,0,0,0,0,0,0,0,0,0,0,0,0,0,0,0,0,0,0,0)';
      OUTPUT_LOAD='(1.0,-1.0)';
    'P3_TXN11':
      PIN_NUMBER='(0,0,0,0,0,0,0,0,0,0,0,0,0,0,0,0,0,CG26,0,0,0,0,0,0,0,0,0,0,0,0,0,0,0,0,0,0,0,0,0,0)';
      OUTPUT_LOAD='(1.0,-1.0)';
    'P3_TXP12':
      PIN_NUMBER='(0,0,0,0,0,0,0,0,0,0,0,0,0,0,0,0,0,CE27,0,0,0,0,0,0,0,0,0,0,0,0,0,0,0,0,0,0,0,0,0,0)';
      OUTPUT_LOAD='(1.0,-1.0)';
    'P3_TXN12':
      PIN_NUMBER='(0,0,0,0,0,0,0,0,0,0,0,0,0,0,0,0,0,CE26,0,0,0,0,0,0,0,0,0,0,0,0,0,0,0,0,0,0,0,0,0,0)';
      OUTPUT_LOAD='(1.0,-1.0)';
    'P3_TXP13':
      PIN_NUMBER='(0,0,0,0,0,0,0,0,0,0,0,0,0,0,0,0,0,CC24,0,0,0,0,0,0,0,0,0,0,0,0,0,0,0,0,0,0,0,0,0,0)';
      OUTPUT_LOAD='(1.0,-1.0)';
    'P3_TXN13':
      PIN_NUMBER='(0,0,0,0,0,0,0,0,0,0,0,0,0,0,0,0,0,CC23,0,0,0,0,0,0,0,0,0,0,0,0,0,0,0,0,0,0,0,0,0,0)';
      OUTPUT_LOAD='(1.0,-1.0)';
    'P3_TXP14':
      PIN_NUMBER='(0,0,0,0,0,0,0,0,0,0,0,0,0,0,0,0,0,CG24,0,0,0,0,0,0,0,0,0,0,0,0,0,0,0,0,0,0,0,0,0,0)';
      OUTPUT_LOAD='(1.0,-1.0)';
    'P3_TXN14':
      PIN_NUMBER='(0,0,0,0,0,0,0,0,0,0,0,0,0,0,0,0,0,CG23,0,0,0,0,0,0,0,0,0,0,0,0,0,0,0,0,0,0,0,0,0,0)';
      OUTPUT_LOAD='(1.0,-1.0)';
    'P3_TXP15':
      PIN_NUMBER='(0,0,0,0,0,0,0,0,0,0,0,0,0,0,0,0,0,CE24,0,0,0,0,0,0,0,0,0,0,0,0,0,0,0,0,0,0,0,0,0,0)';
      OUTPUT_LOAD='(1.0,-1.0)';
    'P3_TXN15':
      PIN_NUMBER='(0,0,0,0,0,0,0,0,0,0,0,0,0,0,0,0,0,CE23,0,0,0,0,0,0,0,0,0,0,0,0,0,0,0,0,0,0,0,0,0,0)';
      OUTPUT_LOAD='(1.0,-1.0)';
    'P4_RXN2':
      PIN_NUMBER='(0,0,0,0,0,0,0,0,0,0,0,0,0,0,0,0,0,0,DG47,0,0,0,0,0,0,0,0,0,0,0,0,0,0,0,0,0,0,0,0,0)';
      INPUT_LOAD='(-0.01,0.01)';
    'P4_RXN3':
      PIN_NUMBER='(0,0,0,0,0,0,0,0,0,0,0,0,0,0,0,0,0,0,DG44,0,0,0,0,0,0,0,0,0,0,0,0,0,0,0,0,0,0,0,0,0)';
      INPUT_LOAD='(-0.01,0.01)';
    'P4_RXP2':
      PIN_NUMBER='(0,0,0,0,0,0,0,0,0,0,0,0,0,0,0,0,0,0,DG48,0,0,0,0,0,0,0,0,0,0,0,0,0,0,0,0,0,0,0,0,0)';
      INPUT_LOAD='(-0.01,0.01)';
    'P4_RXP3':
      PIN_NUMBER='(0,0,0,0,0,0,0,0,0,0,0,0,0,0,0,0,0,0,DG45,0,0,0,0,0,0,0,0,0,0,0,0,0,0,0,0,0,0,0,0,0)';
      INPUT_LOAD='(-0.01,0.01)';
    'P4_TXN2':
      PIN_NUMBER='(0,0,0,0,0,0,0,0,0,0,0,0,0,0,0,0,0,0,DE46,0,0,0,0,0,0,0,0,0,0,0,0,0,0,0,0,0,0,0,0,0)';
      OUTPUT_LOAD='(1.0,-1.0)';
    'P4_TXN3':
      PIN_NUMBER='(0,0,0,0,0,0,0,0,0,0,0,0,0,0,0,0,0,0,DE43,0,0,0,0,0,0,0,0,0,0,0,0,0,0,0,0,0,0,0,0,0)';
      OUTPUT_LOAD='(1.0,-1.0)';
    'P4_TXP2':
      PIN_NUMBER='(0,0,0,0,0,0,0,0,0,0,0,0,0,0,0,0,0,0,DE47,0,0,0,0,0,0,0,0,0,0,0,0,0,0,0,0,0,0,0,0,0)';
      OUTPUT_LOAD='(1.0,-1.0)';
    'P4_TXP3':
      PIN_NUMBER='(0,0,0,0,0,0,0,0,0,0,0,0,0,0,0,0,0,0,DE44,0,0,0,0,0,0,0,0,0,0,0,0,0,0,0,0,0,0,0,0,0)';
      OUTPUT_LOAD='(1.0,-1.0)';
    'P5_RXN2':
      PIN_NUMBER='(0,0,0,0,0,0,0,0,0,0,0,0,0,0,0,0,0,0,E44,0,0,0,0,0,0,0,0,0,0,0,0,0,0,0,0,0,0,0,0,0)';
      INPUT_LOAD='(-0.01,0.01)';
    'P5_RXN3':
      PIN_NUMBER='(0,0,0,0,0,0,0,0,0,0,0,0,0,0,0,0,0,0,E41,0,0,0,0,0,0,0,0,0,0,0,0,0,0,0,0,0,0,0,0,0)';
      INPUT_LOAD='(-0.01,0.01)';
    'P5_RXP2':
      PIN_NUMBER='(0,0,0,0,0,0,0,0,0,0,0,0,0,0,0,0,0,0,E43,0,0,0,0,0,0,0,0,0,0,0,0,0,0,0,0,0,0,0,0,0)';
      INPUT_LOAD='(-0.01,0.01)';
    'P5_RXP3':
      PIN_NUMBER='(0,0,0,0,0,0,0,0,0,0,0,0,0,0,0,0,0,0,E40,0,0,0,0,0,0,0,0,0,0,0,0,0,0,0,0,0,0,0,0,0)';
      INPUT_LOAD='(-0.01,0.01)';
    'P5_TXN2':
      PIN_NUMBER='(0,0,0,0,0,0,0,0,0,0,0,0,0,0,0,0,0,0,C45,0,0,0,0,0,0,0,0,0,0,0,0,0,0,0,0,0,0,0,0,0)';
      OUTPUT_LOAD='(1.0,-1.0)';
    'P5_TXN3':
      PIN_NUMBER='(0,0,0,0,0,0,0,0,0,0,0,0,0,0,0,0,0,0,C42,0,0,0,0,0,0,0,0,0,0,0,0,0,0,0,0,0,0,0,0,0)';
      OUTPUT_LOAD='(1.0,-1.0)';
    'P5_TXP2':
      PIN_NUMBER='(0,0,0,0,0,0,0,0,0,0,0,0,0,0,0,0,0,0,C44,0,0,0,0,0,0,0,0,0,0,0,0,0,0,0,0,0,0,0,0,0)';
      OUTPUT_LOAD='(1.0,-1.0)';
    'P5_TXP3':
      PIN_NUMBER='(0,0,0,0,0,0,0,0,0,0,0,0,0,0,0,0,0,0,C41,0,0,0,0,0,0,0,0,0,0,0,0,0,0,0,0,0,0,0,0,0)';
      OUTPUT_LOAD='(1.0,-1.0)';
    'P4_TXP0':
      PIN_NUMBER='(0,0,0,0,0,0,0,0,0,0,0,0,0,0,0,0,0,0,DE53,0,0,0,0,0,0,0,0,0,0,0,0,0,0,0,0,0,0,0,0,0)';
      OUTPUT_LOAD='(1.0,-1.0)';
    'P4_TXP1':
      PIN_NUMBER='(0,0,0,0,0,0,0,0,0,0,0,0,0,0,0,0,0,0,DE50,0,0,0,0,0,0,0,0,0,0,0,0,0,0,0,0,0,0,0,0,0)';
      OUTPUT_LOAD='(1.0,-1.0)';
    'P4_TXN0':
      PIN_NUMBER='(0,0,0,0,0,0,0,0,0,0,0,0,0,0,0,0,0,0,DE52,0,0,0,0,0,0,0,0,0,0,0,0,0,0,0,0,0,0,0,0,0)';
      OUTPUT_LOAD='(1.0,-1.0)';
    'P4_RXP0':
      PIN_NUMBER='(0,0,0,0,0,0,0,0,0,0,0,0,0,0,0,0,0,0,DG54,0,0,0,0,0,0,0,0,0,0,0,0,0,0,0,0,0,0,0,0,0)';
      INPUT_LOAD='(-0.01,0.01)';
    'P4_TXN1':
      PIN_NUMBER='(0,0,0,0,0,0,0,0,0,0,0,0,0,0,0,0,0,0,DE49,0,0,0,0,0,0,0,0,0,0,0,0,0,0,0,0,0,0,0,0,0)';
      OUTPUT_LOAD='(1.0,-1.0)';
    'P4_RXP1':
      PIN_NUMBER='(0,0,0,0,0,0,0,0,0,0,0,0,0,0,0,0,0,0,DG51,0,0,0,0,0,0,0,0,0,0,0,0,0,0,0,0,0,0,0,0,0)';
      INPUT_LOAD='(-0.01,0.01)';
    'P4_RXN0':
      PIN_NUMBER='(0,0,0,0,0,0,0,0,0,0,0,0,0,0,0,0,0,0,DG53,0,0,0,0,0,0,0,0,0,0,0,0,0,0,0,0,0,0,0,0,0)';
      INPUT_LOAD='(-0.01,0.01)';
    'P4_RXN1':
      PIN_NUMBER='(0,0,0,0,0,0,0,0,0,0,0,0,0,0,0,0,0,0,DG50,0,0,0,0,0,0,0,0,0,0,0,0,0,0,0,0,0,0,0,0,0)';
      INPUT_LOAD='(-0.01,0.01)';
    'WAFL_RXN0||P5_RXN0':
      PIN_NUMBER='(0,0,0,0,0,0,0,0,0,0,0,0,0,0,0,0,0,0,E50,0,0,0,0,0,0,0,0,0,0,0,0,0,0,0,0,0,0,0,0,0)';
      INPUT_LOAD='(-0.01,0.01)';
    'WAFL_RXP0||P5_RXP0':
      PIN_NUMBER='(0,0,0,0,0,0,0,0,0,0,0,0,0,0,0,0,0,0,E49,0,0,0,0,0,0,0,0,0,0,0,0,0,0,0,0,0,0,0,0,0)';
      INPUT_LOAD='(-0.01,0.01)';
    'WAFL_RXN1||P5_RXN1':
      PIN_NUMBER='(0,0,0,0,0,0,0,0,0,0,0,0,0,0,0,0,0,0,E47,0,0,0,0,0,0,0,0,0,0,0,0,0,0,0,0,0,0,0,0,0)';
      INPUT_LOAD='(-0.01,0.01)';
    'WAFL_RXP1||P5_RXP1':
      PIN_NUMBER='(0,0,0,0,0,0,0,0,0,0,0,0,0,0,0,0,0,0,E46,0,0,0,0,0,0,0,0,0,0,0,0,0,0,0,0,0,0,0,0,0)';
      INPUT_LOAD='(-0.01,0.01)';
    'WAFL_TXN0||P5_TXN0':
      PIN_NUMBER='(0,0,0,0,0,0,0,0,0,0,0,0,0,0,0,0,0,0,C51,0,0,0,0,0,0,0,0,0,0,0,0,0,0,0,0,0,0,0,0,0)';
      OUTPUT_LOAD='(1.0,-1.0)';
    'WAFL_TXP0||P5_TXP0':
      PIN_NUMBER='(0,0,0,0,0,0,0,0,0,0,0,0,0,0,0,0,0,0,C50,0,0,0,0,0,0,0,0,0,0,0,0,0,0,0,0,0,0,0,0,0)';
      OUTPUT_LOAD='(1.0,-1.0)';
    'WAFL_TXN1||P5_TXN1':
      PIN_NUMBER='(0,0,0,0,0,0,0,0,0,0,0,0,0,0,0,0,0,0,C48,0,0,0,0,0,0,0,0,0,0,0,0,0,0,0,0,0,0,0,0,0)';
      OUTPUT_LOAD='(1.0,-1.0)';
    'WAFL_TXP1||P5_TXP1':
      PIN_NUMBER='(0,0,0,0,0,0,0,0,0,0,0,0,0,0,0,0,0,0,C47,0,0,0,0,0,0,0,0,0,0,0,0,0,0,0,0,0,0,0,0,0)';
      OUTPUT_LOAD='(1.0,-1.0)';
    'ALERT_L':
      PIN_NUMBER='(0,0,0,0,0,0,0,0,0,0,0,0,0,0,0,0,0,0,0,A68,0,0,0,0,0,0,0,0,0,0,0,0,0,0,0,0,0,0,0,0)';
      OUTPUT_LOAD='(1.0,-1.0)';
    'CPU_PRESENT_L':
      PIN_NUMBER='(0,0,0,0,0,0,0,0,0,0,0,0,0,0,0,0,0,0,0,B66,0,0,0,0,0,0,0,0,0,0,0,0,0,0,0,0,0,0,0,0)';
      OUTPUT_LOAD='(1.0,-1.0)';
    'DBREQ_L':
      PIN_NUMBER='(0,0,0,0,0,0,0,0,0,0,0,0,0,0,0,0,0,0,0,C16,0,0,0,0,0,0,0,0,0,0,0,0,0,0,0,0,0,0,0,0)';
      INPUT_LOAD='(-0.01,0.01)';
    'PROCHOT_L':
      PIN_NUMBER='(0,0,0,0,0,0,0,0,0,0,0,0,0,0,0,0,0,0,0,A69,0,0,0,0,0,0,0,0,0,0,0,0,0,0,0,0,0,0,0,0)';
      INPUT_LOAD='(-0.01,0.01)';
    'SA0':
      PIN_NUMBER='(0,0,0,0,0,0,0,0,0,0,0,0,0,0,0,0,0,0,0,DJ55,0,0,0,0,0,0,0,0,0,0,0,0,0,0,0,0,0,0,0,0)';
      INPUT_LOAD='(-0.01,0.01)';
    'SIC':
      PIN_NUMBER='(0,0,0,0,0,0,0,0,0,0,0,0,0,0,0,0,0,0,0,DJ71,0,0,0,0,0,0,0,0,0,0,0,0,0,0,0,0,0,0,0,0)';
      OUTPUT_LOAD='(1.0,-1.0)';
    'SID':
      PIN_NUMBER='(0,0,0,0,0,0,0,0,0,0,0,0,0,0,0,0,0,0,0,DH71,0,0,0,0,0,0,0,0,0,0,0,0,0,0,0,0,0,0,0,0)';
      BIDIRECTIONAL='TRUE';
      INPUT_LOAD='(-0.01,0.01)';
      OUTPUT_LOAD='(1.0,-1.0)';
    'TDI':
      PIN_NUMBER='(0,0,0,0,0,0,0,0,0,0,0,0,0,0,0,0,0,0,0,C17,0,0,0,0,0,0,0,0,0,0,0,0,0,0,0,0,0,0,0,0)';
      INPUT_LOAD='(-0.01,0.01)';
    'TDO':
      PIN_NUMBER='(0,0,0,0,0,0,0,0,0,0,0,0,0,0,0,0,0,0,0,C18,0,0,0,0,0,0,0,0,0,0,0,0,0,0,0,0,0,0,0,0)';
      OUTPUT_LOAD='(1.0,-1.0)';
    'THERMTRIP_L':
      PIN_NUMBER='(0,0,0,0,0,0,0,0,0,0,0,0,0,0,0,0,0,0,0,DJ9,0,0,0,0,0,0,0,0,0,0,0,0,0,0,0,0,0,0,0,0)';
      OUTPUT_LOAD='(1.0,-1.0)';
    'TMS':
      PIN_NUMBER='(0,0,0,0,0,0,0,0,0,0,0,0,0,0,0,0,0,0,0,A16,0,0,0,0,0,0,0,0,0,0,0,0,0,0,0,0,0,0,0,0)';
      INPUT_LOAD='(-0.01,0.01)';
    'TRST_L':
      PIN_NUMBER='(0,0,0,0,0,0,0,0,0,0,0,0,0,0,0,0,0,0,0,A17,0,0,0,0,0,0,0,0,0,0,0,0,0,0,0,0,0,0,0,0)';
      INPUT_LOAD='(-0.01,0.01)';
    'XTRIG_L4':
      PIN_NUMBER='(0,0,0,0,0,0,0,0,0,0,0,0,0,0,0,0,0,0,0,C66,0,0,0,0,0,0,0,0,0,0,0,0,0,0,0,0,0,0,0,0)';
      OUTPUT_LOAD='(1.0,-1.0)';
    'XTRIG_L5':
      PIN_NUMBER='(0,0,0,0,0,0,0,0,0,0,0,0,0,0,0,0,0,0,0,C65,0,0,0,0,0,0,0,0,0,0,0,0,0,0,0,0,0,0,0,0)';
      OUTPUT_LOAD='(1.0,-1.0)';
    'XTRIG_L6':
      PIN_NUMBER='(0,0,0,0,0,0,0,0,0,0,0,0,0,0,0,0,0,0,0,A66,0,0,0,0,0,0,0,0,0,0,0,0,0,0,0,0,0,0,0,0)';
      OUTPUT_LOAD='(1.0,-1.0)';
    'XTRIG_L7':
      PIN_NUMBER='(0,0,0,0,0,0,0,0,0,0,0,0,0,0,0,0,0,0,0,A65,0,0,0,0,0,0,0,0,0,0,0,0,0,0,0,0,0,0,0,0)';
      OUTPUT_LOAD='(1.0,-1.0)';
    'SA1':
      PIN_NUMBER='(0,0,0,0,0,0,0,0,0,0,0,0,0,0,0,0,0,0,0,DJ56,0,0,0,0,0,0,0,0,0,0,0,0,0,0,0,0,0,0,0,0)';
      INPUT_LOAD='(-0.01,0.01)';
    'CORETYPE0':
      PIN_NUMBER='(0,0,0,0,0,0,0,0,0,0,0,0,0,0,0,0,0,0,0,C70,0,0,0,0,0,0,0,0,0,0,0,0,0,0,0,0,0,0,0,0)';
      OUTPUT_LOAD='(1.0,-1.0)';
    'CORETYPE1':
      PIN_NUMBER='(0,0,0,0,0,0,0,0,0,0,0,0,0,0,0,0,0,0,0,B69,0,0,0,0,0,0,0,0,0,0,0,0,0,0,0,0,0,0,0,0)';
      OUTPUT_LOAD='(1.0,-1.0)';
    'SP5R2':
      PIN_NUMBER='(0,0,0,0,0,0,0,0,0,0,0,0,0,0,0,0,0,0,0,C68,0,0,0,0,0,0,0,0,0,0,0,0,0,0,0,0,0,0,0,0)';
      OUTPUT_LOAD='(1.0,-1.0)';
    'SP5R3':
      PIN_NUMBER='(0,0,0,0,0,0,0,0,0,0,0,0,0,0,0,0,0,0,0,DH73,0,0,0,0,0,0,0,0,0,0,0,0,0,0,0,0,0,0,0,0)';
      OUTPUT_LOAD='(1.0,-1.0)';
    'SP5R4':
      PIN_NUMBER='(0,0,0,0,0,0,0,0,0,0,0,0,0,0,0,0,0,0,0,DH10,0,0,0,0,0,0,0,0,0,0,0,0,0,0,0,0,0,0,0,0)';
      OUTPUT_LOAD='(1.0,-1.0)';
    'PCC0_L':
      PIN_NUMBER='(0,0,0,0,0,0,0,0,0,0,0,0,0,0,0,0,0,0,0,C22,0,0,0,0,0,0,0,0,0,0,0,0,0,0,0,0,0,0,0,0)';
      INPUT_LOAD='(-0.01,0.01)';
    'PCC1_L':
      PIN_NUMBER='(0,0,0,0,0,0,0,0,0,0,0,0,0,0,0,0,0,0,0,DG72,0,0,0,0,0,0,0,0,0,0,0,0,0,0,0,0,0,0,0,0)';
      INPUT_LOAD='(-0.01,0.01)';
    'AZ_BITCLK':
      PIN_NUMBER='(0,0,0,0,0,0,0,0,0,0,0,0,0,0,0,0,0,0,0,C32,0,0,0,0,0,0,0,0,0,0,0,0,0,0,0,0,0,0,0,0)';
      OUTPUT_LOAD='(1.0,-1.0)';
    'AZ_SYNC':
      PIN_NUMBER='(0,0,0,0,0,0,0,0,0,0,0,0,0,0,0,0,0,0,0,D32,0,0,0,0,0,0,0,0,0,0,0,0,0,0,0,0,0,0,0,0)';
      OUTPUT_LOAD='(1.0,-1.0)';
    'SVD0':
      PIN_NUMBER='(0,0,0,0,0,0,0,0,0,0,0,0,0,0,0,0,0,0,0,A22,0,0,0,0,0,0,0,0,0,0,0,0,0,0,0,0,0,0,0,0)';
      BIDIRECTIONAL='TRUE';
      INPUT_LOAD='(-0.01,0.01)';
      OUTPUT_LOAD='(1.0,-1.0)';
    'SVT0':
      PIN_NUMBER='(0,0,0,0,0,0,0,0,0,0,0,0,0,0,0,0,0,0,0,B21,0,0,0,0,0,0,0,0,0,0,0,0,0,0,0,0,0,0,0,0)';
      INPUT_LOAD='(-0.01,0.01)';
    'SVD1':
      PIN_NUMBER='(0,0,0,0,0,0,0,0,0,0,0,0,0,0,0,0,0,0,0,DH72,0,0,0,0,0,0,0,0,0,0,0,0,0,0,0,0,0,0,0,0)';
      BIDIRECTIONAL='TRUE';
      INPUT_LOAD='(-0.01,0.01)';
      OUTPUT_LOAD='(1.0,-1.0)';
    'SVC0':
      PIN_NUMBER='(0,0,0,0,0,0,0,0,0,0,0,0,0,0,0,0,0,0,0,A23,0,0,0,0,0,0,0,0,0,0,0,0,0,0,0,0,0,0,0,0)';
      OUTPUT_LOAD='(1.0,-1.0)';
    'SVT1':
      PIN_NUMBER='(0,0,0,0,0,0,0,0,0,0,0,0,0,0,0,0,0,0,0,DG73,0,0,0,0,0,0,0,0,0,0,0,0,0,0,0,0,0,0,0,0)';
      INPUT_LOAD='(-0.01,0.01)';
    'SVC1':
      PIN_NUMBER='(0,0,0,0,0,0,0,0,0,0,0,0,0,0,0,0,0,0,0,DJ72,0,0,0,0,0,0,0,0,0,0,0,0,0,0,0,0,0,0,0,0)';
      OUTPUT_LOAD='(1.0,-1.0)';
    'UART0_RXD||AGPIO136':
      PIN_NUMBER='(0,0,0,0,0,0,0,0,0,0,0,0,0,0,0,0,0,0,0,DG35,0,0,0,0,0,0,0,0,0,0,0,0,0,0,0,0,0,0,0,0)';
      BIDIRECTIONAL='TRUE';
      INPUT_LOAD='(-0.01,0.01)';
      OUTPUT_LOAD='(1.0,-1.0)';
    'UART0_RTS_L||UART2_RXD||AGPIO137':
      PIN_NUMBER='(0,0,0,0,0,0,0,0,0,0,0,0,0,0,0,0,0,0,0,DF34,0,0,0,0,0,0,0,0,0,0,0,0,0,0,0,0,0,0,0,0)';
      BIDIRECTIONAL='TRUE';
      INPUT_LOAD='(-0.01,0.01)';
      OUTPUT_LOAD='(1.0,-1.0)';
    'UART0_INTR||AGPIO139':
      PIN_NUMBER='(0,0,0,0,0,0,0,0,0,0,0,0,0,0,0,0,0,0,0,DG34,0,0,0,0,0,0,0,0,0,0,0,0,0,0,0,0,0,0,0,0)';
      BIDIRECTIONAL='TRUE';
      INPUT_LOAD='(-0.01,0.01)';
      OUTPUT_LOAD='(1.0,-1.0)';
    'UART0_TXD||AGPIO138':
      PIN_NUMBER='(0,0,0,0,0,0,0,0,0,0,0,0,0,0,0,0,0,0,0,DJ34,0,0,0,0,0,0,0,0,0,0,0,0,0,0,0,0,0,0,0,0)';
      BIDIRECTIONAL='TRUE';
      INPUT_LOAD='(-0.01,0.01)';
      OUTPUT_LOAD='(1.0,-1.0)';
    'UART0_CTS_L||UART2_TXD||AGPIO135':
      PIN_NUMBER='(0,0,0,0,0,0,0,0,0,0,0,0,0,0,0,0,0,0,0,DJ33,0,0,0,0,0,0,0,0,0,0,0,0,0,0,0,0,0,0,0,0)';
      BIDIRECTIONAL='TRUE';
      INPUT_LOAD='(-0.01,0.01)';
      OUTPUT_LOAD='(1.0,-1.0)';
    'AZ_SDIN2||SW_MDATA0':
      PIN_NUMBER='(0,0,0,0,0,0,0,0,0,0,0,0,0,0,0,0,0,0,0,A33,0,0,0,0,0,0,0,0,0,0,0,0,0,0,0,0,0,0,0,0)';
      OUTPUT_LOAD='(1.0,-1.0)';
    'AZ_SDOUT||SW_MDATA2':
      PIN_NUMBER='(0,0,0,0,0,0,0,0,0,0,0,0,0,0,0,0,0,0,0,A32,0,0,0,0,0,0,0,0,0,0,0,0,0,0,0,0,0,0,0,0)';
      OUTPUT_LOAD='(1.0,-1.0)';
    'AZ_RST_L||SW_MDATA1':
      PIN_NUMBER='(0,0,0,0,0,0,0,0,0,0,0,0,0,0,0,0,0,0,0,A34,0,0,0,0,0,0,0,0,0,0,0,0,0,0,0,0,0,0,0,0)';
      OUTPUT_LOAD='(1.0,-1.0)';
    'AZ_SDIN0||SW_MDATA3':
      PIN_NUMBER='(0,0,0,0,0,0,0,0,0,0,0,0,0,0,0,0,0,0,0,C33,0,0,0,0,0,0,0,0,0,0,0,0,0,0,0,0,0,0,0,0)';
      OUTPUT_LOAD='(1.0,-1.0)';
    'AZ_SDIN1||SW_MCLK':
      PIN_NUMBER='(0,0,0,0,0,0,0,0,0,0,0,0,0,0,0,0,0,0,0,D33,0,0,0,0,0,0,0,0,0,0,0,0,0,0,0,0,0,0,0,0)';
      OUTPUT_LOAD='(1.0,-1.0)';
    'SP5R1':
      PIN_NUMBER='(0,0,0,0,0,0,0,0,0,0,0,0,0,0,0,0,0,0,0,C19,0,0,0,0,0,0,0,0,0,0,0,0,0,0,0,0,0,0,0,0)';
      OUTPUT_LOAD='(1.0,-1.0)';
    'TCK':
      PIN_NUMBER='(0,0,0,0,0,0,0,0,0,0,0,0,0,0,0,0,0,0,0,B17,0,0,0,0,0,0,0,0,0,0,0,0,0,0,0,0,0,0,0,0)';
      INPUT_LOAD='(-0.01,0.01)';
    'RTC_LDO_SELECT':
      PIN_NUMBER='(0,0,0,0,0,0,0,0,0,0,0,0,0,0,0,0,0,0,0,DH8,0,0,0,0,0,0,0,0,0,0,0,0,0,0,0,0,0,0,0,0)';
      INPUT_LOAD='(-0.01,0.01)';
    'UART1_RXD||AGPIO141':
      PIN_NUMBER='(0,0,0,0,0,0,0,0,0,0,0,0,0,0,0,0,0,0,0,DH33,0,0,0,0,0,0,0,0,0,0,0,0,0,0,0,0,0,0,0,0)';
      BIDIRECTIONAL='TRUE';
      INPUT_LOAD='(-0.01,0.01)';
      OUTPUT_LOAD='(1.0,-1.0)';
    'UART1_TXD||AGPIO142':
      PIN_NUMBER='(0,0,0,0,0,0,0,0,0,0,0,0,0,0,0,0,0,0,0,DJ32,0,0,0,0,0,0,0,0,0,0,0,0,0,0,0,0,0,0,0,0)';
      BIDIRECTIONAL='TRUE';
      INPUT_LOAD='(-0.01,0.01)';
      OUTPUT_LOAD='(1.0,-1.0)';
    'VSS_SENSE_A':
      PIN_NUMBER='(0,0,0,0,0,0,0,0,0,0,0,0,0,0,0,0,0,0,0,C3,0,0,0,0,0,0,0,0,0,0,0,0,0,0,0,0,0,0,0,0)';
      PINUSE='POWER';
      NO_LOAD_CHECK='Both';
      NO_IO_CHECK='Both';
      NO_ASSERT_CHECK='TRUE';
      NO_DIR_CHECK='TRUE';
      ALLOW_CONNECT='TRUE';
    'VSS_SENSE_B':
      PIN_NUMBER='(0,0,0,0,0,0,0,0,0,0,0,0,0,0,0,0,0,0,0,BR54,0,0,0,0,0,0,0,0,0,0,0,0,0,0,0,0,0,0,0,0)';
      PINUSE='POWER';
      NO_LOAD_CHECK='Both';
      NO_IO_CHECK='Both';
      NO_ASSERT_CHECK='TRUE';
      NO_DIR_CHECK='TRUE';
      ALLOW_CONNECT='TRUE';
    'VSS_SENSE_C':
      PIN_NUMBER='(0,0,0,0,0,0,0,0,0,0,0,0,0,0,0,0,0,0,0,DJ3,0,0,0,0,0,0,0,0,0,0,0,0,0,0,0,0,0,0,0,0)';
      PINUSE='POWER';
      NO_LOAD_CHECK='Both';
      NO_IO_CHECK='Both';
      NO_ASSERT_CHECK='TRUE';
      NO_DIR_CHECK='TRUE';
      ALLOW_CONNECT='TRUE';
    'VSS_SENSE_D':
      PIN_NUMBER='(0,0,0,0,0,0,0,0,0,0,0,0,0,0,0,0,0,0,0,B73,0,0,0,0,0,0,0,0,0,0,0,0,0,0,0,0,0,0,0,0)';
      PINUSE='POWER';
      NO_LOAD_CHECK='Both';
      NO_IO_CHECK='Both';
      NO_ASSERT_CHECK='TRUE';
      NO_DIR_CHECK='TRUE';
      ALLOW_CONNECT='TRUE';
    'VDDIO_SENSE':
      PIN_NUMBER='(0,0,0,0,0,0,0,0,0,0,0,0,0,0,0,0,0,0,0,BR53,0,0,0,0,0,0,0,0,0,0,0,0,0,0,0,0,0,0,0,0)';
      PINUSE='POWER';
      NO_LOAD_CHECK='Both';
      NO_IO_CHECK='Both';
      NO_ASSERT_CHECK='TRUE';
      NO_DIR_CHECK='TRUE';
      ALLOW_CONNECT='TRUE';
    'VDD_11_S3_SENSE':
      PIN_NUMBER='(0,0,0,0,0,0,0,0,0,0,0,0,0,0,0,0,0,0,0,DH3,0,0,0,0,0,0,0,0,0,0,0,0,0,0,0,0,0,0,0,0)';
      PINUSE='POWER';
      NO_LOAD_CHECK='Both';
      NO_IO_CHECK='Both';
      NO_ASSERT_CHECK='TRUE';
      NO_DIR_CHECK='TRUE';
      ALLOW_CONNECT='TRUE';
    'VDD_18_S5_SENSE':
      PIN_NUMBER='(0,0,0,0,0,0,0,0,0,0,0,0,0,0,0,0,0,0,0,C74,0,0,0,0,0,0,0,0,0,0,0,0,0,0,0,0,0,0,0,0)';
      PINUSE='POWER';
      NO_LOAD_CHECK='Both';
      NO_IO_CHECK='Both';
      NO_ASSERT_CHECK='TRUE';
      NO_DIR_CHECK='TRUE';
      ALLOW_CONNECT='TRUE';
    'VDD_33_S5_SENSE':
      PIN_NUMBER='(0,0,0,0,0,0,0,0,0,0,0,0,0,0,0,0,0,0,0,BP53,0,0,0,0,0,0,0,0,0,0,0,0,0,0,0,0,0,0,0,0)';
      PINUSE='POWER';
      NO_LOAD_CHECK='Both';
      NO_IO_CHECK='Both';
      NO_ASSERT_CHECK='TRUE';
      NO_DIR_CHECK='TRUE';
      ALLOW_CONNECT='TRUE';
    'VDDCR_SOC_SENSE':
      PIN_NUMBER='(0,0,0,0,0,0,0,0,0,0,0,0,0,0,0,0,0,0,0,B3,0,0,0,0,0,0,0,0,0,0,0,0,0,0,0,0,0,0,0,0)';
      PINUSE='POWER';
      NO_LOAD_CHECK='Both';
      NO_IO_CHECK='Both';
      NO_ASSERT_CHECK='TRUE';
      NO_DIR_CHECK='TRUE';
      ALLOW_CONNECT='TRUE';
    'VDDCR_CPU1_SENSE':
      PIN_NUMBER='(0,0,0,0,0,0,0,0,0,0,0,0,0,0,0,0,0,0,0,DG3,0,0,0,0,0,0,0,0,0,0,0,0,0,0,0,0,0,0,0,0)';
      PINUSE='POWER';
      NO_LOAD_CHECK='Both';
      NO_IO_CHECK='Both';
      NO_ASSERT_CHECK='TRUE';
      NO_DIR_CHECK='TRUE';
      ALLOW_CONNECT='TRUE';
    'VDDCR_CPU0_SENSE':
      PIN_NUMBER='(0,0,0,0,0,0,0,0,0,0,0,0,0,0,0,0,0,0,0,C2,0,0,0,0,0,0,0,0,0,0,0,0,0,0,0,0,0,0,0,0)';
      PINUSE='POWER';
      NO_LOAD_CHECK='Both';
      NO_IO_CHECK='Both';
      NO_ASSERT_CHECK='TRUE';
      NO_DIR_CHECK='TRUE';
      ALLOW_CONNECT='TRUE';
    'TEST6_X3D4':
      PIN_NUMBER='(0,0,0,0,0,0,0,0,0,0,0,0,0,0,0,0,0,0,0,AA23,0,0,0,0,0,0,0,0,0,0,0,0,0,0,0,0,0,0,0,0)';
      OUTPUT_LOAD='(1.0,-1.0)';
    'TEST6_CCD1':
      PIN_NUMBER='(0,0,0,0,0,0,0,0,0,0,0,0,0,0,0,0,0,0,0,CJ30,0,0,0,0,0,0,0,0,0,0,0,0,0,0,0,0,0,0,0,0)';
      OUTPUT_LOAD='(1.0,-1.0)';
    'TEST5_CCD0':
      PIN_NUMBER='(0,0,0,0,0,0,0,0,0,0,0,0,0,0,0,0,0,0,0,AA51,0,0,0,0,0,0,0,0,0,0,0,0,0,0,0,0,0,0,0,0)';
      OUTPUT_TYPE='(TS,TS)';
      INPUT_LOAD='(-0.01,0.01)';
      OUTPUT_LOAD='(1.0,-1.0)';
    'TEST6_X3D5':
      PIN_NUMBER='(0,0,0,0,0,0,0,0,0,0,0,0,0,0,0,0,0,0,0,CJ53,0,0,0,0,0,0,0,0,0,0,0,0,0,0,0,0,0,0,0,0)';
      OUTPUT_LOAD='(1.0,-1.0)';
    'TEST6_CCD2':
      PIN_NUMBER='(0,0,0,0,0,0,0,0,0,0,0,0,0,0,0,0,0,0,0,CJ46,0,0,0,0,0,0,0,0,0,0,0,0,0,0,0,0,0,0,0,0)';
      OUTPUT_LOAD='(1.0,-1.0)';
    'TEST5_CCD1':
      PIN_NUMBER='(0,0,0,0,0,0,0,0,0,0,0,0,0,0,0,0,0,0,0,CJ27,0,0,0,0,0,0,0,0,0,0,0,0,0,0,0,0,0,0,0,0)';
      OUTPUT_TYPE='(TS,TS)';
      INPUT_LOAD='(-0.01,0.01)';
      OUTPUT_LOAD='(1.0,-1.0)';
    'TEST4_CCD0':
      PIN_NUMBER='(0,0,0,0,0,0,0,0,0,0,0,0,0,0,0,0,0,0,0,AA50,0,0,0,0,0,0,0,0,0,0,0,0,0,0,0,0,0,0,0,0)';
      OUTPUT_TYPE='(TS,TS)';
      INPUT_LOAD='(-0.01,0.01)';
      OUTPUT_LOAD='(1.0,-1.0)';
    'TEST6_CCD3':
      PIN_NUMBER='(0,0,0,0,0,0,0,0,0,0,0,0,0,0,0,0,0,0,0,Y46,0,0,0,0,0,0,0,0,0,0,0,0,0,0,0,0,0,0,0,0)';
      OUTPUT_LOAD='(1.0,-1.0)';
    'TEST5_CCD2':
      PIN_NUMBER='(0,0,0,0,0,0,0,0,0,0,0,0,0,0,0,0,0,0,0,CJ49,0,0,0,0,0,0,0,0,0,0,0,0,0,0,0,0,0,0,0,0)';
      OUTPUT_TYPE='(TS,TS)';
      INPUT_LOAD='(-0.01,0.01)';
      OUTPUT_LOAD='(1.0,-1.0)';
    'TEST4_CCD1':
      PIN_NUMBER='(0,0,0,0,0,0,0,0,0,0,0,0,0,0,0,0,0,0,0,CJ28,0,0,0,0,0,0,0,0,0,0,0,0,0,0,0,0,0,0,0,0)';
      OUTPUT_TYPE='(TS,TS)';
      INPUT_LOAD='(-0.01,0.01)';
      OUTPUT_LOAD='(1.0,-1.0)';
    'TEST5_CCD3':
      PIN_NUMBER='(0,0,0,0,0,0,0,0,0,0,0,0,0,0,0,0,0,0,0,Y30,0,0,0,0,0,0,0,0,0,0,0,0,0,0,0,0,0,0,0,0)';
      OUTPUT_TYPE='(TS,TS)';
      INPUT_LOAD='(-0.01,0.01)';
      OUTPUT_LOAD='(1.0,-1.0)';
    'TEST4_IOD':
      PIN_NUMBER='(0,0,0,0,0,0,0,0,0,0,0,0,0,0,0,0,0,0,0,AA25,0,0,0,0,0,0,0,0,0,0,0,0,0,0,0,0,0,0,0,0)';
      OUTPUT_TYPE='(TS,TS)';
      INPUT_LOAD='(-0.01,0.01)';
      OUTPUT_LOAD='(1.0,-1.0)';
    'TEST4_CCD2':
      PIN_NUMBER='(0,0,0,0,0,0,0,0,0,0,0,0,0,0,0,0,0,0,0,CJ48,0,0,0,0,0,0,0,0,0,0,0,0,0,0,0,0,0,0,0,0)';
      OUTPUT_TYPE='(TS,TS)';
      INPUT_LOAD='(-0.01,0.01)';
      OUTPUT_LOAD='(1.0,-1.0)';
    'TEST5_IOD':
      PIN_NUMBER='(0,0,0,0,0,0,0,0,0,0,0,0,0,0,0,0,0,0,0,AA24,0,0,0,0,0,0,0,0,0,0,0,0,0,0,0,0,0,0,0,0)';
      OUTPUT_TYPE='(TS,TS)';
      INPUT_LOAD='(-0.01,0.01)';
      OUTPUT_LOAD='(1.0,-1.0)';
    'TEST5_CCD4':
      PIN_NUMBER='(0,0,0,0,0,0,0,0,0,0,0,0,0,0,0,0,0,0,0,AA53,0,0,0,0,0,0,0,0,0,0,0,0,0,0,0,0,0,0,0,0)';
      OUTPUT_TYPE='(TS,TS)';
      INPUT_LOAD='(-0.01,0.01)';
      OUTPUT_LOAD='(1.0,-1.0)';
    'TEST4_CCD3':
      PIN_NUMBER='(0,0,0,0,0,0,0,0,0,0,0,0,0,0,0,0,0,0,0,AA30,0,0,0,0,0,0,0,0,0,0,0,0,0,0,0,0,0,0,0,0)';
      OUTPUT_TYPE='(TS,TS)';
      INPUT_LOAD='(-0.01,0.01)';
      OUTPUT_LOAD='(1.0,-1.0)';
    'TEST6_IOD':
      PIN_NUMBER='(0,0,0,0,0,0,0,0,0,0,0,0,0,0,0,0,0,0,0,AA49,0,0,0,0,0,0,0,0,0,0,0,0,0,0,0,0,0,0,0,0)';
      OUTPUT_LOAD='(1.0,-1.0)';
    'TEST5_CCD5':
      PIN_NUMBER='(0,0,0,0,0,0,0,0,0,0,0,0,0,0,0,0,0,0,0,CJ25,0,0,0,0,0,0,0,0,0,0,0,0,0,0,0,0,0,0,0,0)';
      OUTPUT_TYPE='(TS,TS)';
      INPUT_LOAD='(-0.01,0.01)';
      OUTPUT_LOAD='(1.0,-1.0)';
    'TEST4_CCD4':
      PIN_NUMBER='(0,0,0,0,0,0,0,0,0,0,0,0,0,0,0,0,0,0,0,AA52,0,0,0,0,0,0,0,0,0,0,0,0,0,0,0,0,0,0,0,0)';
      OUTPUT_TYPE='(TS,TS)';
      INPUT_LOAD='(-0.01,0.01)';
      OUTPUT_LOAD='(1.0,-1.0)';
    'TEST5_CCD6':
      PIN_NUMBER='(0,0,0,0,0,0,0,0,0,0,0,0,0,0,0,0,0,0,0,CJ51,0,0,0,0,0,0,0,0,0,0,0,0,0,0,0,0,0,0,0,0)';
      OUTPUT_TYPE='(TS,TS)';
      INPUT_LOAD='(-0.01,0.01)';
      OUTPUT_LOAD='(1.0,-1.0)';
    'TEST4_CCD5':
      PIN_NUMBER='(0,0,0,0,0,0,0,0,0,0,0,0,0,0,0,0,0,0,0,CJ26,0,0,0,0,0,0,0,0,0,0,0,0,0,0,0,0,0,0,0,0)';
      OUTPUT_TYPE='(TS,TS)';
      INPUT_LOAD='(-0.01,0.01)';
      OUTPUT_LOAD='(1.0,-1.0)';
    'TEST5_CCD7':
      PIN_NUMBER='(0,0,0,0,0,0,0,0,0,0,0,0,0,0,0,0,0,0,0,AA26,0,0,0,0,0,0,0,0,0,0,0,0,0,0,0,0,0,0,0,0)';
      OUTPUT_TYPE='(TS,TS)';
      INPUT_LOAD='(-0.01,0.01)';
      OUTPUT_LOAD='(1.0,-1.0)';
    'TEST4_CCD6':
      PIN_NUMBER='(0,0,0,0,0,0,0,0,0,0,0,0,0,0,0,0,0,0,0,CJ50,0,0,0,0,0,0,0,0,0,0,0,0,0,0,0,0,0,0,0,0)';
      OUTPUT_TYPE='(TS,TS)';
      INPUT_LOAD='(-0.01,0.01)';
      OUTPUT_LOAD='(1.0,-1.0)';
    'TEST47_CCD0':
      PIN_NUMBER='(0,0,0,0,0,0,0,0,0,0,0,0,0,0,0,0,0,0,0,B60,0,0,0,0,0,0,0,0,0,0,0,0,0,0,0,0,0,0,0,0)';
      OUTPUT_TYPE='(TS,TS)';
      INPUT_LOAD='(-0.01,0.01)';
      OUTPUT_LOAD='(1.0,-1.0)';
    'TEST5_CCD8':
      PIN_NUMBER='(0,0,0,0,0,0,0,0,0,0,0,0,0,0,0,0,0,0,0,Y47,0,0,0,0,0,0,0,0,0,0,0,0,0,0,0,0,0,0,0,0)';
      OUTPUT_TYPE='(TS,TS)';
      INPUT_LOAD='(-0.01,0.01)';
      OUTPUT_LOAD='(1.0,-1.0)';
    'TEST50_IOD':
      PIN_NUMBER='(0,0,0,0,0,0,0,0,0,0,0,0,0,0,0,0,0,0,0,B61,0,0,0,0,0,0,0,0,0,0,0,0,0,0,0,0,0,0,0,0)';
      OUTPUT_TYPE='(TS,TS)';
      INPUT_LOAD='(-0.01,0.01)';
      OUTPUT_LOAD='(1.0,-1.0)';
    'TEST4_CCD7':
      PIN_NUMBER='(0,0,0,0,0,0,0,0,0,0,0,0,0,0,0,0,0,0,0,AA27,0,0,0,0,0,0,0,0,0,0,0,0,0,0,0,0,0,0,0,0)';
      OUTPUT_TYPE='(TS,TS)';
      INPUT_LOAD='(-0.01,0.01)';
      OUTPUT_LOAD='(1.0,-1.0)';
    'TEST47_CCD1':
      PIN_NUMBER='(0,0,0,0,0,0,0,0,0,0,0,0,0,0,0,0,0,0,0,CJ24,0,0,0,0,0,0,0,0,0,0,0,0,0,0,0,0,0,0,0,0)';
      OUTPUT_TYPE='(TS,TS)';
      INPUT_LOAD='(-0.01,0.01)';
      OUTPUT_LOAD='(1.0,-1.0)';
    'TEST5_CCD9':
      PIN_NUMBER='(0,0,0,0,0,0,0,0,0,0,0,0,0,0,0,0,0,0,0,CK29,0,0,0,0,0,0,0,0,0,0,0,0,0,0,0,0,0,0,0,0)';
      OUTPUT_TYPE='(TS,TS)';
      INPUT_LOAD='(-0.01,0.01)';
      OUTPUT_LOAD='(1.0,-1.0)';
    'TEST4_CCD8':
      PIN_NUMBER='(0,0,0,0,0,0,0,0,0,0,0,0,0,0,0,0,0,0,0,AA48,0,0,0,0,0,0,0,0,0,0,0,0,0,0,0,0,0,0,0,0)';
      OUTPUT_TYPE='(TS,TS)';
      INPUT_LOAD='(-0.01,0.01)';
      OUTPUT_LOAD='(1.0,-1.0)';
    'TEST47_CCD2':
      PIN_NUMBER='(0,0,0,0,0,0,0,0,0,0,0,0,0,0,0,0,0,0,0,CK46,0,0,0,0,0,0,0,0,0,0,0,0,0,0,0,0,0,0,0,0)';
      OUTPUT_TYPE='(TS,TS)';
      INPUT_LOAD='(-0.01,0.01)';
      OUTPUT_LOAD='(1.0,-1.0)';
    'TEST4_CCD10':
      PIN_NUMBER='(0,0,0,0,0,0,0,0,0,0,0,0,0,0,0,0,0,0,0,CJ47,0,0,0,0,0,0,0,0,0,0,0,0,0,0,0,0,0,0,0,0)';
      OUTPUT_TYPE='(TS,TS)';
      INPUT_LOAD='(-0.01,0.01)';
      OUTPUT_LOAD='(1.0,-1.0)';
    'TEST4_CCD9':
      PIN_NUMBER='(0,0,0,0,0,0,0,0,0,0,0,0,0,0,0,0,0,0,0,CK30,0,0,0,0,0,0,0,0,0,0,0,0,0,0,0,0,0,0,0,0)';
      OUTPUT_TYPE='(TS,TS)';
      INPUT_LOAD='(-0.01,0.01)';
      OUTPUT_LOAD='(1.0,-1.0)';
    'TEST5_CCD10':
      PIN_NUMBER='(0,0,0,0,0,0,0,0,0,0,0,0,0,0,0,0,0,0,0,CK47,0,0,0,0,0,0,0,0,0,0,0,0,0,0,0,0,0,0,0,0)';
      OUTPUT_TYPE='(TS,TS)';
      INPUT_LOAD='(-0.01,0.01)';
      OUTPUT_LOAD='(1.0,-1.0)';
    'TEST4_CCD11':
      PIN_NUMBER='(0,0,0,0,0,0,0,0,0,0,0,0,0,0,0,0,0,0,0,AA28,0,0,0,0,0,0,0,0,0,0,0,0,0,0,0,0,0,0,0,0)';
      OUTPUT_TYPE='(TS,TS)';
      INPUT_LOAD='(-0.01,0.01)';
      OUTPUT_LOAD='(1.0,-1.0)';
    'TEST5_CCD11':
      PIN_NUMBER='(0,0,0,0,0,0,0,0,0,0,0,0,0,0,0,0,0,0,0,Y29,0,0,0,0,0,0,0,0,0,0,0,0,0,0,0,0,0,0,0,0)';
      OUTPUT_TYPE='(TS,TS)';
      INPUT_LOAD='(-0.01,0.01)';
      OUTPUT_LOAD='(1.0,-1.0)';
    'TEST6_X3D0':
      PIN_NUMBER='(0,0,0,0,0,0,0,0,0,0,0,0,0,0,0,0,0,0,0,AA47,0,0,0,0,0,0,0,0,0,0,0,0,0,0,0,0,0,0,0,0)';
      OUTPUT_LOAD='(1.0,-1.0)';
    'TEST47_IOD0':
      PIN_NUMBER='(0,0,0,0,0,0,0,0,0,0,0,0,0,0,0,0,0,0,0,B58,0,0,0,0,0,0,0,0,0,0,0,0,0,0,0,0,0,0,0,0)';
      OUTPUT_TYPE='(TS,TS)';
      INPUT_LOAD='(-0.01,0.01)';
      OUTPUT_LOAD='(1.0,-1.0)';
    'TEST6_X3D1':
      PIN_NUMBER='(0,0,0,0,0,0,0,0,0,0,0,0,0,0,0,0,0,0,0,CJ29,0,0,0,0,0,0,0,0,0,0,0,0,0,0,0,0,0,0,0,0)';
      OUTPUT_LOAD='(1.0,-1.0)';
    'TEST47_IOD1':
      PIN_NUMBER='(0,0,0,0,0,0,0,0,0,0,0,0,0,0,0,0,0,0,0,D7,0,0,0,0,0,0,0,0,0,0,0,0,0,0,0,0,0,0,0,0)';
      OUTPUT_TYPE='(TS,TS)';
      INPUT_LOAD='(-0.01,0.01)';
      OUTPUT_LOAD='(1.0,-1.0)';
    'TEST6_X3D2':
      PIN_NUMBER='(0,0,0,0,0,0,0,0,0,0,0,0,0,0,0,0,0,0,0,AA29,0,0,0,0,0,0,0,0,0,0,0,0,0,0,0,0,0,0,0,0)';
      OUTPUT_LOAD='(1.0,-1.0)';
    'TEST6_X3D3':
      PIN_NUMBER='(0,0,0,0,0,0,0,0,0,0,0,0,0,0,0,0,0,0,0,CJ52,0,0,0,0,0,0,0,0,0,0,0,0,0,0,0,0,0,0,0,0)';
      OUTPUT_LOAD='(1.0,-1.0)';
    'TEST6_CCD0':
      PIN_NUMBER='(0,0,0,0,0,0,0,0,0,0,0,0,0,0,0,0,0,0,0,AA46,0,0,0,0,0,0,0,0,0,0,0,0,0,0,0,0,0,0,0,0)';
      OUTPUT_LOAD='(1.0,-1.0)';
    'TEST47_CCD3':
      PIN_NUMBER='(0,0,0,0,0,0,0,0,0,0,0,0,0,0,0,0,0,0,0,E32,0,0,0,0,0,0,0,0,0,0,0,0,0,0,0,0,0,0,0,0)';
      OUTPUT_TYPE='(TS,TS)';
      INPUT_LOAD='(-0.01,0.01)';
      OUTPUT_LOAD='(1.0,-1.0)';
    'TEST41_IOD':
      PIN_NUMBER='(0,0,0,0,0,0,0,0,0,0,0,0,0,0,0,0,0,0,0,W31,0,0,0,0,0,0,0,0,0,0,0,0,0,0,0,0,0,0,0,0)';
      OUTPUT_TYPE='(TS,TS)';
      INPUT_LOAD='(-0.01,0.01)';
      OUTPUT_LOAD='(1.0,-1.0)';
    'BP0':
      PIN_NUMBER='(0,0,0,0,0,0,0,0,0,0,0,0,0,0,0,0,0,0,0,C63,0,0,0,0,0,0,0,0,0,0,0,0,0,0,0,0,0,0,0,0)';
      OUTPUT_LOAD='(1.0,-1.0)';
    'BP1':
      PIN_NUMBER='(0,0,0,0,0,0,0,0,0,0,0,0,0,0,0,0,0,0,0,C62,0,0,0,0,0,0,0,0,0,0,0,0,0,0,0,0,0,0,0,0)';
      OUTPUT_LOAD='(1.0,-1.0)';
    'BP2':
      PIN_NUMBER='(0,0,0,0,0,0,0,0,0,0,0,0,0,0,0,0,0,0,0,A63,0,0,0,0,0,0,0,0,0,0,0,0,0,0,0,0,0,0,0,0)';
      OUTPUT_LOAD='(1.0,-1.0)';
    'BP3':
      PIN_NUMBER='(0,0,0,0,0,0,0,0,0,0,0,0,0,0,0,0,0,0,0,A62,0,0,0,0,0,0,0,0,0,0,0,0,0,0,0,0,0,0,0,0)';
      OUTPUT_LOAD='(1.0,-1.0)';
    'CORETYPE2':
      PIN_NUMBER='(0,0,0,0,0,0,0,0,0,0,0,0,0,0,0,0,0,0,0,D68,0,0,0,0,0,0,0,0,0,0,0,0,0,0,0,0,0,0,0,0)';
      OUTPUT_LOAD='(1.0,-1.0)';
    'PWR_GOOD':
      PIN_NUMBER='(0,0,0,0,0,0,0,0,0,0,0,0,0,0,0,0,0,0,0,0,DJ8,0,0,0,0,0,0,0,0,0,0,0,0,0,0,0,0,0,0,0)';
      INPUT_LOAD='(-0.01,0.01)';
    'RSMRST_L':
      PIN_NUMBER='(0,0,0,0,0,0,0,0,0,0,0,0,0,0,0,0,0,0,0,0,DG10,0,0,0,0,0,0,0,0,0,0,0,0,0,0,0,0,0,0,0)';
      INPUT_LOAD='(-0.01,0.01)';
    'SLP_S3_L':
      PIN_NUMBER='(0,0,0,0,0,0,0,0,0,0,0,0,0,0,0,0,0,0,0,0,DJ5,0,0,0,0,0,0,0,0,0,0,0,0,0,0,0,0,0,0,0)';
      OUTPUT_LOAD='(1.0,-1.0)';
    'SLP_S5_L':
      PIN_NUMBER='(0,0,0,0,0,0,0,0,0,0,0,0,0,0,0,0,0,0,0,0,DG4,0,0,0,0,0,0,0,0,0,0,0,0,0,0,0,0,0,0,0)';
      OUTPUT_LOAD='(1.0,-1.0)';
    'SYS_RESET_L||AGPIO1':
      PIN_NUMBER='(0,0,0,0,0,0,0,0,0,0,0,0,0,0,0,0,0,0,0,0,DH6,0,0,0,0,0,0,0,0,0,0,0,0,0,0,0,0,0,0,0)';
      BIDIRECTIONAL='TRUE';
      INPUT_LOAD='(-0.01,0.01)';
      OUTPUT_LOAD='(1.0,-1.0)';
    'WAKE_L||AGPIO2':
      PIN_NUMBER='(0,0,0,0,0,0,0,0,0,0,0,0,0,0,0,0,0,0,0,0,DJ10,0,0,0,0,0,0,0,0,0,0,0,0,0,0,0,0,0,0,0)';
      BIDIRECTIONAL='TRUE';
      INPUT_LOAD='(-0.01,0.01)';
      OUTPUT_LOAD='(1.0,-1.0)';
    'X32K_X1':
      PIN_NUMBER='(0,0,0,0,0,0,0,0,0,0,0,0,0,0,0,0,0,0,0,0,DJ14,0,0,0,0,0,0,0,0,0,0,0,0,0,0,0,0,0,0,0)';
      INPUT_LOAD='(-0.01,0.01)';
    'X32K_X2':
      PIN_NUMBER='(0,0,0,0,0,0,0,0,0,0,0,0,0,0,0,0,0,0,0,0,DJ13,0,0,0,0,0,0,0,0,0,0,0,0,0,0,0,0,0,0,0)';
      INPUT_LOAD='(-0.01,0.01)';
    'X48M_X1':
      PIN_NUMBER='(0,0,0,0,0,0,0,0,0,0,0,0,0,0,0,0,0,0,0,0,DJ17,0,0,0,0,0,0,0,0,0,0,0,0,0,0,0,0,0,0,0)';
      INPUT_LOAD='(-0.01,0.01)';
    'X48M_X2':
      PIN_NUMBER='(0,0,0,0,0,0,0,0,0,0,0,0,0,0,0,0,0,0,0,0,DJ16,0,0,0,0,0,0,0,0,0,0,0,0,0,0,0,0,0,0,0)';
      INPUT_LOAD='(-0.01,0.01)';
    'PWR_BTN_L||AGPIO0':
      PIN_NUMBER='(0,0,0,0,0,0,0,0,0,0,0,0,0,0,0,0,0,0,0,0,DH7,0,0,0,0,0,0,0,0,0,0,0,0,0,0,0,0,0,0,0)';
      BIDIRECTIONAL='TRUE';
      INPUT_LOAD='(-0.01,0.01)';
      OUTPUT_LOAD='(1.0,-1.0)';
    'NV_SAVE_L':
      PIN_NUMBER='(0,0,0,0,0,0,0,0,0,0,0,0,0,0,0,0,0,0,0,0,B64,0,0,0,0,0,0,0,0,0,0,0,0,0,0,0,0,0,0,0)';
      OUTPUT_LOAD='(1.0,-1.0)';
    'FORCE_SELFREFRESH':
      PIN_NUMBER='(0,0,0,0,0,0,0,0,0,0,0,0,0,0,0,0,0,0,0,0,B63,0,0,0,0,0,0,0,0,0,0,0,0,0,0,0,0,0,0,0)';
      INPUT_LOAD='(-0.01,0.01)';
    'RTCCLK':
      PIN_NUMBER='(0,0,0,0,0,0,0,0,0,0,0,0,0,0,0,0,0,0,0,0,DH9,0,0,0,0,0,0,0,0,0,0,0,0,0,0,0,0,0,0,0)';
      BIDIRECTIONAL='TRUE';
      INPUT_LOAD='(-0.01,0.01)';
      OUTPUT_LOAD='(1.0,-1.0)';
    'GPP_CLK05N':
      PIN_NUMBER='(0,0,0,0,0,0,0,0,0,0,0,0,0,0,0,0,0,0,0,0,C9,0,0,0,0,0,0,0,0,0,0,0,0,0,0,0,0,0,0,0)';
      OUTPUT_LOAD='(1.0,-1.0)';
    'GPP_CLK15N':
      PIN_NUMBER='(0,0,0,0,0,0,0,0,0,0,0,0,0,0,0,0,0,0,0,0,DJ50,0,0,0,0,0,0,0,0,0,0,0,0,0,0,0,0,0,0,0)';
      OUTPUT_LOAD='(1.0,-1.0)';
    'GPP_CLK04N':
      PIN_NUMBER='(0,0,0,0,0,0,0,0,0,0,0,0,0,0,0,0,0,0,0,0,C12,0,0,0,0,0,0,0,0,0,0,0,0,0,0,0,0,0,0,0)';
      OUTPUT_LOAD='(1.0,-1.0)';
    'GPP_CLK14N':
      PIN_NUMBER='(0,0,0,0,0,0,0,0,0,0,0,0,0,0,0,0,0,0,0,0,DJ47,0,0,0,0,0,0,0,0,0,0,0,0,0,0,0,0,0,0,0)';
      OUTPUT_LOAD='(1.0,-1.0)';
    'GPP_CLK05P':
      PIN_NUMBER='(0,0,0,0,0,0,0,0,0,0,0,0,0,0,0,0,0,0,0,0,B9,0,0,0,0,0,0,0,0,0,0,0,0,0,0,0,0,0,0,0)';
      OUTPUT_LOAD='(1.0,-1.0)';
    'GPP_CLK03N':
      PIN_NUMBER='(0,0,0,0,0,0,0,0,0,0,0,0,0,0,0,0,0,0,0,0,A11,0,0,0,0,0,0,0,0,0,0,0,0,0,0,0,0,0,0,0)';
      OUTPUT_LOAD='(1.0,-1.0)';
    'GPP_CLK15P':
      PIN_NUMBER='(0,0,0,0,0,0,0,0,0,0,0,0,0,0,0,0,0,0,0,0,DJ51,0,0,0,0,0,0,0,0,0,0,0,0,0,0,0,0,0,0,0)';
      OUTPUT_LOAD='(1.0,-1.0)';
    'GPP_CLK13N':
      PIN_NUMBER='(0,0,0,0,0,0,0,0,0,0,0,0,0,0,0,0,0,0,0,0,DJ54,0,0,0,0,0,0,0,0,0,0,0,0,0,0,0,0,0,0,0)';
      OUTPUT_LOAD='(1.0,-1.0)';
    'GPP_CLK04P':
      PIN_NUMBER='(0,0,0,0,0,0,0,0,0,0,0,0,0,0,0,0,0,0,0,0,B12,0,0,0,0,0,0,0,0,0,0,0,0,0,0,0,0,0,0,0)';
      OUTPUT_LOAD='(1.0,-1.0)';
    'GPP_CLK02N':
      PIN_NUMBER='(0,0,0,0,0,0,0,0,0,0,0,0,0,0,0,0,0,0,0,0,C6,0,0,0,0,0,0,0,0,0,0,0,0,0,0,0,0,0,0,0)';
      OUTPUT_LOAD='(1.0,-1.0)';
    'GPP_CLK14P':
      PIN_NUMBER='(0,0,0,0,0,0,0,0,0,0,0,0,0,0,0,0,0,0,0,0,DJ48,0,0,0,0,0,0,0,0,0,0,0,0,0,0,0,0,0,0,0)';
      OUTPUT_LOAD='(1.0,-1.0)';
    'GPP_CLK12N':
      PIN_NUMBER='(0,0,0,0,0,0,0,0,0,0,0,0,0,0,0,0,0,0,0,0,DJ44,0,0,0,0,0,0,0,0,0,0,0,0,0,0,0,0,0,0,0)';
      OUTPUT_LOAD='(1.0,-1.0)';
    'GPP_CLK03P':
      PIN_NUMBER='(0,0,0,0,0,0,0,0,0,0,0,0,0,0,0,0,0,0,0,0,A10,0,0,0,0,0,0,0,0,0,0,0,0,0,0,0,0,0,0,0)';
      OUTPUT_LOAD='(1.0,-1.0)';
    'GPP_CLK01N':
      PIN_NUMBER='(0,0,0,0,0,0,0,0,0,0,0,0,0,0,0,0,0,0,0,0,A7,0,0,0,0,0,0,0,0,0,0,0,0,0,0,0,0,0,0,0)';
      OUTPUT_LOAD='(1.0,-1.0)';
    'GPP_CLK13P':
      PIN_NUMBER='(0,0,0,0,0,0,0,0,0,0,0,0,0,0,0,0,0,0,0,0,DJ53,0,0,0,0,0,0,0,0,0,0,0,0,0,0,0,0,0,0,0)';
      OUTPUT_LOAD='(1.0,-1.0)';
    'GPP_CLK11N':
      PIN_NUMBER='(0,0,0,0,0,0,0,0,0,0,0,0,0,0,0,0,0,0,0,0,DJ42,0,0,0,0,0,0,0,0,0,0,0,0,0,0,0,0,0,0,0)';
      OUTPUT_LOAD='(1.0,-1.0)';
    'GPP_CLK02P':
      PIN_NUMBER='(0,0,0,0,0,0,0,0,0,0,0,0,0,0,0,0,0,0,0,0,B6,0,0,0,0,0,0,0,0,0,0,0,0,0,0,0,0,0,0,0)';
      OUTPUT_LOAD='(1.0,-1.0)';
    'GPP_CLK12P':
      PIN_NUMBER='(0,0,0,0,0,0,0,0,0,0,0,0,0,0,0,0,0,0,0,0,DJ45,0,0,0,0,0,0,0,0,0,0,0,0,0,0,0,0,0,0,0)';
      OUTPUT_LOAD='(1.0,-1.0)';
    'GPP_CLK01P':
      PIN_NUMBER='(0,0,0,0,0,0,0,0,0,0,0,0,0,0,0,0,0,0,0,0,A8,0,0,0,0,0,0,0,0,0,0,0,0,0,0,0,0,0,0,0)';
      OUTPUT_LOAD='(1.0,-1.0)';
    'GPP_CLK11P':
      PIN_NUMBER='(0,0,0,0,0,0,0,0,0,0,0,0,0,0,0,0,0,0,0,0,DJ41,0,0,0,0,0,0,0,0,0,0,0,0,0,0,0,0,0,0,0)';
      OUTPUT_LOAD='(1.0,-1.0)';
    'AGPIO4||SATA_ACT_L':
      PIN_NUMBER='(0,0,0,0,0,0,0,0,0,0,0,0,0,0,0,0,0,0,0,0,DF36,0,0,0,0,0,0,0,0,0,0,0,0,0,0,0,0,0,0,0)';
      BIDIRECTIONAL='TRUE';
      INPUT_LOAD='(-0.01,0.01)';
      OUTPUT_LOAD='(1.0,-1.0)';
    'AGPIO3||SPD_HOST_CTRL_L':
      PIN_NUMBER='(0,0,0,0,0,0,0,0,0,0,0,0,0,0,0,0,0,0,0,0,DE36,0,0,0,0,0,0,0,0,0,0,0,0,0,0,0,0,0,0,0)';
      BIDIRECTIONAL='TRUE';
      INPUT_LOAD='(-0.01,0.01)';
      OUTPUT_LOAD='(1.0,-1.0)';
    'PCIE_RST1_L||AGPIO26':
      PIN_NUMBER='(0,0,0,0,0,0,0,0,0,0,0,0,0,0,0,0,0,0,0,0,DG36,0,0,0,0,0,0,0,0,0,0,0,0,0,0,0,0,0,0,0)';
      BIDIRECTIONAL='TRUE';
      INPUT_LOAD='(-0.01,0.01)';
      OUTPUT_LOAD='(1.0,-1.0)';
    'SGPIO_LOAD||AGPIO261':
      PIN_NUMBER='(0,0,0,0,0,0,0,0,0,0,0,0,0,0,0,0,0,0,0,0,B15,0,0,0,0,0,0,0,0,0,0,0,0,0,0,0,0,0,0,0)';
      BIDIRECTIONAL='TRUE';
      INPUT_LOAD='(-0.01,0.01)';
      OUTPUT_LOAD='(1.0,-1.0)';
    'I3C2_SDA||I2C2_SDA||SPD2_SDA||AGPIO150':
      PIN_NUMBER='(0,0,0,0,0,0,0,0,0,0,0,0,0,0,0,0,0,0,0,0,B72,0,0,0,0,0,0,0,0,0,0,0,0,0,0,0,0,0,0,0)';
      BIDIRECTIONAL='TRUE';
      INPUT_LOAD='(-0.01,0.01)';
      OUTPUT_LOAD='(1.0,-1.0)';
    'SGPIO_DATAOUT||AGPIO260':
      PIN_NUMBER='(0,0,0,0,0,0,0,0,0,0,0,0,0,0,0,0,0,0,0,0,D15,0,0,0,0,0,0,0,0,0,0,0,0,0,0,0,0,0,0,0)';
      BIDIRECTIONAL='TRUE';
      INPUT_LOAD='(-0.01,0.01)';
      OUTPUT_LOAD='(1.0,-1.0)';
    'I3C3_SDA||I2C3_SDA||SPD3_SDA||AGPIO152':
      PIN_NUMBER='(0,0,0,0,0,0,0,0,0,0,0,0,0,0,0,0,0,0,0,0,B4,0,0,0,0,0,0,0,0,0,0,0,0,0,0,0,0,0,0,0)';
      BIDIRECTIONAL='TRUE';
      INPUT_LOAD='(-0.01,0.01)';
      OUTPUT_LOAD='(1.0,-1.0)';
    'AGPIO258||SGPIO2_CLK||CLK_REQ02_L':
      PIN_NUMBER='(0,0,0,0,0,0,0,0,0,0,0,0,0,0,0,0,0,0,0,0,A13,0,0,0,0,0,0,0,0,0,0,0,0,0,0,0,0,0,0,0)';
      BIDIRECTIONAL='TRUE';
      INPUT_LOAD='(-0.01,0.01)';
      OUTPUT_LOAD='(1.0,-1.0)';
    'AGPIO256||SGPIO0_CLK':
      PIN_NUMBER='(0,0,0,0,0,0,0,0,0,0,0,0,0,0,0,0,0,0,0,0,A14,0,0,0,0,0,0,0,0,0,0,0,0,0,0,0,0,0,0,0)';
      BIDIRECTIONAL='TRUE';
      INPUT_LOAD='(-0.01,0.01)';
      OUTPUT_LOAD='(1.0,-1.0)';
    'PCIE_RST0_L||AGPIO266':
      PIN_NUMBER='(0,0,0,0,0,0,0,0,0,0,0,0,0,0,0,0,0,0,0,0,D18,0,0,0,0,0,0,0,0,0,0,0,0,0,0,0,0,0,0,0)';
      BIDIRECTIONAL='TRUE';
      INPUT_LOAD='(-0.01,0.01)';
      OUTPUT_LOAD='(1.0,-1.0)';
    'AGPIO115||CLK_REQ11_L':
      PIN_NUMBER='(0,0,0,0,0,0,0,0,0,0,0,0,0,0,0,0,0,0,0,0,DH16,0,0,0,0,0,0,0,0,0,0,0,0,0,0,0,0,0,0,0)';
      BIDIRECTIONAL='TRUE';
      INPUT_LOAD='(-0.01,0.01)';
      OUTPUT_LOAD='(1.0,-1.0)';
    'I3C0_SDA||I2C0_SDA||SPD0_SDA||SMBUS0_SDA||AGPIO146':
      PIN_NUMBER='(0,0,0,0,0,0,0,0,0,0,0,0,0,0,0,0,0,0,0,0,B71,0,0,0,0,0,0,0,0,0,0,0,0,0,0,0,0,0,0,0)';
      BIDIRECTIONAL='TRUE';
      INPUT_LOAD='(-0.01,0.01)';
      OUTPUT_LOAD='(1.0,-1.0)';
    'I3C1_SCL||I2C1_SCL||SPD1_SCL||AGPIO147':
      PIN_NUMBER='(0,0,0,0,0,0,0,0,0,0,0,0,0,0,0,0,0,0,0,0,C7,0,0,0,0,0,0,0,0,0,0,0,0,0,0,0,0,0,0,0)';
      BIDIRECTIONAL='TRUE';
      INPUT_LOAD='(-0.01,0.01)';
      OUTPUT_LOAD='(1.0,-1.0)';
    'I3C2_SCL||I2C2_SCL||SPD2_SCL||AGPIO149':
      PIN_NUMBER='(0,0,0,0,0,0,0,0,0,0,0,0,0,0,0,0,0,0,0,0,C72,0,0,0,0,0,0,0,0,0,0,0,0,0,0,0,0,0,0,0)';
      BIDIRECTIONAL='TRUE';
      INPUT_LOAD='(-0.01,0.01)';
      OUTPUT_LOAD='(1.0,-1.0)';
    'I3C0_SCL||I2C0_SCL||SPD0_SCL||SMBUS0_SCL||AGPIO145':
      PIN_NUMBER='(0,0,0,0,0,0,0,0,0,0,0,0,0,0,0,0,0,0,0,0,A71,0,0,0,0,0,0,0,0,0,0,0,0,0,0,0,0,0,0,0)';
      BIDIRECTIONAL='TRUE';
      INPUT_LOAD='(-0.01,0.01)';
      OUTPUT_LOAD='(1.0,-1.0)';
    'AGPIO259||SGPIO3_CLK':
      PIN_NUMBER='(0,0,0,0,0,0,0,0,0,0,0,0,0,0,0,0,0,0,0,0,B16,0,0,0,0,0,0,0,0,0,0,0,0,0,0,0,0,0,0,0)';
      BIDIRECTIONAL='TRUE';
      INPUT_LOAD='(-0.01,0.01)';
      OUTPUT_LOAD='(1.0,-1.0)';
    'PWRGD_OUT||AGPIO12':
      PIN_NUMBER='(0,0,0,0,0,0,0,0,0,0,0,0,0,0,0,0,0,0,0,0,DH36,0,0,0,0,0,0,0,0,0,0,0,0,0,0,0,0,0,0,0)';
      BIDIRECTIONAL='TRUE';
      INPUT_LOAD='(-0.01,0.01)';
      OUTPUT_LOAD='(1.0,-1.0)';
    'AGPIO116||CLK_REQ12_L':
      PIN_NUMBER='(0,0,0,0,0,0,0,0,0,0,0,0,0,0,0,0,0,0,0,0,DH15,0,0,0,0,0,0,0,0,0,0,0,0,0,0,0,0,0,0,0)';
      BIDIRECTIONAL='TRUE';
      INPUT_LOAD='(-0.01,0.01)';
      OUTPUT_LOAD='(1.0,-1.0)';
    'I3C1_SDA||I2C1_SDA||SPD1_SDA||AGPIO148':
      PIN_NUMBER='(0,0,0,0,0,0,0,0,0,0,0,0,0,0,0,0,0,0,0,0,A5,0,0,0,0,0,0,0,0,0,0,0,0,0,0,0,0,0,0,0)';
      BIDIRECTIONAL='TRUE';
      INPUT_LOAD='(-0.01,0.01)';
      OUTPUT_LOAD='(1.0,-1.0)';
    'I3C3_SCL||I2C3_SCL||SPD3_SCL||AGPIO151':
      PIN_NUMBER='(0,0,0,0,0,0,0,0,0,0,0,0,0,0,0,0,0,0,0,0,A4,0,0,0,0,0,0,0,0,0,0,0,0,0,0,0,0,0,0,0)';
      BIDIRECTIONAL='TRUE';
      INPUT_LOAD='(-0.01,0.01)';
      OUTPUT_LOAD='(1.0,-1.0)';
    'I2C4_SCL||HP_SCL||UBM_SCL||AGPIO13':
      PIN_NUMBER='(0,0,0,0,0,0,0,0,0,0,0,0,0,0,0,0,0,0,0,0,DG12,0,0,0,0,0,0,0,0,0,0,0,0,0,0,0,0,0,0,0)';
      BIDIRECTIONAL='TRUE';
      INPUT_LOAD='(-0.01,0.01)';
      OUTPUT_LOAD='(1.0,-1.0)';
    'I2C4_SDA||HP_SDA||UBM_SDA||AGPIO14':
      PIN_NUMBER='(0,0,0,0,0,0,0,0,0,0,0,0,0,0,0,0,0,0,0,0,DH12,0,0,0,0,0,0,0,0,0,0,0,0,0,0,0,0,0,0,0)';
      BIDIRECTIONAL='TRUE';
      INPUT_LOAD='(-0.01,0.01)';
      OUTPUT_LOAD='(1.0,-1.0)';
    'I2C5_SCL||BMC_SCL||SMBUS1_SCL||AGPIO19':
      PIN_NUMBER='(0,0,0,0,0,0,0,0,0,0,0,0,0,0,0,0,0,0,0,0,DJ21,0,0,0,0,0,0,0,0,0,0,0,0,0,0,0,0,0,0,0)';
      BIDIRECTIONAL='TRUE';
      INPUT_LOAD='(-0.01,0.01)';
      OUTPUT_LOAD='(1.0,-1.0)';
    'I2C5_SDA||BMC_SDA||SMBUS1_SDA||AGPIO20':
      PIN_NUMBER='(0,0,0,0,0,0,0,0,0,0,0,0,0,0,0,0,0,0,0,0,DJ20,0,0,0,0,0,0,0,0,0,0,0,0,0,0,0,0,0,0,0)';
      BIDIRECTIONAL='TRUE';
      INPUT_LOAD='(-0.01,0.01)';
      OUTPUT_LOAD='(1.0,-1.0)';
    'SMERR_L||AGPIO24':
      PIN_NUMBER='(0,0,0,0,0,0,0,0,0,0,0,0,0,0,0,0,0,0,0,0,DJ11,0,0,0,0,0,0,0,0,0,0,0,0,0,0,0,0,0,0,0)';
      BIDIRECTIONAL='TRUE';
      INPUT_LOAD='(-0.01,0.01)';
      OUTPUT_LOAD='(1.0,-1.0)';
    'REFCLK100SSC_P||GPP_CLK10P':
      PIN_NUMBER='(0,0,0,0,0,0,0,0,0,0,0,0,0,0,0,0,0,0,0,0,A19,0,0,0,0,0,0,0,0,0,0,0,0,0,0,0,0,0,0,0)';
      BIDIRECTIONAL='TRUE';
      INPUT_LOAD='(-0.01,0.01)';
      OUTPUT_LOAD='(1.0,-1.0)';
    'REFCLK100SSC_N||GPP_CLK10N':
      PIN_NUMBER='(0,0,0,0,0,0,0,0,0,0,0,0,0,0,0,0,0,0,0,0,A20,0,0,0,0,0,0,0,0,0,0,0,0,0,0,0,0,0,0,0)';
      BIDIRECTIONAL='TRUE';
      INPUT_LOAD='(-0.01,0.01)';
      OUTPUT_LOAD='(1.0,-1.0)';
    'RESET_L':
      PIN_NUMBER='(0,0,0,0,0,0,0,0,0,0,0,0,0,0,0,0,0,0,0,0,B67,0,0,0,0,0,0,0,0,0,0,0,0,0,0,0,0,0,0,0)';
      BIDIRECTIONAL='TRUE';
      INPUT_LOAD='(-0.01,0.01)';
      OUTPUT_LOAD='(1.0,-1.0)';
    'AGPIO104':
      PIN_NUMBER='(0,0,0,0,0,0,0,0,0,0,0,0,0,0,0,0,0,0,0,0,DH30,0,0,0,0,0,0,0,0,0,0,0,0,0,0,0,0,0,0,0)';
      BIDIRECTIONAL='TRUE';
      INPUT_LOAD='(-0.01,0.01)';
      OUTPUT_LOAD='(1.0,-1.0)';
    'AGPIO105':
      PIN_NUMBER='(0,0,0,0,0,0,0,0,0,0,0,0,0,0,0,0,0,0,0,0,DE30,0,0,0,0,0,0,0,0,0,0,0,0,0,0,0,0,0,0,0)';
      BIDIRECTIONAL='TRUE';
      INPUT_LOAD='(-0.01,0.01)';
      OUTPUT_LOAD='(1.0,-1.0)';
    'AGPIO106':
      PIN_NUMBER='(0,0,0,0,0,0,0,0,0,0,0,0,0,0,0,0,0,0,0,0,DF31,0,0,0,0,0,0,0,0,0,0,0,0,0,0,0,0,0,0,0)';
      BIDIRECTIONAL='TRUE';
      INPUT_LOAD='(-0.01,0.01)';
      OUTPUT_LOAD='(1.0,-1.0)';
    'AGPIO107':
      PIN_NUMBER='(0,0,0,0,0,0,0,0,0,0,0,0,0,0,0,0,0,0,0,0,DG31,0,0,0,0,0,0,0,0,0,0,0,0,0,0,0,0,0,0,0)';
      BIDIRECTIONAL='TRUE';
      INPUT_LOAD='(-0.01,0.01)';
      OUTPUT_LOAD='(1.0,-1.0)';
    'AGPIO109':
      PIN_NUMBER='(0,0,0,0,0,0,0,0,0,0,0,0,0,0,0,0,0,0,0,0,DG32,0,0,0,0,0,0,0,0,0,0,0,0,0,0,0,0,0,0,0)';
      BIDIRECTIONAL='TRUE';
      INPUT_LOAD='(-0.01,0.01)';
      OUTPUT_LOAD='(1.0,-1.0)';
    'AGPIO87':
      PIN_NUMBER='(0,0,0,0,0,0,0,0,0,0,0,0,0,0,0,0,0,0,0,0,DG11,0,0,0,0,0,0,0,0,0,0,0,0,0,0,0,0,0,0,0)';
      BIDIRECTIONAL='TRUE';
      INPUT_LOAD='(-0.01,0.01)';
      OUTPUT_LOAD='(1.0,-1.0)';
    'AGPIO21':
      PIN_NUMBER='(0,0,0,0,0,0,0,0,0,0,0,0,0,0,0,0,0,0,0,0,DF33,0,0,0,0,0,0,0,0,0,0,0,0,0,0,0,0,0,0,0)';
      BIDIRECTIONAL='TRUE';
      INPUT_LOAD='(-0.01,0.01)';
      OUTPUT_LOAD='(1.0,-1.0)';
    'AGPIO88':
      PIN_NUMBER='(0,0,0,0,0,0,0,0,0,0,0,0,0,0,0,0,0,0,0,0,DJ29,0,0,0,0,0,0,0,0,0,0,0,0,0,0,0,0,0,0,0)';
      BIDIRECTIONAL='TRUE';
      INPUT_LOAD='(-0.01,0.01)';
      OUTPUT_LOAD='(1.0,-1.0)';
    'AGPIO22':
      PIN_NUMBER='(0,0,0,0,0,0,0,0,0,0,0,0,0,0,0,0,0,0,0,0,DE32,0,0,0,0,0,0,0,0,0,0,0,0,0,0,0,0,0,0,0)';
      BIDIRECTIONAL='TRUE';
      INPUT_LOAD='(-0.01,0.01)';
      OUTPUT_LOAD='(1.0,-1.0)';
    'GENINT_L||PM_INTR_L||UBM_CPRSNT_CHANGE_DET_L||AGPIO89':
      PIN_NUMBER='(0,0,0,0,0,0,0,0,0,0,0,0,0,0,0,0,0,0,0,0,DJ35,0,0,0,0,0,0,0,0,0,0,0,0,0,0,0,0,0,0,0)';
      BIDIRECTIONAL='TRUE';
      INPUT_LOAD='(-0.01,0.01)';
      OUTPUT_LOAD='(1.0,-1.0)';
    'AGPIO5||DEVSLP0||SATA_ZP0_L':
      PIN_NUMBER='(0,0,0,0,0,0,0,0,0,0,0,0,0,0,0,0,0,0,0,0,DF40,0,0,0,0,0,0,0,0,0,0,0,0,0,0,0,0,0,0,0)';
      BIDIRECTIONAL='TRUE';
      INPUT_LOAD='(-0.01,0.01)';
      OUTPUT_LOAD='(1.0,-1.0)';
    'AGPIO6||DEVSLP1||SATA_ZP1_L':
      PIN_NUMBER='(0,0,0,0,0,0,0,0,0,0,0,0,0,0,0,0,0,0,0,0,DE40,0,0,0,0,0,0,0,0,0,0,0,0,0,0,0,0,0,0,0)';
      BIDIRECTIONAL='TRUE';
      INPUT_LOAD='(-0.01,0.01)';
      OUTPUT_LOAD='(1.0,-1.0)';
    'PWROK||SVI_RST_L':
      PIN_NUMBER='(0,0,0,0,0,0,0,0,0,0,0,0,0,0,0,0,0,0,0,0,D69,0,0,0,0,0,0,0,0,0,0,0,0,0,0,0,0,0,0,0)';
      OUTPUT_LOAD='(1.0,-1.0)';
    'AGPIO257||SGPIO1_CLK||CLK_REQ01_L':
      PIN_NUMBER='(0,0,0,0,0,0,0,0,0,0,0,0,0,0,0,0,0,0,0,0,C14,0,0,0,0,0,0,0,0,0,0,0,0,0,0,0,0,0,0,0)';
      BIDIRECTIONAL='TRUE';
      INPUT_LOAD='(-0.01,0.01)';
      OUTPUT_LOAD='(1.0,-1.0)';
    'SEC_SDA||AGPIO263':
      PIN_NUMBER='(0,0,0,0,0,0,0,0,0,0,0,0,0,0,0,0,0,0,0,0,D14,0,0,0,0,0,0,0,0,0,0,0,0,0,0,0,0,0,0,0)';
      BIDIRECTIONAL='TRUE';
      INPUT_LOAD='(-0.01,0.01)';
      OUTPUT_LOAD='(1.0,-1.0)';
    'SEC_SCL||AGPIO262':
      PIN_NUMBER='(0,0,0,0,0,0,0,0,0,0,0,0,0,0,0,0,0,0,0,0,B14,0,0,0,0,0,0,0,0,0,0,0,0,0,0,0,0,0,0,0)';
      BIDIRECTIONAL='TRUE';
      INPUT_LOAD='(-0.01,0.01)';
      OUTPUT_LOAD='(1.0,-1.0)';
    'NMI_SYNC_FLOOD_L':
      PIN_NUMBER='(0,0,0,0,0,0,0,0,0,0,0,0,0,0,0,0,0,0,0,0,DJ31,0,0,0,0,0,0,0,0,0,0,0,0,0,0,0,0,0,0,0)';
      INPUT_LOAD='(-0.01,0.01)';
    'AGPIO7':
      PIN_NUMBER='(0,0,0,0,0,0,0,0,0,0,0,0,0,0,0,0,0,0,0,0,DH4,0,0,0,0,0,0,0,0,0,0,0,0,0,0,0,0,0,0,0)';
      BIDIRECTIONAL='TRUE';
      INPUT_LOAD='(-0.01,0.01)';
      OUTPUT_LOAD='(1.0,-1.0)';
    'USB00_DN':
      PIN_NUMBER='(0,0,0,0,0,0,0,0,0,0,0,0,0,0,0,0,0,0,0,0,0,A25,0,0,0,0,0,0,0,0,0,0,0,0,0,0,0,0,0,0)';
      BIDIRECTIONAL='TRUE';
      INPUT_LOAD='(-0.01,0.01)';
      OUTPUT_LOAD='(1.0,-1.0)';
    'USB00_DP':
      PIN_NUMBER='(0,0,0,0,0,0,0,0,0,0,0,0,0,0,0,0,0,0,0,0,0,A26,0,0,0,0,0,0,0,0,0,0,0,0,0,0,0,0,0,0)';
      BIDIRECTIONAL='TRUE';
      INPUT_LOAD='(-0.01,0.01)';
      OUTPUT_LOAD='(1.0,-1.0)';
    'USB00_RXN':
      PIN_NUMBER='(0,0,0,0,0,0,0,0,0,0,0,0,0,0,0,0,0,0,0,0,0,E26,0,0,0,0,0,0,0,0,0,0,0,0,0,0,0,0,0,0)';
      INPUT_LOAD='(-0.01,0.01)';
    'USB00_RXP':
      PIN_NUMBER='(0,0,0,0,0,0,0,0,0,0,0,0,0,0,0,0,0,0,0,0,0,E27,0,0,0,0,0,0,0,0,0,0,0,0,0,0,0,0,0,0)';
      INPUT_LOAD='(-0.01,0.01)';
    'USB00_TXN':
      PIN_NUMBER='(0,0,0,0,0,0,0,0,0,0,0,0,0,0,0,0,0,0,0,0,0,C26,0,0,0,0,0,0,0,0,0,0,0,0,0,0,0,0,0,0)';
      OUTPUT_LOAD='(1.0,-1.0)';
    'USB00_TXP':
      PIN_NUMBER='(0,0,0,0,0,0,0,0,0,0,0,0,0,0,0,0,0,0,0,0,0,C25,0,0,0,0,0,0,0,0,0,0,0,0,0,0,0,0,0,0)';
      OUTPUT_LOAD='(1.0,-1.0)';
    'USB01_DN':
      PIN_NUMBER='(0,0,0,0,0,0,0,0,0,0,0,0,0,0,0,0,0,0,0,0,0,A29,0,0,0,0,0,0,0,0,0,0,0,0,0,0,0,0,0,0)';
      BIDIRECTIONAL='TRUE';
      INPUT_LOAD='(-0.01,0.01)';
      OUTPUT_LOAD='(1.0,-1.0)';
    'USB01_DP':
      PIN_NUMBER='(0,0,0,0,0,0,0,0,0,0,0,0,0,0,0,0,0,0,0,0,0,A28,0,0,0,0,0,0,0,0,0,0,0,0,0,0,0,0,0,0)';
      BIDIRECTIONAL='TRUE';
      INPUT_LOAD='(-0.01,0.01)';
      OUTPUT_LOAD='(1.0,-1.0)';
    'USB01_RXN':
      PIN_NUMBER='(0,0,0,0,0,0,0,0,0,0,0,0,0,0,0,0,0,0,0,0,0,C28,0,0,0,0,0,0,0,0,0,0,0,0,0,0,0,0,0,0)';
      INPUT_LOAD='(-0.01,0.01)';
    'USB01_RXP':
      PIN_NUMBER='(0,0,0,0,0,0,0,0,0,0,0,0,0,0,0,0,0,0,0,0,0,C29,0,0,0,0,0,0,0,0,0,0,0,0,0,0,0,0,0,0)';
      INPUT_LOAD='(-0.01,0.01)';
    'USB01_TXN':
      PIN_NUMBER='(0,0,0,0,0,0,0,0,0,0,0,0,0,0,0,0,0,0,0,0,0,E29,0,0,0,0,0,0,0,0,0,0,0,0,0,0,0,0,0,0)';
      OUTPUT_LOAD='(1.0,-1.0)';
    'USB01_TXP':
      PIN_NUMBER='(0,0,0,0,0,0,0,0,0,0,0,0,0,0,0,0,0,0,0,0,0,E30,0,0,0,0,0,0,0,0,0,0,0,0,0,0,0,0,0,0)';
      OUTPUT_LOAD='(1.0,-1.0)';
    'USB10_DN':
      PIN_NUMBER='(0,0,0,0,0,0,0,0,0,0,0,0,0,0,0,0,0,0,0,0,0,DH67,0,0,0,0,0,0,0,0,0,0,0,0,0,0,0,0,0,0)';
      BIDIRECTIONAL='TRUE';
      INPUT_LOAD='(-0.01,0.01)';
      OUTPUT_LOAD='(1.0,-1.0)';
    'USB10_DP':
      PIN_NUMBER='(0,0,0,0,0,0,0,0,0,0,0,0,0,0,0,0,0,0,0,0,0,DJ67,0,0,0,0,0,0,0,0,0,0,0,0,0,0,0,0,0,0)';
      BIDIRECTIONAL='TRUE';
      INPUT_LOAD='(-0.01,0.01)';
      OUTPUT_LOAD='(1.0,-1.0)';
    'USB10_RXN':
      PIN_NUMBER='(0,0,0,0,0,0,0,0,0,0,0,0,0,0,0,0,0,0,0,0,0,DH65,0,0,0,0,0,0,0,0,0,0,0,0,0,0,0,0,0,0)';
      INPUT_LOAD='(-0.01,0.01)';
    'USB10_RXP':
      PIN_NUMBER='(0,0,0,0,0,0,0,0,0,0,0,0,0,0,0,0,0,0,0,0,0,DJ65,0,0,0,0,0,0,0,0,0,0,0,0,0,0,0,0,0,0)';
      INPUT_LOAD='(-0.01,0.01)';
    'USB10_TXN':
      PIN_NUMBER='(0,0,0,0,0,0,0,0,0,0,0,0,0,0,0,0,0,0,0,0,0,DJ69,0,0,0,0,0,0,0,0,0,0,0,0,0,0,0,0,0,0)';
      OUTPUT_LOAD='(1.0,-1.0)';
    'USB10_TXP':
      PIN_NUMBER='(0,0,0,0,0,0,0,0,0,0,0,0,0,0,0,0,0,0,0,0,0,DH69,0,0,0,0,0,0,0,0,0,0,0,0,0,0,0,0,0,0)';
      OUTPUT_LOAD='(1.0,-1.0)';
    'USB11_DN':
      PIN_NUMBER='(0,0,0,0,0,0,0,0,0,0,0,0,0,0,0,0,0,0,0,0,0,DJ60,0,0,0,0,0,0,0,0,0,0,0,0,0,0,0,0,0,0)';
      BIDIRECTIONAL='TRUE';
      INPUT_LOAD='(-0.01,0.01)';
      OUTPUT_LOAD='(1.0,-1.0)';
    'USB11_DP':
      PIN_NUMBER='(0,0,0,0,0,0,0,0,0,0,0,0,0,0,0,0,0,0,0,0,0,DH60,0,0,0,0,0,0,0,0,0,0,0,0,0,0,0,0,0,0)';
      BIDIRECTIONAL='TRUE';
      INPUT_LOAD='(-0.01,0.01)';
      OUTPUT_LOAD='(1.0,-1.0)';
    'USB11_RXN':
      PIN_NUMBER='(0,0,0,0,0,0,0,0,0,0,0,0,0,0,0,0,0,0,0,0,0,DH62,0,0,0,0,0,0,0,0,0,0,0,0,0,0,0,0,0,0)';
      INPUT_LOAD='(-0.01,0.01)';
    'USB11_RXP':
      PIN_NUMBER='(0,0,0,0,0,0,0,0,0,0,0,0,0,0,0,0,0,0,0,0,0,DJ62,0,0,0,0,0,0,0,0,0,0,0,0,0,0,0,0,0,0)';
      INPUT_LOAD='(-0.01,0.01)';
    'USB11_TXN':
      PIN_NUMBER='(0,0,0,0,0,0,0,0,0,0,0,0,0,0,0,0,0,0,0,0,0,DH58,0,0,0,0,0,0,0,0,0,0,0,0,0,0,0,0,0,0)';
      OUTPUT_LOAD='(1.0,-1.0)';
    'USB11_TXP':
      PIN_NUMBER='(0,0,0,0,0,0,0,0,0,0,0,0,0,0,0,0,0,0,0,0,0,DG58,0,0,0,0,0,0,0,0,0,0,0,0,0,0,0,0,0,0)';
      OUTPUT_LOAD='(1.0,-1.0)';
    'USB10_OC_L||AGPIO16':
      PIN_NUMBER='(0,0,0,0,0,0,0,0,0,0,0,0,0,0,0,0,0,0,0,0,0,DG40,0,0,0,0,0,0,0,0,0,0,0,0,0,0,0,0,0,0)';
      BIDIRECTIONAL='TRUE';
      INPUT_LOAD='(-0.01,0.01)';
      OUTPUT_LOAD='(1.0,-1.0)';
    'USB11_OC_L||AGPIO17':
      PIN_NUMBER='(0,0,0,0,0,0,0,0,0,0,0,0,0,0,0,0,0,0,0,0,0,DH40,0,0,0,0,0,0,0,0,0,0,0,0,0,0,0,0,0,0)';
      BIDIRECTIONAL='TRUE';
      INPUT_LOAD='(-0.01,0.01)';
      OUTPUT_LOAD='(1.0,-1.0)';
    'ESPI_CS0_L||AGPIO124':
      PIN_NUMBER='(0,0,0,0,0,0,0,0,0,0,0,0,0,0,0,0,0,0,0,0,0,DG28,0,0,0,0,0,0,0,0,0,0,0,0,0,0,0,0,0,0)';
      BIDIRECTIONAL='TRUE';
      INPUT_LOAD='(-0.01,0.01)';
      OUTPUT_LOAD='(1.0,-1.0)';
    'USB00_OC_L||AGPIO264':
      PIN_NUMBER='(0,0,0,0,0,0,0,0,0,0,0,0,0,0,0,0,0,0,0,0,0,E23,0,0,0,0,0,0,0,0,0,0,0,0,0,0,0,0,0,0)';
      BIDIRECTIONAL='TRUE';
      INPUT_LOAD='(-0.01,0.01)';
      OUTPUT_LOAD='(1.0,-1.0)';
    'SPI_CS0_L||AGPIO118':
      PIN_NUMBER='(0,0,0,0,0,0,0,0,0,0,0,0,0,0,0,0,0,0,0,0,0,DF30,0,0,0,0,0,0,0,0,0,0,0,0,0,0,0,0,0,0)';
      BIDIRECTIONAL='TRUE';
      INPUT_LOAD='(-0.01,0.01)';
      OUTPUT_LOAD='(1.0,-1.0)';
    'ESPI1_DAT1||SPI1_DAT1||AGPIO132':
      PIN_NUMBER='(0,0,0,0,0,0,0,0,0,0,0,0,0,0,0,0,0,0,0,0,0,DE24,0,0,0,0,0,0,0,0,0,0,0,0,0,0,0,0,0,0)';
      BIDIRECTIONAL='TRUE';
      INPUT_LOAD='(-0.01,0.01)';
      OUTPUT_LOAD='(1.0,-1.0)';
    'ESPI1_DAT0||SPI1_DAT0||AGPIO131':
      PIN_NUMBER='(0,0,0,0,0,0,0,0,0,0,0,0,0,0,0,0,0,0,0,0,0,DH24,0,0,0,0,0,0,0,0,0,0,0,0,0,0,0,0,0,0)';
      BIDIRECTIONAL='TRUE';
      INPUT_LOAD='(-0.01,0.01)';
      OUTPUT_LOAD='(1.0,-1.0)';
    'ESPI_CS1_L||AGPIO125':
      PIN_NUMBER='(0,0,0,0,0,0,0,0,0,0,0,0,0,0,0,0,0,0,0,0,0,DJ23,0,0,0,0,0,0,0,0,0,0,0,0,0,0,0,0,0,0)';
      BIDIRECTIONAL='TRUE';
      INPUT_LOAD='(-0.01,0.01)';
      OUTPUT_LOAD='(1.0,-1.0)';
    'ESPI1_DAT3||SPI1_DAT3||AGPIO134':
      PIN_NUMBER='(0,0,0,0,0,0,0,0,0,0,0,0,0,0,0,0,0,0,0,0,0,DG25,0,0,0,0,0,0,0,0,0,0,0,0,0,0,0,0,0,0)';
      BIDIRECTIONAL='TRUE';
      INPUT_LOAD='(-0.01,0.01)';
      OUTPUT_LOAD='(1.0,-1.0)';
    'ESPI1_DAT2||SPI1_DAT2||AGPIO133':
      PIN_NUMBER='(0,0,0,0,0,0,0,0,0,0,0,0,0,0,0,0,0,0,0,0,0,DF25,0,0,0,0,0,0,0,0,0,0,0,0,0,0,0,0,0,0)';
      BIDIRECTIONAL='TRUE';
      INPUT_LOAD='(-0.01,0.01)';
      OUTPUT_LOAD='(1.0,-1.0)';
    'ESPI0_DAT3||SPI0_DAT3||AGPIO123':
      PIN_NUMBER='(0,0,0,0,0,0,0,0,0,0,0,0,0,0,0,0,0,0,0,0,0,DG29,0,0,0,0,0,0,0,0,0,0,0,0,0,0,0,0,0,0)';
      BIDIRECTIONAL='TRUE';
      INPUT_LOAD='(-0.01,0.01)';
      OUTPUT_LOAD='(1.0,-1.0)';
    'ESPI0_DAT2||SPI0_DAT2||AGPIO122':
      PIN_NUMBER='(0,0,0,0,0,0,0,0,0,0,0,0,0,0,0,0,0,0,0,0,0,DJ28,0,0,0,0,0,0,0,0,0,0,0,0,0,0,0,0,0,0)';
      BIDIRECTIONAL='TRUE';
      INPUT_LOAD='(-0.01,0.01)';
      OUTPUT_LOAD='(1.0,-1.0)';
    'ESPI0_DAT1||SPI0_DAT1||AGPIO121':
      PIN_NUMBER='(0,0,0,0,0,0,0,0,0,0,0,0,0,0,0,0,0,0,0,0,0,DG22,0,0,0,0,0,0,0,0,0,0,0,0,0,0,0,0,0,0)';
      BIDIRECTIONAL='TRUE';
      INPUT_LOAD='(-0.01,0.01)';
      OUTPUT_LOAD='(1.0,-1.0)';
    'ESPI0_DAT0||SPI0_DAT0||AGPIO120':
      PIN_NUMBER='(0,0,0,0,0,0,0,0,0,0,0,0,0,0,0,0,0,0,0,0,0,DF28,0,0,0,0,0,0,0,0,0,0,0,0,0,0,0,0,0,0)';
      BIDIRECTIONAL='TRUE';
      INPUT_LOAD='(-0.01,0.01)';
      OUTPUT_LOAD='(1.0,-1.0)';
    'SPI_CS2_L||AGPIO126':
      PIN_NUMBER='(0,0,0,0,0,0,0,0,0,0,0,0,0,0,0,0,0,0,0,0,0,DH27,0,0,0,0,0,0,0,0,0,0,0,0,0,0,0,0,0,0)';
      BIDIRECTIONAL='TRUE';
      INPUT_LOAD='(-0.01,0.01)';
      OUTPUT_LOAD='(1.0,-1.0)';
    'SPI_CS1_L||AGPIO119':
      PIN_NUMBER='(0,0,0,0,0,0,0,0,0,0,0,0,0,0,0,0,0,0,0,0,0,DG26,0,0,0,0,0,0,0,0,0,0,0,0,0,0,0,0,0,0)';
      BIDIRECTIONAL='TRUE';
      INPUT_LOAD='(-0.01,0.01)';
      OUTPUT_LOAD='(1.0,-1.0)';
    'USB01_OC_L||AGPIO265':
      PIN_NUMBER='(0,0,0,0,0,0,0,0,0,0,0,0,0,0,0,0,0,0,0,0,0,E24,0,0,0,0,0,0,0,0,0,0,0,0,0,0,0,0,0,0)';
      BIDIRECTIONAL='TRUE';
      INPUT_LOAD='(-0.01,0.01)';
      OUTPUT_LOAD='(1.0,-1.0)';
    'ESPI_RSTIN_L||KBRST_L||AGPIO129':
      PIN_NUMBER='(0,0,0,0,0,0,0,0,0,0,0,0,0,0,0,0,0,0,0,0,0,DJ26,0,0,0,0,0,0,0,0,0,0,0,0,0,0,0,0,0,0)';
      BIDIRECTIONAL='TRUE';
      INPUT_LOAD='(-0.01,0.01)';
      OUTPUT_LOAD='(1.0,-1.0)';
    'ESPI1_ALERT_L||AGPIO110':
      PIN_NUMBER='(0,0,0,0,0,0,0,0,0,0,0,0,0,0,0,0,0,0,0,0,0,DF24,0,0,0,0,0,0,0,0,0,0,0,0,0,0,0,0,0,0)';
      BIDIRECTIONAL='TRUE';
      INPUT_LOAD='(-0.01,0.01)';
      OUTPUT_LOAD='(1.0,-1.0)';
    'ESPI_CLK0||SPI_CLK0||AGPIO117':
      PIN_NUMBER='(0,0,0,0,0,0,0,0,0,0,0,0,0,0,0,0,0,0,0,0,0,DJ27,0,0,0,0,0,0,0,0,0,0,0,0,0,0,0,0,0,0)';
      BIDIRECTIONAL='TRUE';
      INPUT_LOAD='(-0.01,0.01)';
      OUTPUT_LOAD='(1.0,-1.0)';
    'AGPIO76||SPI_TPM_CS_L':
      PIN_NUMBER='(0,0,0,0,0,0,0,0,0,0,0,0,0,0,0,0,0,0,0,0,0,DJ25,0,0,0,0,0,0,0,0,0,0,0,0,0,0,0,0,0,0)';
      BIDIRECTIONAL='TRUE';
      INPUT_LOAD='(-0.01,0.01)';
      OUTPUT_LOAD='(1.0,-1.0)';
    'ESPI0_ALERT_L||AGPIO108':
      PIN_NUMBER='(0,0,0,0,0,0,0,0,0,0,0,0,0,0,0,0,0,0,0,0,0,DJ22,0,0,0,0,0,0,0,0,0,0,0,0,0,0,0,0,0,0)';
      BIDIRECTIONAL='TRUE';
      INPUT_LOAD='(-0.01,0.01)';
      OUTPUT_LOAD='(1.0,-1.0)';
    'ESPI_CLK2||AGPIO74':
      PIN_NUMBER='(0,0,0,0,0,0,0,0,0,0,0,0,0,0,0,0,0,0,0,0,0,DF27,0,0,0,0,0,0,0,0,0,0,0,0,0,0,0,0,0,0)';
      BIDIRECTIONAL='TRUE';
      INPUT_LOAD='(-0.01,0.01)';
      OUTPUT_LOAD='(1.0,-1.0)';
    'ESPI_CLK1||SPI_CLK1||AGPIO75':
      PIN_NUMBER='(0,0,0,0,0,0,0,0,0,0,0,0,0,0,0,0,0,0,0,0,0,DG23,0,0,0,0,0,0,0,0,0,0,0,0,0,0,0,0,0,0)';
      BIDIRECTIONAL='TRUE';
      INPUT_LOAD='(-0.01,0.01)';
      OUTPUT_LOAD='(1.0,-1.0)';
    'ESPI_RSTOUT_L||AGPIO23':
      PIN_NUMBER='(0,0,0,0,0,0,0,0,0,0,0,0,0,0,0,0,0,0,0,0,0,DE27,0,0,0,0,0,0,0,0,0,0,0,0,0,0,0,0,0,0)';
      BIDIRECTIONAL='TRUE';
      INPUT_LOAD='(-0.01,0.01)';
      OUTPUT_LOAD='(1.0,-1.0)';
    'RSVD_BD62':
      PIN_NUMBER='(0,0,0,0,0,0,0,0,0,0,0,0,0,0,0,0,0,0,0,0,0,0,BD62,0,0,0,0,0,0,0,0,0,0,0,0,0,0,0,0,0)';
      OUTPUT_TYPE='(TS,TS)';
      INPUT_LOAD='(-0.01,0.01)';
      OUTPUT_LOAD='(1.0,-1.0)';
    'RSVD_D72':
      PIN_NUMBER='(0,0,0,0,0,0,0,0,0,0,0,0,0,0,0,0,0,0,0,0,0,0,D72,0,0,0,0,0,0,0,0,0,0,0,0,0,0,0,0,0)';
      OUTPUT_TYPE='(TS,TS)';
      INPUT_LOAD='(-0.01,0.01)';
      OUTPUT_LOAD='(1.0,-1.0)';
    'RSVD_C54':
      PIN_NUMBER='(0,0,0,0,0,0,0,0,0,0,0,0,0,0,0,0,0,0,0,0,0,0,C54,0,0,0,0,0,0,0,0,0,0,0,0,0,0,0,0,0)';
      OUTPUT_TYPE='(TS,TS)';
      INPUT_LOAD='(-0.01,0.01)';
      OUTPUT_LOAD='(1.0,-1.0)';
    'RSVD_BD65':
      PIN_NUMBER='(0,0,0,0,0,0,0,0,0,0,0,0,0,0,0,0,0,0,0,0,0,0,BD65,0,0,0,0,0,0,0,0,0,0,0,0,0,0,0,0,0)';
      OUTPUT_TYPE='(TS,TS)';
      INPUT_LOAD='(-0.01,0.01)';
      OUTPUT_LOAD='(1.0,-1.0)';
    'RSVD_E33':
      PIN_NUMBER='(0,0,0,0,0,0,0,0,0,0,0,0,0,0,0,0,0,0,0,0,0,0,E33,0,0,0,0,0,0,0,0,0,0,0,0,0,0,0,0,0)';
      OUTPUT_TYPE='(TS,TS)';
      INPUT_LOAD='(-0.01,0.01)';
      OUTPUT_LOAD='(1.0,-1.0)';
    'RSVD_D4':
      PIN_NUMBER='(0,0,0,0,0,0,0,0,0,0,0,0,0,0,0,0,0,0,0,0,0,0,D4,0,0,0,0,0,0,0,0,0,0,0,0,0,0,0,0,0)';
      OUTPUT_TYPE='(TS,TS)';
      INPUT_LOAD='(-0.01,0.01)';
      OUTPUT_LOAD='(1.0,-1.0)';
    'RSVD_A55':
      PIN_NUMBER='(0,0,0,0,0,0,0,0,0,0,0,0,0,0,0,0,0,0,0,0,0,0,A55,0,0,0,0,0,0,0,0,0,0,0,0,0,0,0,0,0)';
      OUTPUT_TYPE='(TS,TS)';
      INPUT_LOAD='(-0.01,0.01)';
      OUTPUT_LOAD='(1.0,-1.0)';
    'RSVD_BD69':
      PIN_NUMBER='(0,0,0,0,0,0,0,0,0,0,0,0,0,0,0,0,0,0,0,0,0,0,BD69,0,0,0,0,0,0,0,0,0,0,0,0,0,0,0,0,0)';
      OUTPUT_TYPE='(TS,TS)';
      INPUT_LOAD='(-0.01,0.01)';
      OUTPUT_LOAD='(1.0,-1.0)';
    'RSVD_E36':
      PIN_NUMBER='(0,0,0,0,0,0,0,0,0,0,0,0,0,0,0,0,0,0,0,0,0,0,E36,0,0,0,0,0,0,0,0,0,0,0,0,0,0,0,0,0)';
      OUTPUT_TYPE='(TS,TS)';
      INPUT_LOAD='(-0.01,0.01)';
      OUTPUT_LOAD='(1.0,-1.0)';
    'RSVD_D8':
      PIN_NUMBER='(0,0,0,0,0,0,0,0,0,0,0,0,0,0,0,0,0,0,0,0,0,0,D8,0,0,0,0,0,0,0,0,0,0,0,0,0,0,0,0,0)';
      OUTPUT_TYPE='(TS,TS)';
      INPUT_LOAD='(-0.01,0.01)';
      OUTPUT_LOAD='(1.0,-1.0)';
    'RSVD_A56':
      PIN_NUMBER='(0,0,0,0,0,0,0,0,0,0,0,0,0,0,0,0,0,0,0,0,0,0,A56,0,0,0,0,0,0,0,0,0,0,0,0,0,0,0,0,0)';
      OUTPUT_TYPE='(TS,TS)';
      INPUT_LOAD='(-0.01,0.01)';
      OUTPUT_LOAD='(1.0,-1.0)';
    'RSVD_BD72':
      PIN_NUMBER='(0,0,0,0,0,0,0,0,0,0,0,0,0,0,0,0,0,0,0,0,0,0,BD72,0,0,0,0,0,0,0,0,0,0,0,0,0,0,0,0,0)';
      OUTPUT_TYPE='(TS,TS)';
      INPUT_LOAD='(-0.01,0.01)';
      OUTPUT_LOAD='(1.0,-1.0)';
    'RSVD_BD4':
      PIN_NUMBER='(0,0,0,0,0,0,0,0,0,0,0,0,0,0,0,0,0,0,0,0,0,0,BD4,0,0,0,0,0,0,0,0,0,0,0,0,0,0,0,0,0)';
      OUTPUT_TYPE='(TS,TS)';
      INPUT_LOAD='(-0.01,0.01)';
      OUTPUT_LOAD='(1.0,-1.0)';
    'RSVD_D11':
      PIN_NUMBER='(0,0,0,0,0,0,0,0,0,0,0,0,0,0,0,0,0,0,0,0,0,0,D11,0,0,0,0,0,0,0,0,0,0,0,0,0,0,0,0,0)';
      OUTPUT_TYPE='(TS,TS)';
      INPUT_LOAD='(-0.01,0.01)';
      OUTPUT_LOAD='(1.0,-1.0)';
    'RSVD_A57':
      PIN_NUMBER='(0,0,0,0,0,0,0,0,0,0,0,0,0,0,0,0,0,0,0,0,0,0,A57,0,0,0,0,0,0,0,0,0,0,0,0,0,0,0,0,0)';
      OUTPUT_TYPE='(TS,TS)';
      INPUT_LOAD='(-0.01,0.01)';
      OUTPUT_LOAD='(1.0,-1.0)';
    'RSVD_DG17':
      PIN_NUMBER='(0,0,0,0,0,0,0,0,0,0,0,0,0,0,0,0,0,0,0,0,0,0,DG17,0,0,0,0,0,0,0,0,0,0,0,0,0,0,0,0,0)';
      OUTPUT_TYPE='(TS,TS)';
      INPUT_LOAD='(-0.01,0.01)';
      OUTPUT_LOAD='(1.0,-1.0)';
    'RSVD_D22':
      PIN_NUMBER='(0,0,0,0,0,0,0,0,0,0,0,0,0,0,0,0,0,0,0,0,0,0,D22,0,0,0,0,0,0,0,0,0,0,0,0,0,0,0,0,0)';
      OUTPUT_TYPE='(TS,TS)';
      INPUT_LOAD='(-0.01,0.01)';
      OUTPUT_LOAD='(1.0,-1.0)';
    'RSVD_A59':
      PIN_NUMBER='(0,0,0,0,0,0,0,0,0,0,0,0,0,0,0,0,0,0,0,0,0,0,A59,0,0,0,0,0,0,0,0,0,0,0,0,0,0,0,0,0)';
      OUTPUT_TYPE='(TS,TS)';
      INPUT_LOAD='(-0.01,0.01)';
      OUTPUT_LOAD='(1.0,-1.0)';
    'RSVD_DH17':
      PIN_NUMBER='(0,0,0,0,0,0,0,0,0,0,0,0,0,0,0,0,0,0,0,0,0,0,DH17,0,0,0,0,0,0,0,0,0,0,0,0,0,0,0,0,0)';
      OUTPUT_TYPE='(TS,TS)';
      INPUT_LOAD='(-0.01,0.01)';
      OUTPUT_LOAD='(1.0,-1.0)';
    'RSVD_BD11':
      PIN_NUMBER='(0,0,0,0,0,0,0,0,0,0,0,0,0,0,0,0,0,0,0,0,0,0,BD11,0,0,0,0,0,0,0,0,0,0,0,0,0,0,0,0,0)';
      OUTPUT_TYPE='(TS,TS)';
      INPUT_LOAD='(-0.01,0.01)';
      OUTPUT_LOAD='(1.0,-1.0)';
    'RSVD_D34':
      PIN_NUMBER='(0,0,0,0,0,0,0,0,0,0,0,0,0,0,0,0,0,0,0,0,0,0,D34,0,0,0,0,0,0,0,0,0,0,0,0,0,0,0,0,0)';
      OUTPUT_TYPE='(TS,TS)';
      INPUT_LOAD='(-0.01,0.01)';
      OUTPUT_LOAD='(1.0,-1.0)';
    'RSVD_A31':
      PIN_NUMBER='(0,0,0,0,0,0,0,0,0,0,0,0,0,0,0,0,0,0,0,0,0,0,A31,0,0,0,0,0,0,0,0,0,0,0,0,0,0,0,0,0)';
      OUTPUT_TYPE='(TS,TS)';
      INPUT_LOAD='(-0.01,0.01)';
      OUTPUT_LOAD='(1.0,-1.0)';
    'RSVD_DH21':
      PIN_NUMBER='(0,0,0,0,0,0,0,0,0,0,0,0,0,0,0,0,0,0,0,0,0,0,DH21,0,0,0,0,0,0,0,0,0,0,0,0,0,0,0,0,0)';
      OUTPUT_TYPE='(TS,TS)';
      INPUT_LOAD='(-0.01,0.01)';
      OUTPUT_LOAD='(1.0,-1.0)';
    'RSVD_BD14':
      PIN_NUMBER='(0,0,0,0,0,0,0,0,0,0,0,0,0,0,0,0,0,0,0,0,0,0,BD14,0,0,0,0,0,0,0,0,0,0,0,0,0,0,0,0,0)';
      OUTPUT_TYPE='(TS,TS)';
      INPUT_LOAD='(-0.01,0.01)';
      OUTPUT_LOAD='(1.0,-1.0)';
    'RSVD_B40':
      PIN_NUMBER='(0,0,0,0,0,0,0,0,0,0,0,0,0,0,0,0,0,0,0,0,0,0,B40,0,0,0,0,0,0,0,0,0,0,0,0,0,0,0,0,0)';
      OUTPUT_TYPE='(TS,TS)';
      INPUT_LOAD='(-0.01,0.01)';
      OUTPUT_LOAD='(1.0,-1.0)';
    'RSVD_A35':
      PIN_NUMBER='(0,0,0,0,0,0,0,0,0,0,0,0,0,0,0,0,0,0,0,0,0,0,A35,0,0,0,0,0,0,0,0,0,0,0,0,0,0,0,0,0)';
      OUTPUT_TYPE='(TS,TS)';
      INPUT_LOAD='(-0.01,0.01)';
      OUTPUT_LOAD='(1.0,-1.0)';
    'RSVD_DJ4':
      PIN_NUMBER='(0,0,0,0,0,0,0,0,0,0,0,0,0,0,0,0,0,0,0,0,0,0,DJ4,0,0,0,0,0,0,0,0,0,0,0,0,0,0,0,0,0)';
      OUTPUT_TYPE='(TS,TS)';
      INPUT_LOAD='(-0.01,0.01)';
      OUTPUT_LOAD='(1.0,-1.0)';
    'RSVD_BD18':
      PIN_NUMBER='(0,0,0,0,0,0,0,0,0,0,0,0,0,0,0,0,0,0,0,0,0,0,BD18,0,0,0,0,0,0,0,0,0,0,0,0,0,0,0,0,0)';
      OUTPUT_TYPE='(TS,TS)';
      INPUT_LOAD='(-0.01,0.01)';
      OUTPUT_LOAD='(1.0,-1.0)';
    'RSVD_D58':
      PIN_NUMBER='(0,0,0,0,0,0,0,0,0,0,0,0,0,0,0,0,0,0,0,0,0,0,D58,0,0,0,0,0,0,0,0,0,0,0,0,0,0,0,0,0)';
      OUTPUT_TYPE='(TS,TS)';
      INPUT_LOAD='(-0.01,0.01)';
      OUTPUT_LOAD='(1.0,-1.0)';
    'RSVD_C31':
      PIN_NUMBER='(0,0,0,0,0,0,0,0,0,0,0,0,0,0,0,0,0,0,0,0,0,0,C31,0,0,0,0,0,0,0,0,0,0,0,0,0,0,0,0,0)';
      OUTPUT_TYPE='(TS,TS)';
      INPUT_LOAD='(-0.01,0.01)';
      OUTPUT_LOAD='(1.0,-1.0)';
    'RSVD_A41':
      PIN_NUMBER='(0,0,0,0,0,0,0,0,0,0,0,0,0,0,0,0,0,0,0,0,0,0,A41,0,0,0,0,0,0,0,0,0,0,0,0,0,0,0,0,0)';
      OUTPUT_TYPE='(TS,TS)';
      INPUT_LOAD='(-0.01,0.01)';
      OUTPUT_LOAD='(1.0,-1.0)';
    'RSVD_BD21':
      PIN_NUMBER='(0,0,0,0,0,0,0,0,0,0,0,0,0,0,0,0,0,0,0,0,0,0,BD21,0,0,0,0,0,0,0,0,0,0,0,0,0,0,0,0,0)';
      OUTPUT_TYPE='(TS,TS)';
      INPUT_LOAD='(-0.01,0.01)';
      OUTPUT_LOAD='(1.0,-1.0)';
    'RSVD_D62':
      PIN_NUMBER='(0,0,0,0,0,0,0,0,0,0,0,0,0,0,0,0,0,0,0,0,0,0,D62,0,0,0,0,0,0,0,0,0,0,0,0,0,0,0,0,0)';
      OUTPUT_TYPE='(TS,TS)';
      INPUT_LOAD='(-0.01,0.01)';
      OUTPUT_LOAD='(1.0,-1.0)';
    'RSVD_C34':
      PIN_NUMBER='(0,0,0,0,0,0,0,0,0,0,0,0,0,0,0,0,0,0,0,0,0,0,C34,0,0,0,0,0,0,0,0,0,0,0,0,0,0,0,0,0)';
      OUTPUT_TYPE='(TS,TS)';
      INPUT_LOAD='(-0.01,0.01)';
      OUTPUT_LOAD='(1.0,-1.0)';
    'RSVD_A42':
      PIN_NUMBER='(0,0,0,0,0,0,0,0,0,0,0,0,0,0,0,0,0,0,0,0,0,0,A42,0,0,0,0,0,0,0,0,0,0,0,0,0,0,0,0,0)';
      OUTPUT_TYPE='(TS,TS)';
      INPUT_LOAD='(-0.01,0.01)';
      OUTPUT_LOAD='(1.0,-1.0)';
    'RSVD_D65':
      PIN_NUMBER='(0,0,0,0,0,0,0,0,0,0,0,0,0,0,0,0,0,0,0,0,0,0,D65,0,0,0,0,0,0,0,0,0,0,0,0,0,0,0,0,0)';
      OUTPUT_TYPE='(TS,TS)';
      INPUT_LOAD='(-0.01,0.01)';
      OUTPUT_LOAD='(1.0,-1.0)';
    'RSVD_C35':
      PIN_NUMBER='(0,0,0,0,0,0,0,0,0,0,0,0,0,0,0,0,0,0,0,0,0,0,C35,0,0,0,0,0,0,0,0,0,0,0,0,0,0,0,0,0)';
      OUTPUT_TYPE='(TS,TS)';
      INPUT_LOAD='(-0.01,0.01)';
      OUTPUT_LOAD='(1.0,-1.0)';
    'RSVD_A45':
      PIN_NUMBER='(0,0,0,0,0,0,0,0,0,0,0,0,0,0,0,0,0,0,0,0,0,0,A45,0,0,0,0,0,0,0,0,0,0,0,0,0,0,0,0,0)';
      OUTPUT_TYPE='(TS,TS)';
      INPUT_LOAD='(-0.01,0.01)';
      OUTPUT_LOAD='(1.0,-1.0)';
    'RSVD_C53':
      PIN_NUMBER='(0,0,0,0,0,0,0,0,0,0,0,0,0,0,0,0,0,0,0,0,0,0,C53,0,0,0,0,0,0,0,0,0,0,0,0,0,0,0,0,0)';
      OUTPUT_TYPE='(TS,TS)';
      INPUT_LOAD='(-0.01,0.01)';
      OUTPUT_LOAD='(1.0,-1.0)';
    'RSVD_A48':
      PIN_NUMBER='(0,0,0,0,0,0,0,0,0,0,0,0,0,0,0,0,0,0,0,0,0,0,A48,0,0,0,0,0,0,0,0,0,0,0,0,0,0,0,0,0)';
      OUTPUT_TYPE='(TS,TS)';
      INPUT_LOAD='(-0.01,0.01)';
      OUTPUT_LOAD='(1.0,-1.0)';
    'RSVD_A50':
      PIN_NUMBER='(0,0,0,0,0,0,0,0,0,0,0,0,0,0,0,0,0,0,0,0,0,0,A50,0,0,0,0,0,0,0,0,0,0,0,0,0,0,0,0,0)';
      OUTPUT_TYPE='(TS,TS)';
      INPUT_LOAD='(-0.01,0.01)';
      OUTPUT_LOAD='(1.0,-1.0)';
    'RSVD_A51':
      PIN_NUMBER='(0,0,0,0,0,0,0,0,0,0,0,0,0,0,0,0,0,0,0,0,0,0,A51,0,0,0,0,0,0,0,0,0,0,0,0,0,0,0,0,0)';
      OUTPUT_TYPE='(TS,TS)';
      INPUT_LOAD='(-0.01,0.01)';
      OUTPUT_LOAD='(1.0,-1.0)';
    'RSVD_A54':
      PIN_NUMBER='(0,0,0,0,0,0,0,0,0,0,0,0,0,0,0,0,0,0,0,0,0,0,A54,0,0,0,0,0,0,0,0,0,0,0,0,0,0,0,0,0)';
      OUTPUT_TYPE='(TS,TS)';
      INPUT_LOAD='(-0.01,0.01)';
      OUTPUT_LOAD='(1.0,-1.0)';
    'RSVD_BD55':
      PIN_NUMBER='(0,0,0,0,0,0,0,0,0,0,0,0,0,0,0,0,0,0,0,0,0,0,BD55,0,0,0,0,0,0,0,0,0,0,0,0,0,0,0,0,0)';
      OUTPUT_TYPE='(TS,TS)';
      INPUT_LOAD='(-0.01,0.01)';
      OUTPUT_LOAD='(1.0,-1.0)';
    'RSVD_BD58':
      PIN_NUMBER='(0,0,0,0,0,0,0,0,0,0,0,0,0,0,0,0,0,0,0,0,0,0,BD58,0,0,0,0,0,0,0,0,0,0,0,0,0,0,0,0,0)';
      OUTPUT_TYPE='(TS,TS)';
      INPUT_LOAD='(-0.01,0.01)';
      OUTPUT_LOAD='(1.0,-1.0)';
    'RSVD_D36':
      PIN_NUMBER='(0,0,0,0,0,0,0,0,0,0,0,0,0,0,0,0,0,0,0,0,0,0,D36,0,0,0,0,0,0,0,0,0,0,0,0,0,0,0,0,0)';
      OUTPUT_TYPE='(TS,TS)';
      INPUT_LOAD='(-0.01,0.01)';
      OUTPUT_LOAD='(1.0,-1.0)';
    'RSVD_BD7':
      PIN_NUMBER='(0,0,0,0,0,0,0,0,0,0,0,0,0,0,0,0,0,0,0,0,0,0,BD7,0,0,0,0,0,0,0,0,0,0,0,0,0,0,0,0,0)';
      OUTPUT_TYPE='(TS,TS)';
      INPUT_LOAD='(-0.01,0.01)';
      OUTPUT_LOAD='(1.0,-1.0)';
    'RSVD_A60':
      PIN_NUMBER='(0,0,0,0,0,0,0,0,0,0,0,0,0,0,0,0,0,0,0,0,0,0,A60,0,0,0,0,0,0,0,0,0,0,0,0,0,0,0,0,0)';
      OUTPUT_TYPE='(TS,TS)';
      INPUT_LOAD='(-0.01,0.01)';
      OUTPUT_LOAD='(1.0,-1.0)';
    'TEST6_X3D7':
      PIN_NUMBER='(0,0,0,0,0,0,0,0,0,0,0,0,0,0,0,0,0,0,0,0,0,0,DJ57,0,0,0,0,0,0,0,0,0,0,0,0,0,0,0,0,0)';
      OUTPUT_LOAD='(1.0,-1.0)';
    'TEST5_CCD13':
      PIN_NUMBER='(0,0,0,0,0,0,0,0,0,0,0,0,0,0,0,0,0,0,0,0,0,0,DH14,0,0,0,0,0,0,0,0,0,0,0,0,0,0,0,0,0)';
      OUTPUT_TYPE='(TS,TS)';
      INPUT_LOAD='(-0.01,0.01)';
      OUTPUT_LOAD='(1.0,-1.0)';
    'TEST4_CCD13':
      PIN_NUMBER='(0,0,0,0,0,0,0,0,0,0,0,0,0,0,0,0,0,0,0,0,0,0,DH13,0,0,0,0,0,0,0,0,0,0,0,0,0,0,0,0,0)';
      OUTPUT_TYPE='(TS,TS)';
      INPUT_LOAD='(-0.01,0.01)';
      OUTPUT_LOAD='(1.0,-1.0)';
    'TEST5_CCD14':
      PIN_NUMBER='(0,0,0,0,0,0,0,0,0,0,0,0,0,0,0,0,0,0,0,0,0,0,DG42,0,0,0,0,0,0,0,0,0,0,0,0,0,0,0,0,0)';
      OUTPUT_TYPE='(TS,TS)';
      INPUT_LOAD='(-0.01,0.01)';
      OUTPUT_LOAD='(1.0,-1.0)';
    'TEST4_CCD14':
      PIN_NUMBER='(0,0,0,0,0,0,0,0,0,0,0,0,0,0,0,0,0,0,0,0,0,0,DF41,0,0,0,0,0,0,0,0,0,0,0,0,0,0,0,0,0)';
      OUTPUT_TYPE='(TS,TS)';
      INPUT_LOAD='(-0.01,0.01)';
      OUTPUT_LOAD='(1.0,-1.0)';
    'TEST5_CCD15':
      PIN_NUMBER='(0,0,0,0,0,0,0,0,0,0,0,0,0,0,0,0,0,0,0,0,0,0,D23,0,0,0,0,0,0,0,0,0,0,0,0,0,0,0,0,0)';
      OUTPUT_TYPE='(TS,TS)';
      INPUT_LOAD='(-0.01,0.01)';
      OUTPUT_LOAD='(1.0,-1.0)';
    'TEST5_CCD12':
      PIN_NUMBER='(0,0,0,0,0,0,0,0,0,0,0,0,0,0,0,0,0,0,0,0,0,0,C59,0,0,0,0,0,0,0,0,0,0,0,0,0,0,0,0,0)';
      OUTPUT_TYPE='(TS,TS)';
      INPUT_LOAD='(-0.01,0.01)';
      OUTPUT_LOAD='(1.0,-1.0)';
    'TEST4_CCD12':
      PIN_NUMBER='(0,0,0,0,0,0,0,0,0,0,0,0,0,0,0,0,0,0,0,0,0,0,C58,0,0,0,0,0,0,0,0,0,0,0,0,0,0,0,0,0)';
      OUTPUT_TYPE='(TS,TS)';
      INPUT_LOAD='(-0.01,0.01)';
      OUTPUT_LOAD='(1.0,-1.0)';
    'TEST4_CCD15':
      PIN_NUMBER='(0,0,0,0,0,0,0,0,0,0,0,0,0,0,0,0,0,0,0,0,0,0,C23,0,0,0,0,0,0,0,0,0,0,0,0,0,0,0,0,0)';
      OUTPUT_TYPE='(TS,TS)';
      INPUT_LOAD='(-0.01,0.01)';
      OUTPUT_LOAD='(1.0,-1.0)';
    'TEST6_X3D6':
      PIN_NUMBER='(0,0,0,0,0,0,0,0,0,0,0,0,0,0,0,0,0,0,0,0,0,0,B36,0,0,0,0,0,0,0,0,0,0,0,0,0,0,0,0,0)';
      OUTPUT_LOAD='(1.0,-1.0)';
    'VDDCR_CPU0_W47':
      PIN_NUMBER='(0,0,0,0,0,0,0,0,0,0,0,0,0,0,0,0,0,0,0,0,0,0,0,W47,0,0,0,0,0,0,0,0,0,0,0,0,0,0,0,0)';
      PINUSE='POWER';
      NO_LOAD_CHECK='Both';
      NO_IO_CHECK='Both';
      NO_ASSERT_CHECK='TRUE';
      NO_DIR_CHECK='TRUE';
      ALLOW_CONNECT='TRUE';
    'VDDCR_CPU0_W46':
      PIN_NUMBER='(0,0,0,0,0,0,0,0,0,0,0,0,0,0,0,0,0,0,0,0,0,0,0,W46,0,0,0,0,0,0,0,0,0,0,0,0,0,0,0,0)';
      PINUSE='POWER';
      NO_LOAD_CHECK='Both';
      NO_IO_CHECK='Both';
      NO_ASSERT_CHECK='TRUE';
      NO_DIR_CHECK='TRUE';
      ALLOW_CONNECT='TRUE';
    'VDDCR_CPU0_W44':
      PIN_NUMBER='(0,0,0,0,0,0,0,0,0,0,0,0,0,0,0,0,0,0,0,0,0,0,0,W44,0,0,0,0,0,0,0,0,0,0,0,0,0,0,0,0)';
      PINUSE='POWER';
      NO_LOAD_CHECK='Both';
      NO_IO_CHECK='Both';
      NO_ASSERT_CHECK='TRUE';
      NO_DIR_CHECK='TRUE';
      ALLOW_CONNECT='TRUE';
    'VDDCR_CPU0_W43':
      PIN_NUMBER='(0,0,0,0,0,0,0,0,0,0,0,0,0,0,0,0,0,0,0,0,0,0,0,W43,0,0,0,0,0,0,0,0,0,0,0,0,0,0,0,0)';
      PINUSE='POWER';
      NO_LOAD_CHECK='Both';
      NO_IO_CHECK='Both';
      NO_ASSERT_CHECK='TRUE';
      NO_DIR_CHECK='TRUE';
      ALLOW_CONNECT='TRUE';
    'VDDCR_CPU0_W33':
      PIN_NUMBER='(0,0,0,0,0,0,0,0,0,0,0,0,0,0,0,0,0,0,0,0,0,0,0,W33,0,0,0,0,0,0,0,0,0,0,0,0,0,0,0,0)';
      PINUSE='POWER';
      NO_LOAD_CHECK='Both';
      NO_IO_CHECK='Both';
      NO_ASSERT_CHECK='TRUE';
      NO_DIR_CHECK='TRUE';
      ALLOW_CONNECT='TRUE';
    'VDDCR_CPU0_W32':
      PIN_NUMBER='(0,0,0,0,0,0,0,0,0,0,0,0,0,0,0,0,0,0,0,0,0,0,0,W32,0,0,0,0,0,0,0,0,0,0,0,0,0,0,0,0)';
      PINUSE='POWER';
      NO_LOAD_CHECK='Both';
      NO_IO_CHECK='Both';
      NO_ASSERT_CHECK='TRUE';
      NO_DIR_CHECK='TRUE';
      ALLOW_CONNECT='TRUE';
    'VDDCR_CPU0_W30':
      PIN_NUMBER='(0,0,0,0,0,0,0,0,0,0,0,0,0,0,0,0,0,0,0,0,0,0,0,W30,0,0,0,0,0,0,0,0,0,0,0,0,0,0,0,0)';
      PINUSE='POWER';
      NO_LOAD_CHECK='Both';
      NO_IO_CHECK='Both';
      NO_ASSERT_CHECK='TRUE';
      NO_DIR_CHECK='TRUE';
      ALLOW_CONNECT='TRUE';
    'VDDCR_CPU0_W29':
      PIN_NUMBER='(0,0,0,0,0,0,0,0,0,0,0,0,0,0,0,0,0,0,0,0,0,0,0,W29,0,0,0,0,0,0,0,0,0,0,0,0,0,0,0,0)';
      PINUSE='POWER';
      NO_LOAD_CHECK='Both';
      NO_IO_CHECK='Both';
      NO_ASSERT_CHECK='TRUE';
      NO_DIR_CHECK='TRUE';
      ALLOW_CONNECT='TRUE';
    'VDDCR_CPU0_U41':
      PIN_NUMBER='(0,0,0,0,0,0,0,0,0,0,0,0,0,0,0,0,0,0,0,0,0,0,0,U41,0,0,0,0,0,0,0,0,0,0,0,0,0,0,0,0)';
      PINUSE='POWER';
      NO_LOAD_CHECK='Both';
      NO_IO_CHECK='Both';
      NO_ASSERT_CHECK='TRUE';
      NO_DIR_CHECK='TRUE';
      ALLOW_CONNECT='TRUE';
    'VDDCR_CPU0_U40':
      PIN_NUMBER='(0,0,0,0,0,0,0,0,0,0,0,0,0,0,0,0,0,0,0,0,0,0,0,U40,0,0,0,0,0,0,0,0,0,0,0,0,0,0,0,0)';
      PINUSE='POWER';
      NO_LOAD_CHECK='Both';
      NO_IO_CHECK='Both';
      NO_ASSERT_CHECK='TRUE';
      NO_DIR_CHECK='TRUE';
      ALLOW_CONNECT='TRUE';
    'VDDCR_CPU0_U36':
      PIN_NUMBER='(0,0,0,0,0,0,0,0,0,0,0,0,0,0,0,0,0,0,0,0,0,0,0,U36,0,0,0,0,0,0,0,0,0,0,0,0,0,0,0,0)';
      PINUSE='POWER';
      NO_LOAD_CHECK='Both';
      NO_IO_CHECK='Both';
      NO_ASSERT_CHECK='TRUE';
      NO_DIR_CHECK='TRUE';
      ALLOW_CONNECT='TRUE';
    'VDDCR_CPU0_U35':
      PIN_NUMBER='(0,0,0,0,0,0,0,0,0,0,0,0,0,0,0,0,0,0,0,0,0,0,0,U35,0,0,0,0,0,0,0,0,0,0,0,0,0,0,0,0)';
      PINUSE='POWER';
      NO_LOAD_CHECK='Both';
      NO_IO_CHECK='Both';
      NO_ASSERT_CHECK='TRUE';
      NO_DIR_CHECK='TRUE';
      ALLOW_CONNECT='TRUE';
    'VDDCR_CPU0_T53':
      PIN_NUMBER='(0,0,0,0,0,0,0,0,0,0,0,0,0,0,0,0,0,0,0,0,0,0,0,T53,0,0,0,0,0,0,0,0,0,0,0,0,0,0,0,0)';
      PINUSE='POWER';
      NO_LOAD_CHECK='Both';
      NO_IO_CHECK='Both';
      NO_ASSERT_CHECK='TRUE';
      NO_DIR_CHECK='TRUE';
      ALLOW_CONNECT='TRUE';
    'VDDCR_CPU0_T52':
      PIN_NUMBER='(0,0,0,0,0,0,0,0,0,0,0,0,0,0,0,0,0,0,0,0,0,0,0,T52,0,0,0,0,0,0,0,0,0,0,0,0,0,0,0,0)';
      PINUSE='POWER';
      NO_LOAD_CHECK='Both';
      NO_IO_CHECK='Both';
      NO_ASSERT_CHECK='TRUE';
      NO_DIR_CHECK='TRUE';
      ALLOW_CONNECT='TRUE';
    'VDDCR_CPU0_T50':
      PIN_NUMBER='(0,0,0,0,0,0,0,0,0,0,0,0,0,0,0,0,0,0,0,0,0,0,0,T50,0,0,0,0,0,0,0,0,0,0,0,0,0,0,0,0)';
      PINUSE='POWER';
      NO_LOAD_CHECK='Both';
      NO_IO_CHECK='Both';
      NO_ASSERT_CHECK='TRUE';
      NO_DIR_CHECK='TRUE';
      ALLOW_CONNECT='TRUE';
    'VDDCR_CPU0_T49':
      PIN_NUMBER='(0,0,0,0,0,0,0,0,0,0,0,0,0,0,0,0,0,0,0,0,0,0,0,T49,0,0,0,0,0,0,0,0,0,0,0,0,0,0,0,0)';
      PINUSE='POWER';
      NO_LOAD_CHECK='Both';
      NO_IO_CHECK='Both';
      NO_ASSERT_CHECK='TRUE';
      NO_DIR_CHECK='TRUE';
      ALLOW_CONNECT='TRUE';
    'VDDCR_CPU0_T47':
      PIN_NUMBER='(0,0,0,0,0,0,0,0,0,0,0,0,0,0,0,0,0,0,0,0,0,0,0,T47,0,0,0,0,0,0,0,0,0,0,0,0,0,0,0,0)';
      PINUSE='POWER';
      NO_LOAD_CHECK='Both';
      NO_IO_CHECK='Both';
      NO_ASSERT_CHECK='TRUE';
      NO_DIR_CHECK='TRUE';
      ALLOW_CONNECT='TRUE';
    'VDDCR_CPU0_T46':
      PIN_NUMBER='(0,0,0,0,0,0,0,0,0,0,0,0,0,0,0,0,0,0,0,0,0,0,0,T46,0,0,0,0,0,0,0,0,0,0,0,0,0,0,0,0)';
      PINUSE='POWER';
      NO_LOAD_CHECK='Both';
      NO_IO_CHECK='Both';
      NO_ASSERT_CHECK='TRUE';
      NO_DIR_CHECK='TRUE';
      ALLOW_CONNECT='TRUE';
    'VDDCR_CPU0_T44':
      PIN_NUMBER='(0,0,0,0,0,0,0,0,0,0,0,0,0,0,0,0,0,0,0,0,0,0,0,T44,0,0,0,0,0,0,0,0,0,0,0,0,0,0,0,0)';
      PINUSE='POWER';
      NO_LOAD_CHECK='Both';
      NO_IO_CHECK='Both';
      NO_ASSERT_CHECK='TRUE';
      NO_DIR_CHECK='TRUE';
      ALLOW_CONNECT='TRUE';
    'VDDCR_CPU0_T43':
      PIN_NUMBER='(0,0,0,0,0,0,0,0,0,0,0,0,0,0,0,0,0,0,0,0,0,0,0,T43,0,0,0,0,0,0,0,0,0,0,0,0,0,0,0,0)';
      PINUSE='POWER';
      NO_LOAD_CHECK='Both';
      NO_IO_CHECK='Both';
      NO_ASSERT_CHECK='TRUE';
      NO_DIR_CHECK='TRUE';
      ALLOW_CONNECT='TRUE';
    'VDDCR_CPU0_T33':
      PIN_NUMBER='(0,0,0,0,0,0,0,0,0,0,0,0,0,0,0,0,0,0,0,0,0,0,0,T33,0,0,0,0,0,0,0,0,0,0,0,0,0,0,0,0)';
      PINUSE='POWER';
      NO_LOAD_CHECK='Both';
      NO_IO_CHECK='Both';
      NO_ASSERT_CHECK='TRUE';
      NO_DIR_CHECK='TRUE';
      ALLOW_CONNECT='TRUE';
    'VDDCR_CPU0_T32':
      PIN_NUMBER='(0,0,0,0,0,0,0,0,0,0,0,0,0,0,0,0,0,0,0,0,0,0,0,T32,0,0,0,0,0,0,0,0,0,0,0,0,0,0,0,0)';
      PINUSE='POWER';
      NO_LOAD_CHECK='Both';
      NO_IO_CHECK='Both';
      NO_ASSERT_CHECK='TRUE';
      NO_DIR_CHECK='TRUE';
      ALLOW_CONNECT='TRUE';
    'VDDCR_CPU0_T30':
      PIN_NUMBER='(0,0,0,0,0,0,0,0,0,0,0,0,0,0,0,0,0,0,0,0,0,0,0,T30,0,0,0,0,0,0,0,0,0,0,0,0,0,0,0,0)';
      PINUSE='POWER';
      NO_LOAD_CHECK='Both';
      NO_IO_CHECK='Both';
      NO_ASSERT_CHECK='TRUE';
      NO_DIR_CHECK='TRUE';
      ALLOW_CONNECT='TRUE';
    'VDDCR_CPU0_T29':
      PIN_NUMBER='(0,0,0,0,0,0,0,0,0,0,0,0,0,0,0,0,0,0,0,0,0,0,0,T29,0,0,0,0,0,0,0,0,0,0,0,0,0,0,0,0)';
      PINUSE='POWER';
      NO_LOAD_CHECK='Both';
      NO_IO_CHECK='Both';
      NO_ASSERT_CHECK='TRUE';
      NO_DIR_CHECK='TRUE';
      ALLOW_CONNECT='TRUE';
    'VDDCR_CPU0_T27':
      PIN_NUMBER='(0,0,0,0,0,0,0,0,0,0,0,0,0,0,0,0,0,0,0,0,0,0,0,T27,0,0,0,0,0,0,0,0,0,0,0,0,0,0,0,0)';
      PINUSE='POWER';
      NO_LOAD_CHECK='Both';
      NO_IO_CHECK='Both';
      NO_ASSERT_CHECK='TRUE';
      NO_DIR_CHECK='TRUE';
      ALLOW_CONNECT='TRUE';
    'VDDCR_CPU0_T26':
      PIN_NUMBER='(0,0,0,0,0,0,0,0,0,0,0,0,0,0,0,0,0,0,0,0,0,0,0,T26,0,0,0,0,0,0,0,0,0,0,0,0,0,0,0,0)';
      PINUSE='POWER';
      NO_LOAD_CHECK='Both';
      NO_IO_CHECK='Both';
      NO_ASSERT_CHECK='TRUE';
      NO_DIR_CHECK='TRUE';
      ALLOW_CONNECT='TRUE';
    'VDDCR_CPU0_T24':
      PIN_NUMBER='(0,0,0,0,0,0,0,0,0,0,0,0,0,0,0,0,0,0,0,0,0,0,0,T24,0,0,0,0,0,0,0,0,0,0,0,0,0,0,0,0)';
      PINUSE='POWER';
      NO_LOAD_CHECK='Both';
      NO_IO_CHECK='Both';
      NO_ASSERT_CHECK='TRUE';
      NO_DIR_CHECK='TRUE';
      ALLOW_CONNECT='TRUE';
    'VDDCR_CPU0_T23':
      PIN_NUMBER='(0,0,0,0,0,0,0,0,0,0,0,0,0,0,0,0,0,0,0,0,0,0,0,T23,0,0,0,0,0,0,0,0,0,0,0,0,0,0,0,0)';
      PINUSE='POWER';
      NO_LOAD_CHECK='Both';
      NO_IO_CHECK='Both';
      NO_ASSERT_CHECK='TRUE';
      NO_DIR_CHECK='TRUE';
      ALLOW_CONNECT='TRUE';
    'VDDCR_CPU0_N41':
      PIN_NUMBER='(0,0,0,0,0,0,0,0,0,0,0,0,0,0,0,0,0,0,0,0,0,0,0,N41,0,0,0,0,0,0,0,0,0,0,0,0,0,0,0,0)';
      PINUSE='POWER';
      NO_LOAD_CHECK='Both';
      NO_IO_CHECK='Both';
      NO_ASSERT_CHECK='TRUE';
      NO_DIR_CHECK='TRUE';
      ALLOW_CONNECT='TRUE';
    'VDDCR_CPU0_N40':
      PIN_NUMBER='(0,0,0,0,0,0,0,0,0,0,0,0,0,0,0,0,0,0,0,0,0,0,0,N40,0,0,0,0,0,0,0,0,0,0,0,0,0,0,0,0)';
      PINUSE='POWER';
      NO_LOAD_CHECK='Both';
      NO_IO_CHECK='Both';
      NO_ASSERT_CHECK='TRUE';
      NO_DIR_CHECK='TRUE';
      ALLOW_CONNECT='TRUE';
    'VDDCR_CPU0_N36':
      PIN_NUMBER='(0,0,0,0,0,0,0,0,0,0,0,0,0,0,0,0,0,0,0,0,0,0,0,N36,0,0,0,0,0,0,0,0,0,0,0,0,0,0,0,0)';
      PINUSE='POWER';
      NO_LOAD_CHECK='Both';
      NO_IO_CHECK='Both';
      NO_ASSERT_CHECK='TRUE';
      NO_DIR_CHECK='TRUE';
      ALLOW_CONNECT='TRUE';
    'VDDCR_CPU0_N35':
      PIN_NUMBER='(0,0,0,0,0,0,0,0,0,0,0,0,0,0,0,0,0,0,0,0,0,0,0,N35,0,0,0,0,0,0,0,0,0,0,0,0,0,0,0,0)';
      PINUSE='POWER';
      NO_LOAD_CHECK='Both';
      NO_IO_CHECK='Both';
      NO_ASSERT_CHECK='TRUE';
      NO_DIR_CHECK='TRUE';
      ALLOW_CONNECT='TRUE';
    'VDDCR_CPU0_M53':
      PIN_NUMBER='(0,0,0,0,0,0,0,0,0,0,0,0,0,0,0,0,0,0,0,0,0,0,0,M53,0,0,0,0,0,0,0,0,0,0,0,0,0,0,0,0)';
      PINUSE='POWER';
      NO_LOAD_CHECK='Both';
      NO_IO_CHECK='Both';
      NO_ASSERT_CHECK='TRUE';
      NO_DIR_CHECK='TRUE';
      ALLOW_CONNECT='TRUE';
    'VDDCR_CPU0_M52':
      PIN_NUMBER='(0,0,0,0,0,0,0,0,0,0,0,0,0,0,0,0,0,0,0,0,0,0,0,M52,0,0,0,0,0,0,0,0,0,0,0,0,0,0,0,0)';
      PINUSE='POWER';
      NO_LOAD_CHECK='Both';
      NO_IO_CHECK='Both';
      NO_ASSERT_CHECK='TRUE';
      NO_DIR_CHECK='TRUE';
      ALLOW_CONNECT='TRUE';
    'VDDCR_CPU0_M50':
      PIN_NUMBER='(0,0,0,0,0,0,0,0,0,0,0,0,0,0,0,0,0,0,0,0,0,0,0,M50,0,0,0,0,0,0,0,0,0,0,0,0,0,0,0,0)';
      PINUSE='POWER';
      NO_LOAD_CHECK='Both';
      NO_IO_CHECK='Both';
      NO_ASSERT_CHECK='TRUE';
      NO_DIR_CHECK='TRUE';
      ALLOW_CONNECT='TRUE';
    'VDDCR_CPU0_M49':
      PIN_NUMBER='(0,0,0,0,0,0,0,0,0,0,0,0,0,0,0,0,0,0,0,0,0,0,0,M49,0,0,0,0,0,0,0,0,0,0,0,0,0,0,0,0)';
      PINUSE='POWER';
      NO_LOAD_CHECK='Both';
      NO_IO_CHECK='Both';
      NO_ASSERT_CHECK='TRUE';
      NO_DIR_CHECK='TRUE';
      ALLOW_CONNECT='TRUE';
    'VDDCR_CPU0_M47':
      PIN_NUMBER='(0,0,0,0,0,0,0,0,0,0,0,0,0,0,0,0,0,0,0,0,0,0,0,M47,0,0,0,0,0,0,0,0,0,0,0,0,0,0,0,0)';
      PINUSE='POWER';
      NO_LOAD_CHECK='Both';
      NO_IO_CHECK='Both';
      NO_ASSERT_CHECK='TRUE';
      NO_DIR_CHECK='TRUE';
      ALLOW_CONNECT='TRUE';
    'VDDCR_CPU0_M46':
      PIN_NUMBER='(0,0,0,0,0,0,0,0,0,0,0,0,0,0,0,0,0,0,0,0,0,0,0,M46,0,0,0,0,0,0,0,0,0,0,0,0,0,0,0,0)';
      PINUSE='POWER';
      NO_LOAD_CHECK='Both';
      NO_IO_CHECK='Both';
      NO_ASSERT_CHECK='TRUE';
      NO_DIR_CHECK='TRUE';
      ALLOW_CONNECT='TRUE';
    'VDDCR_CPU0_M44':
      PIN_NUMBER='(0,0,0,0,0,0,0,0,0,0,0,0,0,0,0,0,0,0,0,0,0,0,0,M44,0,0,0,0,0,0,0,0,0,0,0,0,0,0,0,0)';
      PINUSE='POWER';
      NO_LOAD_CHECK='Both';
      NO_IO_CHECK='Both';
      NO_ASSERT_CHECK='TRUE';
      NO_DIR_CHECK='TRUE';
      ALLOW_CONNECT='TRUE';
    'VDDCR_CPU0_M43':
      PIN_NUMBER='(0,0,0,0,0,0,0,0,0,0,0,0,0,0,0,0,0,0,0,0,0,0,0,M43,0,0,0,0,0,0,0,0,0,0,0,0,0,0,0,0)';
      PINUSE='POWER';
      NO_LOAD_CHECK='Both';
      NO_IO_CHECK='Both';
      NO_ASSERT_CHECK='TRUE';
      NO_DIR_CHECK='TRUE';
      ALLOW_CONNECT='TRUE';
    'VDDCR_CPU0_M33':
      PIN_NUMBER='(0,0,0,0,0,0,0,0,0,0,0,0,0,0,0,0,0,0,0,0,0,0,0,M33,0,0,0,0,0,0,0,0,0,0,0,0,0,0,0,0)';
      PINUSE='POWER';
      NO_LOAD_CHECK='Both';
      NO_IO_CHECK='Both';
      NO_ASSERT_CHECK='TRUE';
      NO_DIR_CHECK='TRUE';
      ALLOW_CONNECT='TRUE';
    'VDDCR_CPU0_M32':
      PIN_NUMBER='(0,0,0,0,0,0,0,0,0,0,0,0,0,0,0,0,0,0,0,0,0,0,0,M32,0,0,0,0,0,0,0,0,0,0,0,0,0,0,0,0)';
      PINUSE='POWER';
      NO_LOAD_CHECK='Both';
      NO_IO_CHECK='Both';
      NO_ASSERT_CHECK='TRUE';
      NO_DIR_CHECK='TRUE';
      ALLOW_CONNECT='TRUE';
    'VDDCR_CPU0_M30':
      PIN_NUMBER='(0,0,0,0,0,0,0,0,0,0,0,0,0,0,0,0,0,0,0,0,0,0,0,M30,0,0,0,0,0,0,0,0,0,0,0,0,0,0,0,0)';
      PINUSE='POWER';
      NO_LOAD_CHECK='Both';
      NO_IO_CHECK='Both';
      NO_ASSERT_CHECK='TRUE';
      NO_DIR_CHECK='TRUE';
      ALLOW_CONNECT='TRUE';
    'VDDCR_CPU0_M29':
      PIN_NUMBER='(0,0,0,0,0,0,0,0,0,0,0,0,0,0,0,0,0,0,0,0,0,0,0,M29,0,0,0,0,0,0,0,0,0,0,0,0,0,0,0,0)';
      PINUSE='POWER';
      NO_LOAD_CHECK='Both';
      NO_IO_CHECK='Both';
      NO_ASSERT_CHECK='TRUE';
      NO_DIR_CHECK='TRUE';
      ALLOW_CONNECT='TRUE';
    'VDDCR_CPU0_M27':
      PIN_NUMBER='(0,0,0,0,0,0,0,0,0,0,0,0,0,0,0,0,0,0,0,0,0,0,0,M27,0,0,0,0,0,0,0,0,0,0,0,0,0,0,0,0)';
      PINUSE='POWER';
      NO_LOAD_CHECK='Both';
      NO_IO_CHECK='Both';
      NO_ASSERT_CHECK='TRUE';
      NO_DIR_CHECK='TRUE';
      ALLOW_CONNECT='TRUE';
    'VDDCR_CPU0_M26':
      PIN_NUMBER='(0,0,0,0,0,0,0,0,0,0,0,0,0,0,0,0,0,0,0,0,0,0,0,M26,0,0,0,0,0,0,0,0,0,0,0,0,0,0,0,0)';
      PINUSE='POWER';
      NO_LOAD_CHECK='Both';
      NO_IO_CHECK='Both';
      NO_ASSERT_CHECK='TRUE';
      NO_DIR_CHECK='TRUE';
      ALLOW_CONNECT='TRUE';
    'VDDCR_CPU0_M24':
      PIN_NUMBER='(0,0,0,0,0,0,0,0,0,0,0,0,0,0,0,0,0,0,0,0,0,0,0,M24,0,0,0,0,0,0,0,0,0,0,0,0,0,0,0,0)';
      PINUSE='POWER';
      NO_LOAD_CHECK='Both';
      NO_IO_CHECK='Both';
      NO_ASSERT_CHECK='TRUE';
      NO_DIR_CHECK='TRUE';
      ALLOW_CONNECT='TRUE';
    'VDDCR_CPU0_M23':
      PIN_NUMBER='(0,0,0,0,0,0,0,0,0,0,0,0,0,0,0,0,0,0,0,0,0,0,0,M23,0,0,0,0,0,0,0,0,0,0,0,0,0,0,0,0)';
      PINUSE='POWER';
      NO_LOAD_CHECK='Both';
      NO_IO_CHECK='Both';
      NO_ASSERT_CHECK='TRUE';
      NO_DIR_CHECK='TRUE';
      ALLOW_CONNECT='TRUE';
    'VDDCR_CPU0_J41':
      PIN_NUMBER='(0,0,0,0,0,0,0,0,0,0,0,0,0,0,0,0,0,0,0,0,0,0,0,J41,0,0,0,0,0,0,0,0,0,0,0,0,0,0,0,0)';
      PINUSE='POWER';
      NO_LOAD_CHECK='Both';
      NO_IO_CHECK='Both';
      NO_ASSERT_CHECK='TRUE';
      NO_DIR_CHECK='TRUE';
      ALLOW_CONNECT='TRUE';
    'VDDCR_CPU0_J40':
      PIN_NUMBER='(0,0,0,0,0,0,0,0,0,0,0,0,0,0,0,0,0,0,0,0,0,0,0,J40,0,0,0,0,0,0,0,0,0,0,0,0,0,0,0,0)';
      PINUSE='POWER';
      NO_LOAD_CHECK='Both';
      NO_IO_CHECK='Both';
      NO_ASSERT_CHECK='TRUE';
      NO_DIR_CHECK='TRUE';
      ALLOW_CONNECT='TRUE';
    'VDDCR_CPU0_J36':
      PIN_NUMBER='(0,0,0,0,0,0,0,0,0,0,0,0,0,0,0,0,0,0,0,0,0,0,0,J36,0,0,0,0,0,0,0,0,0,0,0,0,0,0,0,0)';
      PINUSE='POWER';
      NO_LOAD_CHECK='Both';
      NO_IO_CHECK='Both';
      NO_ASSERT_CHECK='TRUE';
      NO_DIR_CHECK='TRUE';
      ALLOW_CONNECT='TRUE';
    'VDDCR_CPU0_J35':
      PIN_NUMBER='(0,0,0,0,0,0,0,0,0,0,0,0,0,0,0,0,0,0,0,0,0,0,0,J35,0,0,0,0,0,0,0,0,0,0,0,0,0,0,0,0)';
      PINUSE='POWER';
      NO_LOAD_CHECK='Both';
      NO_IO_CHECK='Both';
      NO_ASSERT_CHECK='TRUE';
      NO_DIR_CHECK='TRUE';
      ALLOW_CONNECT='TRUE';
    'VDDCR_CPU0_H53':
      PIN_NUMBER='(0,0,0,0,0,0,0,0,0,0,0,0,0,0,0,0,0,0,0,0,0,0,0,H53,0,0,0,0,0,0,0,0,0,0,0,0,0,0,0,0)';
      PINUSE='POWER';
      NO_LOAD_CHECK='Both';
      NO_IO_CHECK='Both';
      NO_ASSERT_CHECK='TRUE';
      NO_DIR_CHECK='TRUE';
      ALLOW_CONNECT='TRUE';
    'VDDCR_CPU0_H52':
      PIN_NUMBER='(0,0,0,0,0,0,0,0,0,0,0,0,0,0,0,0,0,0,0,0,0,0,0,H52,0,0,0,0,0,0,0,0,0,0,0,0,0,0,0,0)';
      PINUSE='POWER';
      NO_LOAD_CHECK='Both';
      NO_IO_CHECK='Both';
      NO_ASSERT_CHECK='TRUE';
      NO_DIR_CHECK='TRUE';
      ALLOW_CONNECT='TRUE';
    'VDDCR_CPU0_H50':
      PIN_NUMBER='(0,0,0,0,0,0,0,0,0,0,0,0,0,0,0,0,0,0,0,0,0,0,0,H50,0,0,0,0,0,0,0,0,0,0,0,0,0,0,0,0)';
      PINUSE='POWER';
      NO_LOAD_CHECK='Both';
      NO_IO_CHECK='Both';
      NO_ASSERT_CHECK='TRUE';
      NO_DIR_CHECK='TRUE';
      ALLOW_CONNECT='TRUE';
    'VDDCR_CPU0_H49':
      PIN_NUMBER='(0,0,0,0,0,0,0,0,0,0,0,0,0,0,0,0,0,0,0,0,0,0,0,H49,0,0,0,0,0,0,0,0,0,0,0,0,0,0,0,0)';
      PINUSE='POWER';
      NO_LOAD_CHECK='Both';
      NO_IO_CHECK='Both';
      NO_ASSERT_CHECK='TRUE';
      NO_DIR_CHECK='TRUE';
      ALLOW_CONNECT='TRUE';
    'VDDCR_CPU0_H47':
      PIN_NUMBER='(0,0,0,0,0,0,0,0,0,0,0,0,0,0,0,0,0,0,0,0,0,0,0,H47,0,0,0,0,0,0,0,0,0,0,0,0,0,0,0,0)';
      PINUSE='POWER';
      NO_LOAD_CHECK='Both';
      NO_IO_CHECK='Both';
      NO_ASSERT_CHECK='TRUE';
      NO_DIR_CHECK='TRUE';
      ALLOW_CONNECT='TRUE';
    'VDDCR_CPU0_H46':
      PIN_NUMBER='(0,0,0,0,0,0,0,0,0,0,0,0,0,0,0,0,0,0,0,0,0,0,0,H46,0,0,0,0,0,0,0,0,0,0,0,0,0,0,0,0)';
      PINUSE='POWER';
      NO_LOAD_CHECK='Both';
      NO_IO_CHECK='Both';
      NO_ASSERT_CHECK='TRUE';
      NO_DIR_CHECK='TRUE';
      ALLOW_CONNECT='TRUE';
    'VDDCR_CPU0_H44':
      PIN_NUMBER='(0,0,0,0,0,0,0,0,0,0,0,0,0,0,0,0,0,0,0,0,0,0,0,H44,0,0,0,0,0,0,0,0,0,0,0,0,0,0,0,0)';
      PINUSE='POWER';
      NO_LOAD_CHECK='Both';
      NO_IO_CHECK='Both';
      NO_ASSERT_CHECK='TRUE';
      NO_DIR_CHECK='TRUE';
      ALLOW_CONNECT='TRUE';
    'VDDCR_CPU0_H43':
      PIN_NUMBER='(0,0,0,0,0,0,0,0,0,0,0,0,0,0,0,0,0,0,0,0,0,0,0,H43,0,0,0,0,0,0,0,0,0,0,0,0,0,0,0,0)';
      PINUSE='POWER';
      NO_LOAD_CHECK='Both';
      NO_IO_CHECK='Both';
      NO_ASSERT_CHECK='TRUE';
      NO_DIR_CHECK='TRUE';
      ALLOW_CONNECT='TRUE';
    'VDDCR_CPU0_H33':
      PIN_NUMBER='(0,0,0,0,0,0,0,0,0,0,0,0,0,0,0,0,0,0,0,0,0,0,0,H33,0,0,0,0,0,0,0,0,0,0,0,0,0,0,0,0)';
      PINUSE='POWER';
      NO_LOAD_CHECK='Both';
      NO_IO_CHECK='Both';
      NO_ASSERT_CHECK='TRUE';
      NO_DIR_CHECK='TRUE';
      ALLOW_CONNECT='TRUE';
    'VDDCR_CPU0_H32':
      PIN_NUMBER='(0,0,0,0,0,0,0,0,0,0,0,0,0,0,0,0,0,0,0,0,0,0,0,H32,0,0,0,0,0,0,0,0,0,0,0,0,0,0,0,0)';
      PINUSE='POWER';
      NO_LOAD_CHECK='Both';
      NO_IO_CHECK='Both';
      NO_ASSERT_CHECK='TRUE';
      NO_DIR_CHECK='TRUE';
      ALLOW_CONNECT='TRUE';
    'VDDCR_CPU0_H30':
      PIN_NUMBER='(0,0,0,0,0,0,0,0,0,0,0,0,0,0,0,0,0,0,0,0,0,0,0,H30,0,0,0,0,0,0,0,0,0,0,0,0,0,0,0,0)';
      PINUSE='POWER';
      NO_LOAD_CHECK='Both';
      NO_IO_CHECK='Both';
      NO_ASSERT_CHECK='TRUE';
      NO_DIR_CHECK='TRUE';
      ALLOW_CONNECT='TRUE';
    'VDDCR_CPU0_H29':
      PIN_NUMBER='(0,0,0,0,0,0,0,0,0,0,0,0,0,0,0,0,0,0,0,0,0,0,0,H29,0,0,0,0,0,0,0,0,0,0,0,0,0,0,0,0)';
      PINUSE='POWER';
      NO_LOAD_CHECK='Both';
      NO_IO_CHECK='Both';
      NO_ASSERT_CHECK='TRUE';
      NO_DIR_CHECK='TRUE';
      ALLOW_CONNECT='TRUE';
    'VDDCR_CPU0_H27':
      PIN_NUMBER='(0,0,0,0,0,0,0,0,0,0,0,0,0,0,0,0,0,0,0,0,0,0,0,H27,0,0,0,0,0,0,0,0,0,0,0,0,0,0,0,0)';
      PINUSE='POWER';
      NO_LOAD_CHECK='Both';
      NO_IO_CHECK='Both';
      NO_ASSERT_CHECK='TRUE';
      NO_DIR_CHECK='TRUE';
      ALLOW_CONNECT='TRUE';
    'VDDCR_CPU0_H26':
      PIN_NUMBER='(0,0,0,0,0,0,0,0,0,0,0,0,0,0,0,0,0,0,0,0,0,0,0,H26,0,0,0,0,0,0,0,0,0,0,0,0,0,0,0,0)';
      PINUSE='POWER';
      NO_LOAD_CHECK='Both';
      NO_IO_CHECK='Both';
      NO_ASSERT_CHECK='TRUE';
      NO_DIR_CHECK='TRUE';
      ALLOW_CONNECT='TRUE';
    'VDDCR_CPU0_H24':
      PIN_NUMBER='(0,0,0,0,0,0,0,0,0,0,0,0,0,0,0,0,0,0,0,0,0,0,0,H24,0,0,0,0,0,0,0,0,0,0,0,0,0,0,0,0)';
      PINUSE='POWER';
      NO_LOAD_CHECK='Both';
      NO_IO_CHECK='Both';
      NO_ASSERT_CHECK='TRUE';
      NO_DIR_CHECK='TRUE';
      ALLOW_CONNECT='TRUE';
    'VDDCR_CPU0_H23':
      PIN_NUMBER='(0,0,0,0,0,0,0,0,0,0,0,0,0,0,0,0,0,0,0,0,0,0,0,H23,0,0,0,0,0,0,0,0,0,0,0,0,0,0,0,0)';
      PINUSE='POWER';
      NO_LOAD_CHECK='Both';
      NO_IO_CHECK='Both';
      NO_ASSERT_CHECK='TRUE';
      NO_DIR_CHECK='TRUE';
      ALLOW_CONNECT='TRUE';
    'VDDCR_CPU0_G41':
      PIN_NUMBER='(0,0,0,0,0,0,0,0,0,0,0,0,0,0,0,0,0,0,0,0,0,0,0,G41,0,0,0,0,0,0,0,0,0,0,0,0,0,0,0,0)';
      PINUSE='POWER';
      NO_LOAD_CHECK='Both';
      NO_IO_CHECK='Both';
      NO_ASSERT_CHECK='TRUE';
      NO_DIR_CHECK='TRUE';
      ALLOW_CONNECT='TRUE';
    'VDDCR_CPU0_G40':
      PIN_NUMBER='(0,0,0,0,0,0,0,0,0,0,0,0,0,0,0,0,0,0,0,0,0,0,0,G40,0,0,0,0,0,0,0,0,0,0,0,0,0,0,0,0)';
      PINUSE='POWER';
      NO_LOAD_CHECK='Both';
      NO_IO_CHECK='Both';
      NO_ASSERT_CHECK='TRUE';
      NO_DIR_CHECK='TRUE';
      ALLOW_CONNECT='TRUE';
    'VDDCR_CPU0_G36':
      PIN_NUMBER='(0,0,0,0,0,0,0,0,0,0,0,0,0,0,0,0,0,0,0,0,0,0,0,G36,0,0,0,0,0,0,0,0,0,0,0,0,0,0,0,0)';
      PINUSE='POWER';
      NO_LOAD_CHECK='Both';
      NO_IO_CHECK='Both';
      NO_ASSERT_CHECK='TRUE';
      NO_DIR_CHECK='TRUE';
      ALLOW_CONNECT='TRUE';
    'VDDCR_CPU0_G35':
      PIN_NUMBER='(0,0,0,0,0,0,0,0,0,0,0,0,0,0,0,0,0,0,0,0,0,0,0,G35,0,0,0,0,0,0,0,0,0,0,0,0,0,0,0,0)';
      PINUSE='POWER';
      NO_LOAD_CHECK='Both';
      NO_IO_CHECK='Both';
      NO_ASSERT_CHECK='TRUE';
      NO_DIR_CHECK='TRUE';
      ALLOW_CONNECT='TRUE';
    'VDDCR_CPU0_F54':
      PIN_NUMBER='(0,0,0,0,0,0,0,0,0,0,0,0,0,0,0,0,0,0,0,0,0,0,0,F54,0,0,0,0,0,0,0,0,0,0,0,0,0,0,0,0)';
      PINUSE='POWER';
      NO_LOAD_CHECK='Both';
      NO_IO_CHECK='Both';
      NO_ASSERT_CHECK='TRUE';
      NO_DIR_CHECK='TRUE';
      ALLOW_CONNECT='TRUE';
    'VDDCR_CPU0_F51':
      PIN_NUMBER='(0,0,0,0,0,0,0,0,0,0,0,0,0,0,0,0,0,0,0,0,0,0,0,F51,0,0,0,0,0,0,0,0,0,0,0,0,0,0,0,0)';
      PINUSE='POWER';
      NO_LOAD_CHECK='Both';
      NO_IO_CHECK='Both';
      NO_ASSERT_CHECK='TRUE';
      NO_DIR_CHECK='TRUE';
      ALLOW_CONNECT='TRUE';
    'VDDCR_CPU0_F48':
      PIN_NUMBER='(0,0,0,0,0,0,0,0,0,0,0,0,0,0,0,0,0,0,0,0,0,0,0,F48,0,0,0,0,0,0,0,0,0,0,0,0,0,0,0,0)';
      PINUSE='POWER';
      NO_LOAD_CHECK='Both';
      NO_IO_CHECK='Both';
      NO_ASSERT_CHECK='TRUE';
      NO_DIR_CHECK='TRUE';
      ALLOW_CONNECT='TRUE';
    'VDDCR_CPU0_F45':
      PIN_NUMBER='(0,0,0,0,0,0,0,0,0,0,0,0,0,0,0,0,0,0,0,0,0,0,0,F45,0,0,0,0,0,0,0,0,0,0,0,0,0,0,0,0)';
      PINUSE='POWER';
      NO_LOAD_CHECK='Both';
      NO_IO_CHECK='Both';
      NO_ASSERT_CHECK='TRUE';
      NO_DIR_CHECK='TRUE';
      ALLOW_CONNECT='TRUE';
    'VDDCR_CPU0_F42':
      PIN_NUMBER='(0,0,0,0,0,0,0,0,0,0,0,0,0,0,0,0,0,0,0,0,0,0,0,F42,0,0,0,0,0,0,0,0,0,0,0,0,0,0,0,0)';
      PINUSE='POWER';
      NO_LOAD_CHECK='Both';
      NO_IO_CHECK='Both';
      NO_ASSERT_CHECK='TRUE';
      NO_DIR_CHECK='TRUE';
      ALLOW_CONNECT='TRUE';
    'VDDCR_CPU0_F34':
      PIN_NUMBER='(0,0,0,0,0,0,0,0,0,0,0,0,0,0,0,0,0,0,0,0,0,0,0,F34,0,0,0,0,0,0,0,0,0,0,0,0,0,0,0,0)';
      PINUSE='POWER';
      NO_LOAD_CHECK='Both';
      NO_IO_CHECK='Both';
      NO_ASSERT_CHECK='TRUE';
      NO_DIR_CHECK='TRUE';
      ALLOW_CONNECT='TRUE';
    'VDDCR_CPU0_F31':
      PIN_NUMBER='(0,0,0,0,0,0,0,0,0,0,0,0,0,0,0,0,0,0,0,0,0,0,0,F31,0,0,0,0,0,0,0,0,0,0,0,0,0,0,0,0)';
      PINUSE='POWER';
      NO_LOAD_CHECK='Both';
      NO_IO_CHECK='Both';
      NO_ASSERT_CHECK='TRUE';
      NO_DIR_CHECK='TRUE';
      ALLOW_CONNECT='TRUE';
    'VDDCR_CPU0_F28':
      PIN_NUMBER='(0,0,0,0,0,0,0,0,0,0,0,0,0,0,0,0,0,0,0,0,0,0,0,F28,0,0,0,0,0,0,0,0,0,0,0,0,0,0,0,0)';
      PINUSE='POWER';
      NO_LOAD_CHECK='Both';
      NO_IO_CHECK='Both';
      NO_ASSERT_CHECK='TRUE';
      NO_DIR_CHECK='TRUE';
      ALLOW_CONNECT='TRUE';
    'VDDCR_CPU0_F25':
      PIN_NUMBER='(0,0,0,0,0,0,0,0,0,0,0,0,0,0,0,0,0,0,0,0,0,0,0,F25,0,0,0,0,0,0,0,0,0,0,0,0,0,0,0,0)';
      PINUSE='POWER';
      NO_LOAD_CHECK='Both';
      NO_IO_CHECK='Both';
      NO_ASSERT_CHECK='TRUE';
      NO_DIR_CHECK='TRUE';
      ALLOW_CONNECT='TRUE';
    'VDDCR_CPU0_F22':
      PIN_NUMBER='(0,0,0,0,0,0,0,0,0,0,0,0,0,0,0,0,0,0,0,0,0,0,0,F22,0,0,0,0,0,0,0,0,0,0,0,0,0,0,0,0)';
      PINUSE='POWER';
      NO_LOAD_CHECK='Both';
      NO_IO_CHECK='Both';
      NO_ASSERT_CHECK='TRUE';
      NO_DIR_CHECK='TRUE';
      ALLOW_CONNECT='TRUE';
    'VDDCR_CPU0_E54':
      PIN_NUMBER='(0,0,0,0,0,0,0,0,0,0,0,0,0,0,0,0,0,0,0,0,0,0,0,E54,0,0,0,0,0,0,0,0,0,0,0,0,0,0,0,0)';
      PINUSE='POWER';
      NO_LOAD_CHECK='Both';
      NO_IO_CHECK='Both';
      NO_ASSERT_CHECK='TRUE';
      NO_DIR_CHECK='TRUE';
      ALLOW_CONNECT='TRUE';
    'VDDCR_CPU0_E51':
      PIN_NUMBER='(0,0,0,0,0,0,0,0,0,0,0,0,0,0,0,0,0,0,0,0,0,0,0,E51,0,0,0,0,0,0,0,0,0,0,0,0,0,0,0,0)';
      PINUSE='POWER';
      NO_LOAD_CHECK='Both';
      NO_IO_CHECK='Both';
      NO_ASSERT_CHECK='TRUE';
      NO_DIR_CHECK='TRUE';
      ALLOW_CONNECT='TRUE';
    'VDDCR_CPU0_E48':
      PIN_NUMBER='(0,0,0,0,0,0,0,0,0,0,0,0,0,0,0,0,0,0,0,0,0,0,0,E48,0,0,0,0,0,0,0,0,0,0,0,0,0,0,0,0)';
      PINUSE='POWER';
      NO_LOAD_CHECK='Both';
      NO_IO_CHECK='Both';
      NO_ASSERT_CHECK='TRUE';
      NO_DIR_CHECK='TRUE';
      ALLOW_CONNECT='TRUE';
    'VDDCR_CPU0_E45':
      PIN_NUMBER='(0,0,0,0,0,0,0,0,0,0,0,0,0,0,0,0,0,0,0,0,0,0,0,E45,0,0,0,0,0,0,0,0,0,0,0,0,0,0,0,0)';
      PINUSE='POWER';
      NO_LOAD_CHECK='Both';
      NO_IO_CHECK='Both';
      NO_ASSERT_CHECK='TRUE';
      NO_DIR_CHECK='TRUE';
      ALLOW_CONNECT='TRUE';
    'VDDCR_CPU0_E42':
      PIN_NUMBER='(0,0,0,0,0,0,0,0,0,0,0,0,0,0,0,0,0,0,0,0,0,0,0,E42,0,0,0,0,0,0,0,0,0,0,0,0,0,0,0,0)';
      PINUSE='POWER';
      NO_LOAD_CHECK='Both';
      NO_IO_CHECK='Both';
      NO_ASSERT_CHECK='TRUE';
      NO_DIR_CHECK='TRUE';
      ALLOW_CONNECT='TRUE';
    'VDDCR_CPU0_E35':
      PIN_NUMBER='(0,0,0,0,0,0,0,0,0,0,0,0,0,0,0,0,0,0,0,0,0,0,0,E35,0,0,0,0,0,0,0,0,0,0,0,0,0,0,0,0)';
      PINUSE='POWER';
      NO_LOAD_CHECK='Both';
      NO_IO_CHECK='Both';
      NO_ASSERT_CHECK='TRUE';
      NO_DIR_CHECK='TRUE';
      ALLOW_CONNECT='TRUE';
    'VDDCR_CPU0_E34':
      PIN_NUMBER='(0,0,0,0,0,0,0,0,0,0,0,0,0,0,0,0,0,0,0,0,0,0,0,E34,0,0,0,0,0,0,0,0,0,0,0,0,0,0,0,0)';
      PINUSE='POWER';
      NO_LOAD_CHECK='Both';
      NO_IO_CHECK='Both';
      NO_ASSERT_CHECK='TRUE';
      NO_DIR_CHECK='TRUE';
      ALLOW_CONNECT='TRUE';
    'VDDCR_CPU0_E31':
      PIN_NUMBER='(0,0,0,0,0,0,0,0,0,0,0,0,0,0,0,0,0,0,0,0,0,0,0,E31,0,0,0,0,0,0,0,0,0,0,0,0,0,0,0,0)';
      PINUSE='POWER';
      NO_LOAD_CHECK='Both';
      NO_IO_CHECK='Both';
      NO_ASSERT_CHECK='TRUE';
      NO_DIR_CHECK='TRUE';
      ALLOW_CONNECT='TRUE';
    'VDDCR_CPU0_E28':
      PIN_NUMBER='(0,0,0,0,0,0,0,0,0,0,0,0,0,0,0,0,0,0,0,0,0,0,0,E28,0,0,0,0,0,0,0,0,0,0,0,0,0,0,0,0)';
      PINUSE='POWER';
      NO_LOAD_CHECK='Both';
      NO_IO_CHECK='Both';
      NO_ASSERT_CHECK='TRUE';
      NO_DIR_CHECK='TRUE';
      ALLOW_CONNECT='TRUE';
    'VDDCR_CPU0_E25':
      PIN_NUMBER='(0,0,0,0,0,0,0,0,0,0,0,0,0,0,0,0,0,0,0,0,0,0,0,E25,0,0,0,0,0,0,0,0,0,0,0,0,0,0,0,0)';
      PINUSE='POWER';
      NO_LOAD_CHECK='Both';
      NO_IO_CHECK='Both';
      NO_ASSERT_CHECK='TRUE';
      NO_DIR_CHECK='TRUE';
      ALLOW_CONNECT='TRUE';
    'VDDCR_CPU0_E22':
      PIN_NUMBER='(0,0,0,0,0,0,0,0,0,0,0,0,0,0,0,0,0,0,0,0,0,0,0,E22,0,0,0,0,0,0,0,0,0,0,0,0,0,0,0,0)';
      PINUSE='POWER';
      NO_LOAD_CHECK='Both';
      NO_IO_CHECK='Both';
      NO_ASSERT_CHECK='TRUE';
      NO_DIR_CHECK='TRUE';
      ALLOW_CONNECT='TRUE';
    'VDDCR_CPU0_D56':
      PIN_NUMBER='(0,0,0,0,0,0,0,0,0,0,0,0,0,0,0,0,0,0,0,0,0,0,0,D56,0,0,0,0,0,0,0,0,0,0,0,0,0,0,0,0)';
      PINUSE='POWER';
      NO_LOAD_CHECK='Both';
      NO_IO_CHECK='Both';
      NO_ASSERT_CHECK='TRUE';
      NO_DIR_CHECK='TRUE';
      ALLOW_CONNECT='TRUE';
    'VDDCR_CPU0_D55':
      PIN_NUMBER='(0,0,0,0,0,0,0,0,0,0,0,0,0,0,0,0,0,0,0,0,0,0,0,D55,0,0,0,0,0,0,0,0,0,0,0,0,0,0,0,0)';
      PINUSE='POWER';
      NO_LOAD_CHECK='Both';
      NO_IO_CHECK='Both';
      NO_ASSERT_CHECK='TRUE';
      NO_DIR_CHECK='TRUE';
      ALLOW_CONNECT='TRUE';
    'VDDCR_CPU0_C20':
      PIN_NUMBER='(0,0,0,0,0,0,0,0,0,0,0,0,0,0,0,0,0,0,0,0,0,0,0,C20,0,0,0,0,0,0,0,0,0,0,0,0,0,0,0,0)';
      PINUSE='POWER';
      NO_LOAD_CHECK='Both';
      NO_IO_CHECK='Both';
      NO_ASSERT_CHECK='TRUE';
      NO_DIR_CHECK='TRUE';
      ALLOW_CONNECT='TRUE';
    'VDDCR_CPU0_B57':
      PIN_NUMBER='(0,0,0,0,0,0,0,0,0,0,0,0,0,0,0,0,0,0,0,0,0,0,0,B57,0,0,0,0,0,0,0,0,0,0,0,0,0,0,0,0)';
      PINUSE='POWER';
      NO_LOAD_CHECK='Both';
      NO_IO_CHECK='Both';
      NO_ASSERT_CHECK='TRUE';
      NO_DIR_CHECK='TRUE';
      ALLOW_CONNECT='TRUE';
    'VDDCR_CPU0_B56':
      PIN_NUMBER='(0,0,0,0,0,0,0,0,0,0,0,0,0,0,0,0,0,0,0,0,0,0,0,B56,0,0,0,0,0,0,0,0,0,0,0,0,0,0,0,0)';
      PINUSE='POWER';
      NO_LOAD_CHECK='Both';
      NO_IO_CHECK='Both';
      NO_ASSERT_CHECK='TRUE';
      NO_DIR_CHECK='TRUE';
      ALLOW_CONNECT='TRUE';
    'VDDCR_CPU0_B54':
      PIN_NUMBER='(0,0,0,0,0,0,0,0,0,0,0,0,0,0,0,0,0,0,0,0,0,0,0,B54,0,0,0,0,0,0,0,0,0,0,0,0,0,0,0,0)';
      PINUSE='POWER';
      NO_LOAD_CHECK='Both';
      NO_IO_CHECK='Both';
      NO_ASSERT_CHECK='TRUE';
      NO_DIR_CHECK='TRUE';
      ALLOW_CONNECT='TRUE';
    'VDDCR_CPU0_B53':
      PIN_NUMBER='(0,0,0,0,0,0,0,0,0,0,0,0,0,0,0,0,0,0,0,0,0,0,0,B53,0,0,0,0,0,0,0,0,0,0,0,0,0,0,0,0)';
      PINUSE='POWER';
      NO_LOAD_CHECK='Both';
      NO_IO_CHECK='Both';
      NO_ASSERT_CHECK='TRUE';
      NO_DIR_CHECK='TRUE';
      ALLOW_CONNECT='TRUE';
    'VDDCR_CPU0_B51':
      PIN_NUMBER='(0,0,0,0,0,0,0,0,0,0,0,0,0,0,0,0,0,0,0,0,0,0,0,B51,0,0,0,0,0,0,0,0,0,0,0,0,0,0,0,0)';
      PINUSE='POWER';
      NO_LOAD_CHECK='Both';
      NO_IO_CHECK='Both';
      NO_ASSERT_CHECK='TRUE';
      NO_DIR_CHECK='TRUE';
      ALLOW_CONNECT='TRUE';
    'VDDCR_CPU0_B50':
      PIN_NUMBER='(0,0,0,0,0,0,0,0,0,0,0,0,0,0,0,0,0,0,0,0,0,0,0,B50,0,0,0,0,0,0,0,0,0,0,0,0,0,0,0,0)';
      PINUSE='POWER';
      NO_LOAD_CHECK='Both';
      NO_IO_CHECK='Both';
      NO_ASSERT_CHECK='TRUE';
      NO_DIR_CHECK='TRUE';
      ALLOW_CONNECT='TRUE';
    'VDDCR_CPU0_B48':
      PIN_NUMBER='(0,0,0,0,0,0,0,0,0,0,0,0,0,0,0,0,0,0,0,0,0,0,0,B48,0,0,0,0,0,0,0,0,0,0,0,0,0,0,0,0)';
      PINUSE='POWER';
      NO_LOAD_CHECK='Both';
      NO_IO_CHECK='Both';
      NO_ASSERT_CHECK='TRUE';
      NO_DIR_CHECK='TRUE';
      ALLOW_CONNECT='TRUE';
    'VDDCR_CPU0_B47':
      PIN_NUMBER='(0,0,0,0,0,0,0,0,0,0,0,0,0,0,0,0,0,0,0,0,0,0,0,B47,0,0,0,0,0,0,0,0,0,0,0,0,0,0,0,0)';
      PINUSE='POWER';
      NO_LOAD_CHECK='Both';
      NO_IO_CHECK='Both';
      NO_ASSERT_CHECK='TRUE';
      NO_DIR_CHECK='TRUE';
      ALLOW_CONNECT='TRUE';
    'VDDCR_CPU0_B45':
      PIN_NUMBER='(0,0,0,0,0,0,0,0,0,0,0,0,0,0,0,0,0,0,0,0,0,0,0,B45,0,0,0,0,0,0,0,0,0,0,0,0,0,0,0,0)';
      PINUSE='POWER';
      NO_LOAD_CHECK='Both';
      NO_IO_CHECK='Both';
      NO_ASSERT_CHECK='TRUE';
      NO_DIR_CHECK='TRUE';
      ALLOW_CONNECT='TRUE';
    'VDDCR_CPU0_B44':
      PIN_NUMBER='(0,0,0,0,0,0,0,0,0,0,0,0,0,0,0,0,0,0,0,0,0,0,0,B44,0,0,0,0,0,0,0,0,0,0,0,0,0,0,0,0)';
      PINUSE='POWER';
      NO_LOAD_CHECK='Both';
      NO_IO_CHECK='Both';
      NO_ASSERT_CHECK='TRUE';
      NO_DIR_CHECK='TRUE';
      ALLOW_CONNECT='TRUE';
    'VDDCR_CPU0_B42':
      PIN_NUMBER='(0,0,0,0,0,0,0,0,0,0,0,0,0,0,0,0,0,0,0,0,0,0,0,B42,0,0,0,0,0,0,0,0,0,0,0,0,0,0,0,0)';
      PINUSE='POWER';
      NO_LOAD_CHECK='Both';
      NO_IO_CHECK='Both';
      NO_ASSERT_CHECK='TRUE';
      NO_DIR_CHECK='TRUE';
      ALLOW_CONNECT='TRUE';
    'VDDCR_CPU0_B41':
      PIN_NUMBER='(0,0,0,0,0,0,0,0,0,0,0,0,0,0,0,0,0,0,0,0,0,0,0,B41,0,0,0,0,0,0,0,0,0,0,0,0,0,0,0,0)';
      PINUSE='POWER';
      NO_LOAD_CHECK='Both';
      NO_IO_CHECK='Both';
      NO_ASSERT_CHECK='TRUE';
      NO_DIR_CHECK='TRUE';
      ALLOW_CONNECT='TRUE';
    'VDDCR_CPU0_B35':
      PIN_NUMBER='(0,0,0,0,0,0,0,0,0,0,0,0,0,0,0,0,0,0,0,0,0,0,0,B35,0,0,0,0,0,0,0,0,0,0,0,0,0,0,0,0)';
      PINUSE='POWER';
      NO_LOAD_CHECK='Both';
      NO_IO_CHECK='Both';
      NO_ASSERT_CHECK='TRUE';
      NO_DIR_CHECK='TRUE';
      ALLOW_CONNECT='TRUE';
    'VDDCR_CPU0_B34':
      PIN_NUMBER='(0,0,0,0,0,0,0,0,0,0,0,0,0,0,0,0,0,0,0,0,0,0,0,B34,0,0,0,0,0,0,0,0,0,0,0,0,0,0,0,0)';
      PINUSE='POWER';
      NO_LOAD_CHECK='Both';
      NO_IO_CHECK='Both';
      NO_ASSERT_CHECK='TRUE';
      NO_DIR_CHECK='TRUE';
      ALLOW_CONNECT='TRUE';
    'VDDCR_CPU0_B32':
      PIN_NUMBER='(0,0,0,0,0,0,0,0,0,0,0,0,0,0,0,0,0,0,0,0,0,0,0,B32,0,0,0,0,0,0,0,0,0,0,0,0,0,0,0,0)';
      PINUSE='POWER';
      NO_LOAD_CHECK='Both';
      NO_IO_CHECK='Both';
      NO_ASSERT_CHECK='TRUE';
      NO_DIR_CHECK='TRUE';
      ALLOW_CONNECT='TRUE';
    'VDDCR_CPU0_B31':
      PIN_NUMBER='(0,0,0,0,0,0,0,0,0,0,0,0,0,0,0,0,0,0,0,0,0,0,0,B31,0,0,0,0,0,0,0,0,0,0,0,0,0,0,0,0)';
      PINUSE='POWER';
      NO_LOAD_CHECK='Both';
      NO_IO_CHECK='Both';
      NO_ASSERT_CHECK='TRUE';
      NO_DIR_CHECK='TRUE';
      ALLOW_CONNECT='TRUE';
    'VDDCR_CPU0_B29':
      PIN_NUMBER='(0,0,0,0,0,0,0,0,0,0,0,0,0,0,0,0,0,0,0,0,0,0,0,B29,0,0,0,0,0,0,0,0,0,0,0,0,0,0,0,0)';
      PINUSE='POWER';
      NO_LOAD_CHECK='Both';
      NO_IO_CHECK='Both';
      NO_ASSERT_CHECK='TRUE';
      NO_DIR_CHECK='TRUE';
      ALLOW_CONNECT='TRUE';
    'VDDCR_CPU0_B28':
      PIN_NUMBER='(0,0,0,0,0,0,0,0,0,0,0,0,0,0,0,0,0,0,0,0,0,0,0,B28,0,0,0,0,0,0,0,0,0,0,0,0,0,0,0,0)';
      PINUSE='POWER';
      NO_LOAD_CHECK='Both';
      NO_IO_CHECK='Both';
      NO_ASSERT_CHECK='TRUE';
      NO_DIR_CHECK='TRUE';
      ALLOW_CONNECT='TRUE';
    'VDDCR_CPU0_B26':
      PIN_NUMBER='(0,0,0,0,0,0,0,0,0,0,0,0,0,0,0,0,0,0,0,0,0,0,0,B26,0,0,0,0,0,0,0,0,0,0,0,0,0,0,0,0)';
      PINUSE='POWER';
      NO_LOAD_CHECK='Both';
      NO_IO_CHECK='Both';
      NO_ASSERT_CHECK='TRUE';
      NO_DIR_CHECK='TRUE';
      ALLOW_CONNECT='TRUE';
    'VDDCR_CPU0_B25':
      PIN_NUMBER='(0,0,0,0,0,0,0,0,0,0,0,0,0,0,0,0,0,0,0,0,0,0,0,B25,0,0,0,0,0,0,0,0,0,0,0,0,0,0,0,0)';
      PINUSE='POWER';
      NO_LOAD_CHECK='Both';
      NO_IO_CHECK='Both';
      NO_ASSERT_CHECK='TRUE';
      NO_DIR_CHECK='TRUE';
      ALLOW_CONNECT='TRUE';
    'VDDCR_CPU0_B23':
      PIN_NUMBER='(0,0,0,0,0,0,0,0,0,0,0,0,0,0,0,0,0,0,0,0,0,0,0,B23,0,0,0,0,0,0,0,0,0,0,0,0,0,0,0,0)';
      PINUSE='POWER';
      NO_LOAD_CHECK='Both';
      NO_IO_CHECK='Both';
      NO_ASSERT_CHECK='TRUE';
      NO_DIR_CHECK='TRUE';
      ALLOW_CONNECT='TRUE';
    'VDDCR_CPU0_B22':
      PIN_NUMBER='(0,0,0,0,0,0,0,0,0,0,0,0,0,0,0,0,0,0,0,0,0,0,0,B22,0,0,0,0,0,0,0,0,0,0,0,0,0,0,0,0)';
      PINUSE='POWER';
      NO_LOAD_CHECK='Both';
      NO_IO_CHECK='Both';
      NO_ASSERT_CHECK='TRUE';
      NO_DIR_CHECK='TRUE';
      ALLOW_CONNECT='TRUE';
    'VDDCR_CPU0_B20':
      PIN_NUMBER='(0,0,0,0,0,0,0,0,0,0,0,0,0,0,0,0,0,0,0,0,0,0,0,B20,0,0,0,0,0,0,0,0,0,0,0,0,0,0,0,0)';
      PINUSE='POWER';
      NO_LOAD_CHECK='Both';
      NO_IO_CHECK='Both';
      NO_ASSERT_CHECK='TRUE';
      NO_DIR_CHECK='TRUE';
      ALLOW_CONNECT='TRUE';
    'VDDCR_CPU0_B19':
      PIN_NUMBER='(0,0,0,0,0,0,0,0,0,0,0,0,0,0,0,0,0,0,0,0,0,0,0,B19,0,0,0,0,0,0,0,0,0,0,0,0,0,0,0,0)';
      PINUSE='POWER';
      NO_LOAD_CHECK='Both';
      NO_IO_CHECK='Both';
      NO_ASSERT_CHECK='TRUE';
      NO_DIR_CHECK='TRUE';
      ALLOW_CONNECT='TRUE';
    'VDDCR_CPU0_AT47':
      PIN_NUMBER='(0,0,0,0,0,0,0,0,0,0,0,0,0,0,0,0,0,0,0,0,0,0,0,AT47,0,0,0,0,0,0,0,0,0,0,0,0,0,0,0,0)';
      PINUSE='POWER';
      NO_LOAD_CHECK='Both';
      NO_IO_CHECK='Both';
      NO_ASSERT_CHECK='TRUE';
      NO_DIR_CHECK='TRUE';
      ALLOW_CONNECT='TRUE';
    'VDDCR_CPU0_AT45':
      PIN_NUMBER='(0,0,0,0,0,0,0,0,0,0,0,0,0,0,0,0,0,0,0,0,0,0,0,AT45,0,0,0,0,0,0,0,0,0,0,0,0,0,0,0,0)';
      PINUSE='POWER';
      NO_LOAD_CHECK='Both';
      NO_IO_CHECK='Both';
      NO_ASSERT_CHECK='TRUE';
      NO_DIR_CHECK='TRUE';
      ALLOW_CONNECT='TRUE';
    'VDDCR_CPU0_AT43':
      PIN_NUMBER='(0,0,0,0,0,0,0,0,0,0,0,0,0,0,0,0,0,0,0,0,0,0,0,AT43,0,0,0,0,0,0,0,0,0,0,0,0,0,0,0,0)';
      PINUSE='POWER';
      NO_LOAD_CHECK='Both';
      NO_IO_CHECK='Both';
      NO_ASSERT_CHECK='TRUE';
      NO_DIR_CHECK='TRUE';
      ALLOW_CONNECT='TRUE';
    'VDDCR_CPU0_AT41':
      PIN_NUMBER='(0,0,0,0,0,0,0,0,0,0,0,0,0,0,0,0,0,0,0,0,0,0,0,AT41,0,0,0,0,0,0,0,0,0,0,0,0,0,0,0,0)';
      PINUSE='POWER';
      NO_LOAD_CHECK='Both';
      NO_IO_CHECK='Both';
      NO_ASSERT_CHECK='TRUE';
      NO_DIR_CHECK='TRUE';
      ALLOW_CONNECT='TRUE';
    'VDDCR_CPU0_AT39':
      PIN_NUMBER='(0,0,0,0,0,0,0,0,0,0,0,0,0,0,0,0,0,0,0,0,0,0,0,AT39,0,0,0,0,0,0,0,0,0,0,0,0,0,0,0,0)';
      PINUSE='POWER';
      NO_LOAD_CHECK='Both';
      NO_IO_CHECK='Both';
      NO_ASSERT_CHECK='TRUE';
      NO_DIR_CHECK='TRUE';
      ALLOW_CONNECT='TRUE';
    'VDDCR_CPU0_AT36':
      PIN_NUMBER='(0,0,0,0,0,0,0,0,0,0,0,0,0,0,0,0,0,0,0,0,0,0,0,AT36,0,0,0,0,0,0,0,0,0,0,0,0,0,0,0,0)';
      PINUSE='POWER';
      NO_LOAD_CHECK='Both';
      NO_IO_CHECK='Both';
      NO_ASSERT_CHECK='TRUE';
      NO_DIR_CHECK='TRUE';
      ALLOW_CONNECT='TRUE';
    'VDDCR_CPU0_AT34':
      PIN_NUMBER='(0,0,0,0,0,0,0,0,0,0,0,0,0,0,0,0,0,0,0,0,0,0,0,AT34,0,0,0,0,0,0,0,0,0,0,0,0,0,0,0,0)';
      PINUSE='POWER';
      NO_LOAD_CHECK='Both';
      NO_IO_CHECK='Both';
      NO_ASSERT_CHECK='TRUE';
      NO_DIR_CHECK='TRUE';
      ALLOW_CONNECT='TRUE';
    'VDDCR_CPU0_AT32':
      PIN_NUMBER='(0,0,0,0,0,0,0,0,0,0,0,0,0,0,0,0,0,0,0,0,0,0,0,AT32,0,0,0,0,0,0,0,0,0,0,0,0,0,0,0,0)';
      PINUSE='POWER';
      NO_LOAD_CHECK='Both';
      NO_IO_CHECK='Both';
      NO_ASSERT_CHECK='TRUE';
      NO_DIR_CHECK='TRUE';
      ALLOW_CONNECT='TRUE';
    'VDDCR_CPU0_AT30':
      PIN_NUMBER='(0,0,0,0,0,0,0,0,0,0,0,0,0,0,0,0,0,0,0,0,0,0,0,AT30,0,0,0,0,0,0,0,0,0,0,0,0,0,0,0,0)';
      PINUSE='POWER';
      NO_LOAD_CHECK='Both';
      NO_IO_CHECK='Both';
      NO_ASSERT_CHECK='TRUE';
      NO_DIR_CHECK='TRUE';
      ALLOW_CONNECT='TRUE';
    'VDDCR_CPU0_AT28':
      PIN_NUMBER='(0,0,0,0,0,0,0,0,0,0,0,0,0,0,0,0,0,0,0,0,0,0,0,AT28,0,0,0,0,0,0,0,0,0,0,0,0,0,0,0,0)';
      PINUSE='POWER';
      NO_LOAD_CHECK='Both';
      NO_IO_CHECK='Both';
      NO_ASSERT_CHECK='TRUE';
      NO_DIR_CHECK='TRUE';
      ALLOW_CONNECT='TRUE';
    'VDDCR_CPU0_AT26':
      PIN_NUMBER='(0,0,0,0,0,0,0,0,0,0,0,0,0,0,0,0,0,0,0,0,0,0,0,AT26,0,0,0,0,0,0,0,0,0,0,0,0,0,0,0,0)';
      PINUSE='POWER';
      NO_LOAD_CHECK='Both';
      NO_IO_CHECK='Both';
      NO_ASSERT_CHECK='TRUE';
      NO_DIR_CHECK='TRUE';
      ALLOW_CONNECT='TRUE';
    'VDDCR_CPU0_AT24':
      PIN_NUMBER='(0,0,0,0,0,0,0,0,0,0,0,0,0,0,0,0,0,0,0,0,0,0,0,AT24,0,0,0,0,0,0,0,0,0,0,0,0,0,0,0,0)';
      PINUSE='POWER';
      NO_LOAD_CHECK='Both';
      NO_IO_CHECK='Both';
      NO_ASSERT_CHECK='TRUE';
      NO_DIR_CHECK='TRUE';
      ALLOW_CONNECT='TRUE';
    'VDDCR_CPU0_AR50':
      PIN_NUMBER='(0,0,0,0,0,0,0,0,0,0,0,0,0,0,0,0,0,0,0,0,0,0,0,AR50,0,0,0,0,0,0,0,0,0,0,0,0,0,0,0,0)';
      PINUSE='POWER';
      NO_LOAD_CHECK='Both';
      NO_IO_CHECK='Both';
      NO_ASSERT_CHECK='TRUE';
      NO_DIR_CHECK='TRUE';
      ALLOW_CONNECT='TRUE';
    'VDDCR_CPU0_AR48':
      PIN_NUMBER='(0,0,0,0,0,0,0,0,0,0,0,0,0,0,0,0,0,0,0,0,0,0,0,AR48,0,0,0,0,0,0,0,0,0,0,0,0,0,0,0,0)';
      PINUSE='POWER';
      NO_LOAD_CHECK='Both';
      NO_IO_CHECK='Both';
      NO_ASSERT_CHECK='TRUE';
      NO_DIR_CHECK='TRUE';
      ALLOW_CONNECT='TRUE';
    'VDDCR_CPU0_AR46':
      PIN_NUMBER='(0,0,0,0,0,0,0,0,0,0,0,0,0,0,0,0,0,0,0,0,0,0,0,AR46,0,0,0,0,0,0,0,0,0,0,0,0,0,0,0,0)';
      PINUSE='POWER';
      NO_LOAD_CHECK='Both';
      NO_IO_CHECK='Both';
      NO_ASSERT_CHECK='TRUE';
      NO_DIR_CHECK='TRUE';
      ALLOW_CONNECT='TRUE';
    'VDDCR_CPU0_AR44':
      PIN_NUMBER='(0,0,0,0,0,0,0,0,0,0,0,0,0,0,0,0,0,0,0,0,0,0,0,AR44,0,0,0,0,0,0,0,0,0,0,0,0,0,0,0,0)';
      PINUSE='POWER';
      NO_LOAD_CHECK='Both';
      NO_IO_CHECK='Both';
      NO_ASSERT_CHECK='TRUE';
      NO_DIR_CHECK='TRUE';
      ALLOW_CONNECT='TRUE';
    'VDDCR_CPU0_AR42':
      PIN_NUMBER='(0,0,0,0,0,0,0,0,0,0,0,0,0,0,0,0,0,0,0,0,0,0,0,AR42,0,0,0,0,0,0,0,0,0,0,0,0,0,0,0,0)';
      PINUSE='POWER';
      NO_LOAD_CHECK='Both';
      NO_IO_CHECK='Both';
      NO_ASSERT_CHECK='TRUE';
      NO_DIR_CHECK='TRUE';
      ALLOW_CONNECT='TRUE';
    'VDDCR_CPU0_AR40':
      PIN_NUMBER='(0,0,0,0,0,0,0,0,0,0,0,0,0,0,0,0,0,0,0,0,0,0,0,AR40,0,0,0,0,0,0,0,0,0,0,0,0,0,0,0,0)';
      PINUSE='POWER';
      NO_LOAD_CHECK='Both';
      NO_IO_CHECK='Both';
      NO_ASSERT_CHECK='TRUE';
      NO_DIR_CHECK='TRUE';
      ALLOW_CONNECT='TRUE';
    'VDDCR_CPU0_AR35':
      PIN_NUMBER='(0,0,0,0,0,0,0,0,0,0,0,0,0,0,0,0,0,0,0,0,0,0,0,AR35,0,0,0,0,0,0,0,0,0,0,0,0,0,0,0,0)';
      PINUSE='POWER';
      NO_LOAD_CHECK='Both';
      NO_IO_CHECK='Both';
      NO_ASSERT_CHECK='TRUE';
      NO_DIR_CHECK='TRUE';
      ALLOW_CONNECT='TRUE';
    'VDDCR_CPU0_AR33':
      PIN_NUMBER='(0,0,0,0,0,0,0,0,0,0,0,0,0,0,0,0,0,0,0,0,0,0,0,AR33,0,0,0,0,0,0,0,0,0,0,0,0,0,0,0,0)';
      PINUSE='POWER';
      NO_LOAD_CHECK='Both';
      NO_IO_CHECK='Both';
      NO_ASSERT_CHECK='TRUE';
      NO_DIR_CHECK='TRUE';
      ALLOW_CONNECT='TRUE';
    'VDDCR_CPU0_AR31':
      PIN_NUMBER='(0,0,0,0,0,0,0,0,0,0,0,0,0,0,0,0,0,0,0,0,0,0,0,AR31,0,0,0,0,0,0,0,0,0,0,0,0,0,0,0,0)';
      PINUSE='POWER';
      NO_LOAD_CHECK='Both';
      NO_IO_CHECK='Both';
      NO_ASSERT_CHECK='TRUE';
      NO_DIR_CHECK='TRUE';
      ALLOW_CONNECT='TRUE';
    'VDDCR_CPU0_AR29':
      PIN_NUMBER='(0,0,0,0,0,0,0,0,0,0,0,0,0,0,0,0,0,0,0,0,0,0,0,AR29,0,0,0,0,0,0,0,0,0,0,0,0,0,0,0,0)';
      PINUSE='POWER';
      NO_LOAD_CHECK='Both';
      NO_IO_CHECK='Both';
      NO_ASSERT_CHECK='TRUE';
      NO_DIR_CHECK='TRUE';
      ALLOW_CONNECT='TRUE';
    'VDDCR_CPU0_AR27':
      PIN_NUMBER='(0,0,0,0,0,0,0,0,0,0,0,0,0,0,0,0,0,0,0,0,0,0,0,AR27,0,0,0,0,0,0,0,0,0,0,0,0,0,0,0,0)';
      PINUSE='POWER';
      NO_LOAD_CHECK='Both';
      NO_IO_CHECK='Both';
      NO_ASSERT_CHECK='TRUE';
      NO_DIR_CHECK='TRUE';
      ALLOW_CONNECT='TRUE';
    'VDDCR_CPU0_AR25':
      PIN_NUMBER='(0,0,0,0,0,0,0,0,0,0,0,0,0,0,0,0,0,0,0,0,0,0,0,AR25,0,0,0,0,0,0,0,0,0,0,0,0,0,0,0,0)';
      PINUSE='POWER';
      NO_LOAD_CHECK='Both';
      NO_IO_CHECK='Both';
      NO_ASSERT_CHECK='TRUE';
      NO_DIR_CHECK='TRUE';
      ALLOW_CONNECT='TRUE';
    'VDDCR_CPU0_AR23':
      PIN_NUMBER='(0,0,0,0,0,0,0,0,0,0,0,0,0,0,0,0,0,0,0,0,0,0,0,AR23,0,0,0,0,0,0,0,0,0,0,0,0,0,0,0,0)';
      PINUSE='POWER';
      NO_LOAD_CHECK='Both';
      NO_IO_CHECK='Both';
      NO_ASSERT_CHECK='TRUE';
      NO_DIR_CHECK='TRUE';
      ALLOW_CONNECT='TRUE';
    'VDDCR_CPU0_AP53':
      PIN_NUMBER='(0,0,0,0,0,0,0,0,0,0,0,0,0,0,0,0,0,0,0,0,0,0,0,AP53,0,0,0,0,0,0,0,0,0,0,0,0,0,0,0,0)';
      PINUSE='POWER';
      NO_LOAD_CHECK='Both';
      NO_IO_CHECK='Both';
      NO_ASSERT_CHECK='TRUE';
      NO_DIR_CHECK='TRUE';
      ALLOW_CONNECT='TRUE';
    'VDDCR_CPU0_AP52':
      PIN_NUMBER='(0,0,0,0,0,0,0,0,0,0,0,0,0,0,0,0,0,0,0,0,0,0,0,AP52,0,0,0,0,0,0,0,0,0,0,0,0,0,0,0,0)';
      PINUSE='POWER';
      NO_LOAD_CHECK='Both';
      NO_IO_CHECK='Both';
      NO_ASSERT_CHECK='TRUE';
      NO_DIR_CHECK='TRUE';
      ALLOW_CONNECT='TRUE';
    'VDDCR_CPU0_AP50':
      PIN_NUMBER='(0,0,0,0,0,0,0,0,0,0,0,0,0,0,0,0,0,0,0,0,0,0,0,AP50,0,0,0,0,0,0,0,0,0,0,0,0,0,0,0,0)';
      PINUSE='POWER';
      NO_LOAD_CHECK='Both';
      NO_IO_CHECK='Both';
      NO_ASSERT_CHECK='TRUE';
      NO_DIR_CHECK='TRUE';
      ALLOW_CONNECT='TRUE';
    'VDDCR_CPU0_AP49':
      PIN_NUMBER='(0,0,0,0,0,0,0,0,0,0,0,0,0,0,0,0,0,0,0,0,0,0,0,AP49,0,0,0,0,0,0,0,0,0,0,0,0,0,0,0,0)';
      PINUSE='POWER';
      NO_LOAD_CHECK='Both';
      NO_IO_CHECK='Both';
      NO_ASSERT_CHECK='TRUE';
      NO_DIR_CHECK='TRUE';
      ALLOW_CONNECT='TRUE';
    'VDDCR_CPU0_AP47':
      PIN_NUMBER='(0,0,0,0,0,0,0,0,0,0,0,0,0,0,0,0,0,0,0,0,0,0,0,AP47,0,0,0,0,0,0,0,0,0,0,0,0,0,0,0,0)';
      PINUSE='POWER';
      NO_LOAD_CHECK='Both';
      NO_IO_CHECK='Both';
      NO_ASSERT_CHECK='TRUE';
      NO_DIR_CHECK='TRUE';
      ALLOW_CONNECT='TRUE';
    'VDDCR_CPU0_AP46':
      PIN_NUMBER='(0,0,0,0,0,0,0,0,0,0,0,0,0,0,0,0,0,0,0,0,0,0,0,AP46,0,0,0,0,0,0,0,0,0,0,0,0,0,0,0,0)';
      PINUSE='POWER';
      NO_LOAD_CHECK='Both';
      NO_IO_CHECK='Both';
      NO_ASSERT_CHECK='TRUE';
      NO_DIR_CHECK='TRUE';
      ALLOW_CONNECT='TRUE';
    'VDDCR_CPU0_AP44':
      PIN_NUMBER='(0,0,0,0,0,0,0,0,0,0,0,0,0,0,0,0,0,0,0,0,0,0,0,AP44,0,0,0,0,0,0,0,0,0,0,0,0,0,0,0,0)';
      PINUSE='POWER';
      NO_LOAD_CHECK='Both';
      NO_IO_CHECK='Both';
      NO_ASSERT_CHECK='TRUE';
      NO_DIR_CHECK='TRUE';
      ALLOW_CONNECT='TRUE';
    'VDDCR_CPU0_AP43':
      PIN_NUMBER='(0,0,0,0,0,0,0,0,0,0,0,0,0,0,0,0,0,0,0,0,0,0,0,AP43,0,0,0,0,0,0,0,0,0,0,0,0,0,0,0,0)';
      PINUSE='POWER';
      NO_LOAD_CHECK='Both';
      NO_IO_CHECK='Both';
      NO_ASSERT_CHECK='TRUE';
      NO_DIR_CHECK='TRUE';
      ALLOW_CONNECT='TRUE';
    'VDDCR_CPU0_AP33':
      PIN_NUMBER='(0,0,0,0,0,0,0,0,0,0,0,0,0,0,0,0,0,0,0,0,0,0,0,AP33,0,0,0,0,0,0,0,0,0,0,0,0,0,0,0,0)';
      PINUSE='POWER';
      NO_LOAD_CHECK='Both';
      NO_IO_CHECK='Both';
      NO_ASSERT_CHECK='TRUE';
      NO_DIR_CHECK='TRUE';
      ALLOW_CONNECT='TRUE';
    'VDDCR_CPU0_AP32':
      PIN_NUMBER='(0,0,0,0,0,0,0,0,0,0,0,0,0,0,0,0,0,0,0,0,0,0,0,AP32,0,0,0,0,0,0,0,0,0,0,0,0,0,0,0,0)';
      PINUSE='POWER';
      NO_LOAD_CHECK='Both';
      NO_IO_CHECK='Both';
      NO_ASSERT_CHECK='TRUE';
      NO_DIR_CHECK='TRUE';
      ALLOW_CONNECT='TRUE';
    'VDDCR_CPU0_AP30':
      PIN_NUMBER='(0,0,0,0,0,0,0,0,0,0,0,0,0,0,0,0,0,0,0,0,0,0,0,AP30,0,0,0,0,0,0,0,0,0,0,0,0,0,0,0,0)';
      PINUSE='POWER';
      NO_LOAD_CHECK='Both';
      NO_IO_CHECK='Both';
      NO_ASSERT_CHECK='TRUE';
      NO_DIR_CHECK='TRUE';
      ALLOW_CONNECT='TRUE';
    'VDDCR_CPU0_AP29':
      PIN_NUMBER='(0,0,0,0,0,0,0,0,0,0,0,0,0,0,0,0,0,0,0,0,0,0,0,AP29,0,0,0,0,0,0,0,0,0,0,0,0,0,0,0,0)';
      PINUSE='POWER';
      NO_LOAD_CHECK='Both';
      NO_IO_CHECK='Both';
      NO_ASSERT_CHECK='TRUE';
      NO_DIR_CHECK='TRUE';
      ALLOW_CONNECT='TRUE';
    'VDDCR_CPU0_AP27':
      PIN_NUMBER='(0,0,0,0,0,0,0,0,0,0,0,0,0,0,0,0,0,0,0,0,0,0,0,AP27,0,0,0,0,0,0,0,0,0,0,0,0,0,0,0,0)';
      PINUSE='POWER';
      NO_LOAD_CHECK='Both';
      NO_IO_CHECK='Both';
      NO_ASSERT_CHECK='TRUE';
      NO_DIR_CHECK='TRUE';
      ALLOW_CONNECT='TRUE';
    'VDDCR_CPU0_AP26':
      PIN_NUMBER='(0,0,0,0,0,0,0,0,0,0,0,0,0,0,0,0,0,0,0,0,0,0,0,AP26,0,0,0,0,0,0,0,0,0,0,0,0,0,0,0,0)';
      PINUSE='POWER';
      NO_LOAD_CHECK='Both';
      NO_IO_CHECK='Both';
      NO_ASSERT_CHECK='TRUE';
      NO_DIR_CHECK='TRUE';
      ALLOW_CONNECT='TRUE';
    'VDDCR_CPU0_AP24':
      PIN_NUMBER='(0,0,0,0,0,0,0,0,0,0,0,0,0,0,0,0,0,0,0,0,0,0,0,AP24,0,0,0,0,0,0,0,0,0,0,0,0,0,0,0,0)';
      PINUSE='POWER';
      NO_LOAD_CHECK='Both';
      NO_IO_CHECK='Both';
      NO_ASSERT_CHECK='TRUE';
      NO_DIR_CHECK='TRUE';
      ALLOW_CONNECT='TRUE';
    'VDDCR_CPU0_AP23':
      PIN_NUMBER='(0,0,0,0,0,0,0,0,0,0,0,0,0,0,0,0,0,0,0,0,0,0,0,AP23,0,0,0,0,0,0,0,0,0,0,0,0,0,0,0,0)';
      PINUSE='POWER';
      NO_LOAD_CHECK='Both';
      NO_IO_CHECK='Both';
      NO_ASSERT_CHECK='TRUE';
      NO_DIR_CHECK='TRUE';
      ALLOW_CONNECT='TRUE';
    'VDDCR_CPU0_AL41':
      PIN_NUMBER='(0,0,0,0,0,0,0,0,0,0,0,0,0,0,0,0,0,0,0,0,0,0,0,AL41,0,0,0,0,0,0,0,0,0,0,0,0,0,0,0,0)';
      PINUSE='POWER';
      NO_LOAD_CHECK='Both';
      NO_IO_CHECK='Both';
      NO_ASSERT_CHECK='TRUE';
      NO_DIR_CHECK='TRUE';
      ALLOW_CONNECT='TRUE';
    'VDDCR_CPU0_AL40':
      PIN_NUMBER='(0,0,0,0,0,0,0,0,0,0,0,0,0,0,0,0,0,0,0,0,0,0,0,AL40,0,0,0,0,0,0,0,0,0,0,0,0,0,0,0,0)';
      PINUSE='POWER';
      NO_LOAD_CHECK='Both';
      NO_IO_CHECK='Both';
      NO_ASSERT_CHECK='TRUE';
      NO_DIR_CHECK='TRUE';
      ALLOW_CONNECT='TRUE';
    'VDDCR_CPU0_AL36':
      PIN_NUMBER='(0,0,0,0,0,0,0,0,0,0,0,0,0,0,0,0,0,0,0,0,0,0,0,AL36,0,0,0,0,0,0,0,0,0,0,0,0,0,0,0,0)';
      PINUSE='POWER';
      NO_LOAD_CHECK='Both';
      NO_IO_CHECK='Both';
      NO_ASSERT_CHECK='TRUE';
      NO_DIR_CHECK='TRUE';
      ALLOW_CONNECT='TRUE';
    'VDDCR_CPU0_AL35':
      PIN_NUMBER='(0,0,0,0,0,0,0,0,0,0,0,0,0,0,0,0,0,0,0,0,0,0,0,AL35,0,0,0,0,0,0,0,0,0,0,0,0,0,0,0,0)';
      PINUSE='POWER';
      NO_LOAD_CHECK='Both';
      NO_IO_CHECK='Both';
      NO_ASSERT_CHECK='TRUE';
      NO_DIR_CHECK='TRUE';
      ALLOW_CONNECT='TRUE';
    'VDDCR_CPU0_AK53':
      PIN_NUMBER='(0,0,0,0,0,0,0,0,0,0,0,0,0,0,0,0,0,0,0,0,0,0,0,AK53,0,0,0,0,0,0,0,0,0,0,0,0,0,0,0,0)';
      PINUSE='POWER';
      NO_LOAD_CHECK='Both';
      NO_IO_CHECK='Both';
      NO_ASSERT_CHECK='TRUE';
      NO_DIR_CHECK='TRUE';
      ALLOW_CONNECT='TRUE';
    'VDDCR_CPU0_AK52':
      PIN_NUMBER='(0,0,0,0,0,0,0,0,0,0,0,0,0,0,0,0,0,0,0,0,0,0,0,AK52,0,0,0,0,0,0,0,0,0,0,0,0,0,0,0,0)';
      PINUSE='POWER';
      NO_LOAD_CHECK='Both';
      NO_IO_CHECK='Both';
      NO_ASSERT_CHECK='TRUE';
      NO_DIR_CHECK='TRUE';
      ALLOW_CONNECT='TRUE';
    'VDDCR_CPU0_AK50':
      PIN_NUMBER='(0,0,0,0,0,0,0,0,0,0,0,0,0,0,0,0,0,0,0,0,0,0,0,AK50,0,0,0,0,0,0,0,0,0,0,0,0,0,0,0,0)';
      PINUSE='POWER';
      NO_LOAD_CHECK='Both';
      NO_IO_CHECK='Both';
      NO_ASSERT_CHECK='TRUE';
      NO_DIR_CHECK='TRUE';
      ALLOW_CONNECT='TRUE';
    'VDDCR_CPU0_AK49':
      PIN_NUMBER='(0,0,0,0,0,0,0,0,0,0,0,0,0,0,0,0,0,0,0,0,0,0,0,AK49,0,0,0,0,0,0,0,0,0,0,0,0,0,0,0,0)';
      PINUSE='POWER';
      NO_LOAD_CHECK='Both';
      NO_IO_CHECK='Both';
      NO_ASSERT_CHECK='TRUE';
      NO_DIR_CHECK='TRUE';
      ALLOW_CONNECT='TRUE';
    'VDDCR_CPU0_AK47':
      PIN_NUMBER='(0,0,0,0,0,0,0,0,0,0,0,0,0,0,0,0,0,0,0,0,0,0,0,AK47,0,0,0,0,0,0,0,0,0,0,0,0,0,0,0,0)';
      PINUSE='POWER';
      NO_LOAD_CHECK='Both';
      NO_IO_CHECK='Both';
      NO_ASSERT_CHECK='TRUE';
      NO_DIR_CHECK='TRUE';
      ALLOW_CONNECT='TRUE';
    'VDDCR_CPU0_AK46':
      PIN_NUMBER='(0,0,0,0,0,0,0,0,0,0,0,0,0,0,0,0,0,0,0,0,0,0,0,AK46,0,0,0,0,0,0,0,0,0,0,0,0,0,0,0,0)';
      PINUSE='POWER';
      NO_LOAD_CHECK='Both';
      NO_IO_CHECK='Both';
      NO_ASSERT_CHECK='TRUE';
      NO_DIR_CHECK='TRUE';
      ALLOW_CONNECT='TRUE';
    'VDDCR_CPU0_AK44':
      PIN_NUMBER='(0,0,0,0,0,0,0,0,0,0,0,0,0,0,0,0,0,0,0,0,0,0,0,AK44,0,0,0,0,0,0,0,0,0,0,0,0,0,0,0,0)';
      PINUSE='POWER';
      NO_LOAD_CHECK='Both';
      NO_IO_CHECK='Both';
      NO_ASSERT_CHECK='TRUE';
      NO_DIR_CHECK='TRUE';
      ALLOW_CONNECT='TRUE';
    'VDDCR_CPU0_AK43':
      PIN_NUMBER='(0,0,0,0,0,0,0,0,0,0,0,0,0,0,0,0,0,0,0,0,0,0,0,AK43,0,0,0,0,0,0,0,0,0,0,0,0,0,0,0,0)';
      PINUSE='POWER';
      NO_LOAD_CHECK='Both';
      NO_IO_CHECK='Both';
      NO_ASSERT_CHECK='TRUE';
      NO_DIR_CHECK='TRUE';
      ALLOW_CONNECT='TRUE';
    'VDDCR_CPU0_AK33':
      PIN_NUMBER='(0,0,0,0,0,0,0,0,0,0,0,0,0,0,0,0,0,0,0,0,0,0,0,AK33,0,0,0,0,0,0,0,0,0,0,0,0,0,0,0,0)';
      PINUSE='POWER';
      NO_LOAD_CHECK='Both';
      NO_IO_CHECK='Both';
      NO_ASSERT_CHECK='TRUE';
      NO_DIR_CHECK='TRUE';
      ALLOW_CONNECT='TRUE';
    'VDDCR_CPU0_AK32':
      PIN_NUMBER='(0,0,0,0,0,0,0,0,0,0,0,0,0,0,0,0,0,0,0,0,0,0,0,AK32,0,0,0,0,0,0,0,0,0,0,0,0,0,0,0,0)';
      PINUSE='POWER';
      NO_LOAD_CHECK='Both';
      NO_IO_CHECK='Both';
      NO_ASSERT_CHECK='TRUE';
      NO_DIR_CHECK='TRUE';
      ALLOW_CONNECT='TRUE';
    'VDDCR_CPU0_AK30':
      PIN_NUMBER='(0,0,0,0,0,0,0,0,0,0,0,0,0,0,0,0,0,0,0,0,0,0,0,AK30,0,0,0,0,0,0,0,0,0,0,0,0,0,0,0,0)';
      PINUSE='POWER';
      NO_LOAD_CHECK='Both';
      NO_IO_CHECK='Both';
      NO_ASSERT_CHECK='TRUE';
      NO_DIR_CHECK='TRUE';
      ALLOW_CONNECT='TRUE';
    'VDDCR_CPU0_AK29':
      PIN_NUMBER='(0,0,0,0,0,0,0,0,0,0,0,0,0,0,0,0,0,0,0,0,0,0,0,AK29,0,0,0,0,0,0,0,0,0,0,0,0,0,0,0,0)';
      PINUSE='POWER';
      NO_LOAD_CHECK='Both';
      NO_IO_CHECK='Both';
      NO_ASSERT_CHECK='TRUE';
      NO_DIR_CHECK='TRUE';
      ALLOW_CONNECT='TRUE';
    'VDDCR_CPU0_AK27':
      PIN_NUMBER='(0,0,0,0,0,0,0,0,0,0,0,0,0,0,0,0,0,0,0,0,0,0,0,AK27,0,0,0,0,0,0,0,0,0,0,0,0,0,0,0,0)';
      PINUSE='POWER';
      NO_LOAD_CHECK='Both';
      NO_IO_CHECK='Both';
      NO_ASSERT_CHECK='TRUE';
      NO_DIR_CHECK='TRUE';
      ALLOW_CONNECT='TRUE';
    'VDDCR_CPU0_AK26':
      PIN_NUMBER='(0,0,0,0,0,0,0,0,0,0,0,0,0,0,0,0,0,0,0,0,0,0,0,AK26,0,0,0,0,0,0,0,0,0,0,0,0,0,0,0,0)';
      PINUSE='POWER';
      NO_LOAD_CHECK='Both';
      NO_IO_CHECK='Both';
      NO_ASSERT_CHECK='TRUE';
      NO_DIR_CHECK='TRUE';
      ALLOW_CONNECT='TRUE';
    'VDDCR_CPU0_AK24':
      PIN_NUMBER='(0,0,0,0,0,0,0,0,0,0,0,0,0,0,0,0,0,0,0,0,0,0,0,AK24,0,0,0,0,0,0,0,0,0,0,0,0,0,0,0,0)';
      PINUSE='POWER';
      NO_LOAD_CHECK='Both';
      NO_IO_CHECK='Both';
      NO_ASSERT_CHECK='TRUE';
      NO_DIR_CHECK='TRUE';
      ALLOW_CONNECT='TRUE';
    'VDDCR_CPU0_AK23':
      PIN_NUMBER='(0,0,0,0,0,0,0,0,0,0,0,0,0,0,0,0,0,0,0,0,0,0,0,AK23,0,0,0,0,0,0,0,0,0,0,0,0,0,0,0,0)';
      PINUSE='POWER';
      NO_LOAD_CHECK='Both';
      NO_IO_CHECK='Both';
      NO_ASSERT_CHECK='TRUE';
      NO_DIR_CHECK='TRUE';
      ALLOW_CONNECT='TRUE';
    'VDDCR_CPU0_AG41':
      PIN_NUMBER='(0,0,0,0,0,0,0,0,0,0,0,0,0,0,0,0,0,0,0,0,0,0,0,AG41,0,0,0,0,0,0,0,0,0,0,0,0,0,0,0,0)';
      PINUSE='POWER';
      NO_LOAD_CHECK='Both';
      NO_IO_CHECK='Both';
      NO_ASSERT_CHECK='TRUE';
      NO_DIR_CHECK='TRUE';
      ALLOW_CONNECT='TRUE';
    'VDDCR_CPU0_AG40':
      PIN_NUMBER='(0,0,0,0,0,0,0,0,0,0,0,0,0,0,0,0,0,0,0,0,0,0,0,AG40,0,0,0,0,0,0,0,0,0,0,0,0,0,0,0,0)';
      PINUSE='POWER';
      NO_LOAD_CHECK='Both';
      NO_IO_CHECK='Both';
      NO_ASSERT_CHECK='TRUE';
      NO_DIR_CHECK='TRUE';
      ALLOW_CONNECT='TRUE';
    'VDDCR_CPU0_AG36':
      PIN_NUMBER='(0,0,0,0,0,0,0,0,0,0,0,0,0,0,0,0,0,0,0,0,0,0,0,AG36,0,0,0,0,0,0,0,0,0,0,0,0,0,0,0,0)';
      PINUSE='POWER';
      NO_LOAD_CHECK='Both';
      NO_IO_CHECK='Both';
      NO_ASSERT_CHECK='TRUE';
      NO_DIR_CHECK='TRUE';
      ALLOW_CONNECT='TRUE';
    'VDDCR_CPU0_AG35':
      PIN_NUMBER='(0,0,0,0,0,0,0,0,0,0,0,0,0,0,0,0,0,0,0,0,0,0,0,AG35,0,0,0,0,0,0,0,0,0,0,0,0,0,0,0,0)';
      PINUSE='POWER';
      NO_LOAD_CHECK='Both';
      NO_IO_CHECK='Both';
      NO_ASSERT_CHECK='TRUE';
      NO_DIR_CHECK='TRUE';
      ALLOW_CONNECT='TRUE';
    'VDDCR_CPU0_AF53':
      PIN_NUMBER='(0,0,0,0,0,0,0,0,0,0,0,0,0,0,0,0,0,0,0,0,0,0,0,AF53,0,0,0,0,0,0,0,0,0,0,0,0,0,0,0,0)';
      PINUSE='POWER';
      NO_LOAD_CHECK='Both';
      NO_IO_CHECK='Both';
      NO_ASSERT_CHECK='TRUE';
      NO_DIR_CHECK='TRUE';
      ALLOW_CONNECT='TRUE';
    'VDDCR_CPU0_AF52':
      PIN_NUMBER='(0,0,0,0,0,0,0,0,0,0,0,0,0,0,0,0,0,0,0,0,0,0,0,AF52,0,0,0,0,0,0,0,0,0,0,0,0,0,0,0,0)';
      PINUSE='POWER';
      NO_LOAD_CHECK='Both';
      NO_IO_CHECK='Both';
      NO_ASSERT_CHECK='TRUE';
      NO_DIR_CHECK='TRUE';
      ALLOW_CONNECT='TRUE';
    'VDDCR_CPU0_AF50':
      PIN_NUMBER='(0,0,0,0,0,0,0,0,0,0,0,0,0,0,0,0,0,0,0,0,0,0,0,AF50,0,0,0,0,0,0,0,0,0,0,0,0,0,0,0,0)';
      PINUSE='POWER';
      NO_LOAD_CHECK='Both';
      NO_IO_CHECK='Both';
      NO_ASSERT_CHECK='TRUE';
      NO_DIR_CHECK='TRUE';
      ALLOW_CONNECT='TRUE';
    'VDDCR_CPU0_AF49':
      PIN_NUMBER='(0,0,0,0,0,0,0,0,0,0,0,0,0,0,0,0,0,0,0,0,0,0,0,AF49,0,0,0,0,0,0,0,0,0,0,0,0,0,0,0,0)';
      PINUSE='POWER';
      NO_LOAD_CHECK='Both';
      NO_IO_CHECK='Both';
      NO_ASSERT_CHECK='TRUE';
      NO_DIR_CHECK='TRUE';
      ALLOW_CONNECT='TRUE';
    'VDDCR_CPU0_AF47':
      PIN_NUMBER='(0,0,0,0,0,0,0,0,0,0,0,0,0,0,0,0,0,0,0,0,0,0,0,AF47,0,0,0,0,0,0,0,0,0,0,0,0,0,0,0,0)';
      PINUSE='POWER';
      NO_LOAD_CHECK='Both';
      NO_IO_CHECK='Both';
      NO_ASSERT_CHECK='TRUE';
      NO_DIR_CHECK='TRUE';
      ALLOW_CONNECT='TRUE';
    'VDDCR_CPU0_AF46':
      PIN_NUMBER='(0,0,0,0,0,0,0,0,0,0,0,0,0,0,0,0,0,0,0,0,0,0,0,AF46,0,0,0,0,0,0,0,0,0,0,0,0,0,0,0,0)';
      PINUSE='POWER';
      NO_LOAD_CHECK='Both';
      NO_IO_CHECK='Both';
      NO_ASSERT_CHECK='TRUE';
      NO_DIR_CHECK='TRUE';
      ALLOW_CONNECT='TRUE';
    'VDDCR_CPU0_AF44':
      PIN_NUMBER='(0,0,0,0,0,0,0,0,0,0,0,0,0,0,0,0,0,0,0,0,0,0,0,AF44,0,0,0,0,0,0,0,0,0,0,0,0,0,0,0,0)';
      PINUSE='POWER';
      NO_LOAD_CHECK='Both';
      NO_IO_CHECK='Both';
      NO_ASSERT_CHECK='TRUE';
      NO_DIR_CHECK='TRUE';
      ALLOW_CONNECT='TRUE';
    'VDDCR_CPU0_AF43':
      PIN_NUMBER='(0,0,0,0,0,0,0,0,0,0,0,0,0,0,0,0,0,0,0,0,0,0,0,AF43,0,0,0,0,0,0,0,0,0,0,0,0,0,0,0,0)';
      PINUSE='POWER';
      NO_LOAD_CHECK='Both';
      NO_IO_CHECK='Both';
      NO_ASSERT_CHECK='TRUE';
      NO_DIR_CHECK='TRUE';
      ALLOW_CONNECT='TRUE';
    'VDDCR_CPU0_AF33':
      PIN_NUMBER='(0,0,0,0,0,0,0,0,0,0,0,0,0,0,0,0,0,0,0,0,0,0,0,AF33,0,0,0,0,0,0,0,0,0,0,0,0,0,0,0,0)';
      PINUSE='POWER';
      NO_LOAD_CHECK='Both';
      NO_IO_CHECK='Both';
      NO_ASSERT_CHECK='TRUE';
      NO_DIR_CHECK='TRUE';
      ALLOW_CONNECT='TRUE';
    'VDDCR_CPU0_AF32':
      PIN_NUMBER='(0,0,0,0,0,0,0,0,0,0,0,0,0,0,0,0,0,0,0,0,0,0,0,AF32,0,0,0,0,0,0,0,0,0,0,0,0,0,0,0,0)';
      PINUSE='POWER';
      NO_LOAD_CHECK='Both';
      NO_IO_CHECK='Both';
      NO_ASSERT_CHECK='TRUE';
      NO_DIR_CHECK='TRUE';
      ALLOW_CONNECT='TRUE';
    'VDDCR_CPU0_AF30':
      PIN_NUMBER='(0,0,0,0,0,0,0,0,0,0,0,0,0,0,0,0,0,0,0,0,0,0,0,AF30,0,0,0,0,0,0,0,0,0,0,0,0,0,0,0,0)';
      PINUSE='POWER';
      NO_LOAD_CHECK='Both';
      NO_IO_CHECK='Both';
      NO_ASSERT_CHECK='TRUE';
      NO_DIR_CHECK='TRUE';
      ALLOW_CONNECT='TRUE';
    'VDDCR_CPU0_AF29':
      PIN_NUMBER='(0,0,0,0,0,0,0,0,0,0,0,0,0,0,0,0,0,0,0,0,0,0,0,AF29,0,0,0,0,0,0,0,0,0,0,0,0,0,0,0,0)';
      PINUSE='POWER';
      NO_LOAD_CHECK='Both';
      NO_IO_CHECK='Both';
      NO_ASSERT_CHECK='TRUE';
      NO_DIR_CHECK='TRUE';
      ALLOW_CONNECT='TRUE';
    'VDDCR_CPU0_AF27':
      PIN_NUMBER='(0,0,0,0,0,0,0,0,0,0,0,0,0,0,0,0,0,0,0,0,0,0,0,AF27,0,0,0,0,0,0,0,0,0,0,0,0,0,0,0,0)';
      PINUSE='POWER';
      NO_LOAD_CHECK='Both';
      NO_IO_CHECK='Both';
      NO_ASSERT_CHECK='TRUE';
      NO_DIR_CHECK='TRUE';
      ALLOW_CONNECT='TRUE';
    'VDDCR_CPU0_AF26':
      PIN_NUMBER='(0,0,0,0,0,0,0,0,0,0,0,0,0,0,0,0,0,0,0,0,0,0,0,AF26,0,0,0,0,0,0,0,0,0,0,0,0,0,0,0,0)';
      PINUSE='POWER';
      NO_LOAD_CHECK='Both';
      NO_IO_CHECK='Both';
      NO_ASSERT_CHECK='TRUE';
      NO_DIR_CHECK='TRUE';
      ALLOW_CONNECT='TRUE';
    'VDDCR_CPU0_AF24':
      PIN_NUMBER='(0,0,0,0,0,0,0,0,0,0,0,0,0,0,0,0,0,0,0,0,0,0,0,AF24,0,0,0,0,0,0,0,0,0,0,0,0,0,0,0,0)';
      PINUSE='POWER';
      NO_LOAD_CHECK='Both';
      NO_IO_CHECK='Both';
      NO_ASSERT_CHECK='TRUE';
      NO_DIR_CHECK='TRUE';
      ALLOW_CONNECT='TRUE';
    'VDDCR_CPU0_AF23':
      PIN_NUMBER='(0,0,0,0,0,0,0,0,0,0,0,0,0,0,0,0,0,0,0,0,0,0,0,AF23,0,0,0,0,0,0,0,0,0,0,0,0,0,0,0,0)';
      PINUSE='POWER';
      NO_LOAD_CHECK='Both';
      NO_IO_CHECK='Both';
      NO_ASSERT_CHECK='TRUE';
      NO_DIR_CHECK='TRUE';
      ALLOW_CONNECT='TRUE';
    'VDDCR_CPU0_AC41':
      PIN_NUMBER='(0,0,0,0,0,0,0,0,0,0,0,0,0,0,0,0,0,0,0,0,0,0,0,AC41,0,0,0,0,0,0,0,0,0,0,0,0,0,0,0,0)';
      PINUSE='POWER';
      NO_LOAD_CHECK='Both';
      NO_IO_CHECK='Both';
      NO_ASSERT_CHECK='TRUE';
      NO_DIR_CHECK='TRUE';
      ALLOW_CONNECT='TRUE';
    'VDDCR_CPU0_AC40':
      PIN_NUMBER='(0,0,0,0,0,0,0,0,0,0,0,0,0,0,0,0,0,0,0,0,0,0,0,AC40,0,0,0,0,0,0,0,0,0,0,0,0,0,0,0,0)';
      PINUSE='POWER';
      NO_LOAD_CHECK='Both';
      NO_IO_CHECK='Both';
      NO_ASSERT_CHECK='TRUE';
      NO_DIR_CHECK='TRUE';
      ALLOW_CONNECT='TRUE';
    'VDDCR_CPU0_AC36':
      PIN_NUMBER='(0,0,0,0,0,0,0,0,0,0,0,0,0,0,0,0,0,0,0,0,0,0,0,AC36,0,0,0,0,0,0,0,0,0,0,0,0,0,0,0,0)';
      PINUSE='POWER';
      NO_LOAD_CHECK='Both';
      NO_IO_CHECK='Both';
      NO_ASSERT_CHECK='TRUE';
      NO_DIR_CHECK='TRUE';
      ALLOW_CONNECT='TRUE';
    'VDDCR_CPU0_AC35':
      PIN_NUMBER='(0,0,0,0,0,0,0,0,0,0,0,0,0,0,0,0,0,0,0,0,0,0,0,AC35,0,0,0,0,0,0,0,0,0,0,0,0,0,0,0,0)';
      PINUSE='POWER';
      NO_LOAD_CHECK='Both';
      NO_IO_CHECK='Both';
      NO_ASSERT_CHECK='TRUE';
      NO_DIR_CHECK='TRUE';
      ALLOW_CONNECT='TRUE';
    'VDDCR_CPU0_AB53':
      PIN_NUMBER='(0,0,0,0,0,0,0,0,0,0,0,0,0,0,0,0,0,0,0,0,0,0,0,AB53,0,0,0,0,0,0,0,0,0,0,0,0,0,0,0,0)';
      PINUSE='POWER';
      NO_LOAD_CHECK='Both';
      NO_IO_CHECK='Both';
      NO_ASSERT_CHECK='TRUE';
      NO_DIR_CHECK='TRUE';
      ALLOW_CONNECT='TRUE';
    'VDDCR_CPU0_AB52':
      PIN_NUMBER='(0,0,0,0,0,0,0,0,0,0,0,0,0,0,0,0,0,0,0,0,0,0,0,AB52,0,0,0,0,0,0,0,0,0,0,0,0,0,0,0,0)';
      PINUSE='POWER';
      NO_LOAD_CHECK='Both';
      NO_IO_CHECK='Both';
      NO_ASSERT_CHECK='TRUE';
      NO_DIR_CHECK='TRUE';
      ALLOW_CONNECT='TRUE';
    'VDDCR_CPU0_AB50':
      PIN_NUMBER='(0,0,0,0,0,0,0,0,0,0,0,0,0,0,0,0,0,0,0,0,0,0,0,AB50,0,0,0,0,0,0,0,0,0,0,0,0,0,0,0,0)';
      PINUSE='POWER';
      NO_LOAD_CHECK='Both';
      NO_IO_CHECK='Both';
      NO_ASSERT_CHECK='TRUE';
      NO_DIR_CHECK='TRUE';
      ALLOW_CONNECT='TRUE';
    'VDDCR_CPU0_AB49':
      PIN_NUMBER='(0,0,0,0,0,0,0,0,0,0,0,0,0,0,0,0,0,0,0,0,0,0,0,AB49,0,0,0,0,0,0,0,0,0,0,0,0,0,0,0,0)';
      PINUSE='POWER';
      NO_LOAD_CHECK='Both';
      NO_IO_CHECK='Both';
      NO_ASSERT_CHECK='TRUE';
      NO_DIR_CHECK='TRUE';
      ALLOW_CONNECT='TRUE';
    'VDDCR_CPU0_AB47':
      PIN_NUMBER='(0,0,0,0,0,0,0,0,0,0,0,0,0,0,0,0,0,0,0,0,0,0,0,AB47,0,0,0,0,0,0,0,0,0,0,0,0,0,0,0,0)';
      PINUSE='POWER';
      NO_LOAD_CHECK='Both';
      NO_IO_CHECK='Both';
      NO_ASSERT_CHECK='TRUE';
      NO_DIR_CHECK='TRUE';
      ALLOW_CONNECT='TRUE';
    'VDDCR_CPU0_AB46':
      PIN_NUMBER='(0,0,0,0,0,0,0,0,0,0,0,0,0,0,0,0,0,0,0,0,0,0,0,AB46,0,0,0,0,0,0,0,0,0,0,0,0,0,0,0,0)';
      PINUSE='POWER';
      NO_LOAD_CHECK='Both';
      NO_IO_CHECK='Both';
      NO_ASSERT_CHECK='TRUE';
      NO_DIR_CHECK='TRUE';
      ALLOW_CONNECT='TRUE';
    'VDDCR_CPU0_AB44':
      PIN_NUMBER='(0,0,0,0,0,0,0,0,0,0,0,0,0,0,0,0,0,0,0,0,0,0,0,AB44,0,0,0,0,0,0,0,0,0,0,0,0,0,0,0,0)';
      PINUSE='POWER';
      NO_LOAD_CHECK='Both';
      NO_IO_CHECK='Both';
      NO_ASSERT_CHECK='TRUE';
      NO_DIR_CHECK='TRUE';
      ALLOW_CONNECT='TRUE';
    'VDDCR_CPU0_AB43':
      PIN_NUMBER='(0,0,0,0,0,0,0,0,0,0,0,0,0,0,0,0,0,0,0,0,0,0,0,AB43,0,0,0,0,0,0,0,0,0,0,0,0,0,0,0,0)';
      PINUSE='POWER';
      NO_LOAD_CHECK='Both';
      NO_IO_CHECK='Both';
      NO_ASSERT_CHECK='TRUE';
      NO_DIR_CHECK='TRUE';
      ALLOW_CONNECT='TRUE';
    'VDDCR_CPU0_AB33':
      PIN_NUMBER='(0,0,0,0,0,0,0,0,0,0,0,0,0,0,0,0,0,0,0,0,0,0,0,AB33,0,0,0,0,0,0,0,0,0,0,0,0,0,0,0,0)';
      PINUSE='POWER';
      NO_LOAD_CHECK='Both';
      NO_IO_CHECK='Both';
      NO_ASSERT_CHECK='TRUE';
      NO_DIR_CHECK='TRUE';
      ALLOW_CONNECT='TRUE';
    'VDDCR_CPU0_AB32':
      PIN_NUMBER='(0,0,0,0,0,0,0,0,0,0,0,0,0,0,0,0,0,0,0,0,0,0,0,AB32,0,0,0,0,0,0,0,0,0,0,0,0,0,0,0,0)';
      PINUSE='POWER';
      NO_LOAD_CHECK='Both';
      NO_IO_CHECK='Both';
      NO_ASSERT_CHECK='TRUE';
      NO_DIR_CHECK='TRUE';
      ALLOW_CONNECT='TRUE';
    'VDDCR_CPU0_AB30':
      PIN_NUMBER='(0,0,0,0,0,0,0,0,0,0,0,0,0,0,0,0,0,0,0,0,0,0,0,AB30,0,0,0,0,0,0,0,0,0,0,0,0,0,0,0,0)';
      PINUSE='POWER';
      NO_LOAD_CHECK='Both';
      NO_IO_CHECK='Both';
      NO_ASSERT_CHECK='TRUE';
      NO_DIR_CHECK='TRUE';
      ALLOW_CONNECT='TRUE';
    'VDDCR_CPU0_AB29':
      PIN_NUMBER='(0,0,0,0,0,0,0,0,0,0,0,0,0,0,0,0,0,0,0,0,0,0,0,AB29,0,0,0,0,0,0,0,0,0,0,0,0,0,0,0,0)';
      PINUSE='POWER';
      NO_LOAD_CHECK='Both';
      NO_IO_CHECK='Both';
      NO_ASSERT_CHECK='TRUE';
      NO_DIR_CHECK='TRUE';
      ALLOW_CONNECT='TRUE';
    'VDDCR_CPU0_AB27':
      PIN_NUMBER='(0,0,0,0,0,0,0,0,0,0,0,0,0,0,0,0,0,0,0,0,0,0,0,AB27,0,0,0,0,0,0,0,0,0,0,0,0,0,0,0,0)';
      PINUSE='POWER';
      NO_LOAD_CHECK='Both';
      NO_IO_CHECK='Both';
      NO_ASSERT_CHECK='TRUE';
      NO_DIR_CHECK='TRUE';
      ALLOW_CONNECT='TRUE';
    'VDDCR_CPU0_AB26':
      PIN_NUMBER='(0,0,0,0,0,0,0,0,0,0,0,0,0,0,0,0,0,0,0,0,0,0,0,AB26,0,0,0,0,0,0,0,0,0,0,0,0,0,0,0,0)';
      PINUSE='POWER';
      NO_LOAD_CHECK='Both';
      NO_IO_CHECK='Both';
      NO_ASSERT_CHECK='TRUE';
      NO_DIR_CHECK='TRUE';
      ALLOW_CONNECT='TRUE';
    'VDDCR_CPU0_AB24':
      PIN_NUMBER='(0,0,0,0,0,0,0,0,0,0,0,0,0,0,0,0,0,0,0,0,0,0,0,AB24,0,0,0,0,0,0,0,0,0,0,0,0,0,0,0,0)';
      PINUSE='POWER';
      NO_LOAD_CHECK='Both';
      NO_IO_CHECK='Both';
      NO_ASSERT_CHECK='TRUE';
      NO_DIR_CHECK='TRUE';
      ALLOW_CONNECT='TRUE';
    'VDDCR_CPU0_AB23':
      PIN_NUMBER='(0,0,0,0,0,0,0,0,0,0,0,0,0,0,0,0,0,0,0,0,0,0,0,AB23,0,0,0,0,0,0,0,0,0,0,0,0,0,0,0,0)';
      PINUSE='POWER';
      NO_LOAD_CHECK='Both';
      NO_IO_CHECK='Both';
      NO_ASSERT_CHECK='TRUE';
      NO_DIR_CHECK='TRUE';
      ALLOW_CONNECT='TRUE';
    'VDDCR_CPU0_Y41':
      PIN_NUMBER='(0,0,0,0,0,0,0,0,0,0,0,0,0,0,0,0,0,0,0,0,0,0,0,Y41,0,0,0,0,0,0,0,0,0,0,0,0,0,0,0,0)';
      PINUSE='POWER';
      NO_LOAD_CHECK='Both';
      NO_IO_CHECK='Both';
      NO_ASSERT_CHECK='TRUE';
      NO_DIR_CHECK='TRUE';
      ALLOW_CONNECT='TRUE';
    'VDDCR_CPU0_Y40':
      PIN_NUMBER='(0,0,0,0,0,0,0,0,0,0,0,0,0,0,0,0,0,0,0,0,0,0,0,Y40,0,0,0,0,0,0,0,0,0,0,0,0,0,0,0,0)';
      PINUSE='POWER';
      NO_LOAD_CHECK='Both';
      NO_IO_CHECK='Both';
      NO_ASSERT_CHECK='TRUE';
      NO_DIR_CHECK='TRUE';
      ALLOW_CONNECT='TRUE';
    'VDDCR_CPU0_Y36':
      PIN_NUMBER='(0,0,0,0,0,0,0,0,0,0,0,0,0,0,0,0,0,0,0,0,0,0,0,Y36,0,0,0,0,0,0,0,0,0,0,0,0,0,0,0,0)';
      PINUSE='POWER';
      NO_LOAD_CHECK='Both';
      NO_IO_CHECK='Both';
      NO_ASSERT_CHECK='TRUE';
      NO_DIR_CHECK='TRUE';
      ALLOW_CONNECT='TRUE';
    'VDDCR_CPU0_Y35':
      PIN_NUMBER='(0,0,0,0,0,0,0,0,0,0,0,0,0,0,0,0,0,0,0,0,0,0,0,Y35,0,0,0,0,0,0,0,0,0,0,0,0,0,0,0,0)';
      PINUSE='POWER';
      NO_LOAD_CHECK='Both';
      NO_IO_CHECK='Both';
      NO_ASSERT_CHECK='TRUE';
      NO_DIR_CHECK='TRUE';
      ALLOW_CONNECT='TRUE';
    'VDDCR_CPU0_AU42':
      PIN_NUMBER='(0,0,0,0,0,0,0,0,0,0,0,0,0,0,0,0,0,0,0,0,0,0,0,AU42,0,0,0,0,0,0,0,0,0,0,0,0,0,0,0,0)';
      PINUSE='POWER';
      NO_LOAD_CHECK='Both';
      NO_IO_CHECK='Both';
      NO_ASSERT_CHECK='TRUE';
      NO_DIR_CHECK='TRUE';
      ALLOW_CONNECT='TRUE';
    'VDDCR_CPU0_AU46':
      PIN_NUMBER='(0,0,0,0,0,0,0,0,0,0,0,0,0,0,0,0,0,0,0,0,0,0,0,AU46,0,0,0,0,0,0,0,0,0,0,0,0,0,0,0,0)';
      PINUSE='POWER';
      NO_LOAD_CHECK='Both';
      NO_IO_CHECK='Both';
      NO_ASSERT_CHECK='TRUE';
      NO_DIR_CHECK='TRUE';
      ALLOW_CONNECT='TRUE';
    'VDDCR_CPU0_AT49':
      PIN_NUMBER='(0,0,0,0,0,0,0,0,0,0,0,0,0,0,0,0,0,0,0,0,0,0,0,AT49,0,0,0,0,0,0,0,0,0,0,0,0,0,0,0,0)';
      PINUSE='POWER';
      NO_LOAD_CHECK='Both';
      NO_IO_CHECK='Both';
      NO_ASSERT_CHECK='TRUE';
      NO_DIR_CHECK='TRUE';
      ALLOW_CONNECT='TRUE';
    'VDDCR_CPU0_AU29':
      PIN_NUMBER='(0,0,0,0,0,0,0,0,0,0,0,0,0,0,0,0,0,0,0,0,0,0,0,AU29,0,0,0,0,0,0,0,0,0,0,0,0,0,0,0,0)';
      PINUSE='POWER';
      NO_LOAD_CHECK='Both';
      NO_IO_CHECK='Both';
      NO_ASSERT_CHECK='TRUE';
      NO_DIR_CHECK='TRUE';
      ALLOW_CONNECT='TRUE';
    'VDDCR_CPU0_AU44':
      PIN_NUMBER='(0,0,0,0,0,0,0,0,0,0,0,0,0,0,0,0,0,0,0,0,0,0,0,AU44,0,0,0,0,0,0,0,0,0,0,0,0,0,0,0,0)';
      PINUSE='POWER';
      NO_LOAD_CHECK='Both';
      NO_IO_CHECK='Both';
      NO_ASSERT_CHECK='TRUE';
      NO_DIR_CHECK='TRUE';
      ALLOW_CONNECT='TRUE';
    'VDDCR_CPU0_AU48':
      PIN_NUMBER='(0,0,0,0,0,0,0,0,0,0,0,0,0,0,0,0,0,0,0,0,0,0,0,AU48,0,0,0,0,0,0,0,0,0,0,0,0,0,0,0,0)';
      PINUSE='POWER';
      NO_LOAD_CHECK='Both';
      NO_IO_CHECK='Both';
      NO_ASSERT_CHECK='TRUE';
      NO_DIR_CHECK='TRUE';
      ALLOW_CONNECT='TRUE';
    'VDDCR_CPU0_AU25':
      PIN_NUMBER='(0,0,0,0,0,0,0,0,0,0,0,0,0,0,0,0,0,0,0,0,0,0,0,AU25,0,0,0,0,0,0,0,0,0,0,0,0,0,0,0,0)';
      PINUSE='POWER';
      NO_LOAD_CHECK='Both';
      NO_IO_CHECK='Both';
      NO_ASSERT_CHECK='TRUE';
      NO_DIR_CHECK='TRUE';
      ALLOW_CONNECT='TRUE';
    'VDDCR_CPU0_AU33':
      PIN_NUMBER='(0,0,0,0,0,0,0,0,0,0,0,0,0,0,0,0,0,0,0,0,0,0,0,AU33,0,0,0,0,0,0,0,0,0,0,0,0,0,0,0,0)';
      PINUSE='POWER';
      NO_LOAD_CHECK='Both';
      NO_IO_CHECK='Both';
      NO_ASSERT_CHECK='TRUE';
      NO_DIR_CHECK='TRUE';
      ALLOW_CONNECT='TRUE';
    'VDDCR_CPU1_BN31':
      PIN_NUMBER='(0,0,0,0,0,0,0,0,0,0,0,0,0,0,0,0,0,0,0,0,0,0,0,0,BN31,0,0,0,0,0,0,0,0,0,0,0,0,0,0,0)';
      PINUSE='POWER';
      NO_LOAD_CHECK='Both';
      NO_IO_CHECK='Both';
      NO_ASSERT_CHECK='TRUE';
      NO_DIR_CHECK='TRUE';
      ALLOW_CONNECT='TRUE';
    'VDDCR_CPU1_BN42':
      PIN_NUMBER='(0,0,0,0,0,0,0,0,0,0,0,0,0,0,0,0,0,0,0,0,0,0,0,0,BN42,0,0,0,0,0,0,0,0,0,0,0,0,0,0,0)';
      PINUSE='POWER';
      NO_LOAD_CHECK='Both';
      NO_IO_CHECK='Both';
      NO_ASSERT_CHECK='TRUE';
      NO_DIR_CHECK='TRUE';
      ALLOW_CONNECT='TRUE';
    'VDDCR_CPU1_BN50':
      PIN_NUMBER='(0,0,0,0,0,0,0,0,0,0,0,0,0,0,0,0,0,0,0,0,0,0,0,0,BN50,0,0,0,0,0,0,0,0,0,0,0,0,0,0,0)';
      PINUSE='POWER';
      NO_LOAD_CHECK='Both';
      NO_IO_CHECK='Both';
      NO_ASSERT_CHECK='TRUE';
      NO_DIR_CHECK='TRUE';
      ALLOW_CONNECT='TRUE';
    'VDDCR_CPU1_BP26':
      PIN_NUMBER='(0,0,0,0,0,0,0,0,0,0,0,0,0,0,0,0,0,0,0,0,0,0,0,0,BP26,0,0,0,0,0,0,0,0,0,0,0,0,0,0,0)';
      PINUSE='POWER';
      NO_LOAD_CHECK='Both';
      NO_IO_CHECK='Both';
      NO_ASSERT_CHECK='TRUE';
      NO_DIR_CHECK='TRUE';
      ALLOW_CONNECT='TRUE';
    'VDDCR_CPU1_BP30':
      PIN_NUMBER='(0,0,0,0,0,0,0,0,0,0,0,0,0,0,0,0,0,0,0,0,0,0,0,0,BP30,0,0,0,0,0,0,0,0,0,0,0,0,0,0,0)';
      PINUSE='POWER';
      NO_LOAD_CHECK='Both';
      NO_IO_CHECK='Both';
      NO_ASSERT_CHECK='TRUE';
      NO_DIR_CHECK='TRUE';
      ALLOW_CONNECT='TRUE';
    'VDDCR_CPU1_BP34':
      PIN_NUMBER='(0,0,0,0,0,0,0,0,0,0,0,0,0,0,0,0,0,0,0,0,0,0,0,0,BP34,0,0,0,0,0,0,0,0,0,0,0,0,0,0,0)';
      PINUSE='POWER';
      NO_LOAD_CHECK='Both';
      NO_IO_CHECK='Both';
      NO_ASSERT_CHECK='TRUE';
      NO_DIR_CHECK='TRUE';
      ALLOW_CONNECT='TRUE';
    'VDDCR_CPU1_BP36':
      PIN_NUMBER='(0,0,0,0,0,0,0,0,0,0,0,0,0,0,0,0,0,0,0,0,0,0,0,0,BP36,0,0,0,0,0,0,0,0,0,0,0,0,0,0,0)';
      PINUSE='POWER';
      NO_LOAD_CHECK='Both';
      NO_IO_CHECK='Both';
      NO_ASSERT_CHECK='TRUE';
      NO_DIR_CHECK='TRUE';
      ALLOW_CONNECT='TRUE';
    'VDDCR_CPU1_BP39':
      PIN_NUMBER='(0,0,0,0,0,0,0,0,0,0,0,0,0,0,0,0,0,0,0,0,0,0,0,0,BP39,0,0,0,0,0,0,0,0,0,0,0,0,0,0,0)';
      PINUSE='POWER';
      NO_LOAD_CHECK='Both';
      NO_IO_CHECK='Both';
      NO_ASSERT_CHECK='TRUE';
      NO_DIR_CHECK='TRUE';
      ALLOW_CONNECT='TRUE';
    'VDDCR_CPU1_BP41':
      PIN_NUMBER='(0,0,0,0,0,0,0,0,0,0,0,0,0,0,0,0,0,0,0,0,0,0,0,0,BP41,0,0,0,0,0,0,0,0,0,0,0,0,0,0,0)';
      PINUSE='POWER';
      NO_LOAD_CHECK='Both';
      NO_IO_CHECK='Both';
      NO_ASSERT_CHECK='TRUE';
      NO_DIR_CHECK='TRUE';
      ALLOW_CONNECT='TRUE';
    'VDDCR_CPU1_BP43':
      PIN_NUMBER='(0,0,0,0,0,0,0,0,0,0,0,0,0,0,0,0,0,0,0,0,0,0,0,0,BP43,0,0,0,0,0,0,0,0,0,0,0,0,0,0,0)';
      PINUSE='POWER';
      NO_LOAD_CHECK='Both';
      NO_IO_CHECK='Both';
      NO_ASSERT_CHECK='TRUE';
      NO_DIR_CHECK='TRUE';
      ALLOW_CONNECT='TRUE';
    'VDDCR_CPU1_BP45':
      PIN_NUMBER='(0,0,0,0,0,0,0,0,0,0,0,0,0,0,0,0,0,0,0,0,0,0,0,0,BP45,0,0,0,0,0,0,0,0,0,0,0,0,0,0,0)';
      PINUSE='POWER';
      NO_LOAD_CHECK='Both';
      NO_IO_CHECK='Both';
      NO_ASSERT_CHECK='TRUE';
      NO_DIR_CHECK='TRUE';
      ALLOW_CONNECT='TRUE';
    'VDDCR_CPU1_BP47':
      PIN_NUMBER='(0,0,0,0,0,0,0,0,0,0,0,0,0,0,0,0,0,0,0,0,0,0,0,0,BP47,0,0,0,0,0,0,0,0,0,0,0,0,0,0,0)';
      PINUSE='POWER';
      NO_LOAD_CHECK='Both';
      NO_IO_CHECK='Both';
      NO_ASSERT_CHECK='TRUE';
      NO_DIR_CHECK='TRUE';
      ALLOW_CONNECT='TRUE';
    'VDDCR_CPU1_BP49':
      PIN_NUMBER='(0,0,0,0,0,0,0,0,0,0,0,0,0,0,0,0,0,0,0,0,0,0,0,0,BP49,0,0,0,0,0,0,0,0,0,0,0,0,0,0,0)';
      PINUSE='POWER';
      NO_LOAD_CHECK='Both';
      NO_IO_CHECK='Both';
      NO_ASSERT_CHECK='TRUE';
      NO_DIR_CHECK='TRUE';
      ALLOW_CONNECT='TRUE';
    'VDDCR_CPU1_BR23':
      PIN_NUMBER='(0,0,0,0,0,0,0,0,0,0,0,0,0,0,0,0,0,0,0,0,0,0,0,0,BR23,0,0,0,0,0,0,0,0,0,0,0,0,0,0,0)';
      PINUSE='POWER';
      NO_LOAD_CHECK='Both';
      NO_IO_CHECK='Both';
      NO_ASSERT_CHECK='TRUE';
      NO_DIR_CHECK='TRUE';
      ALLOW_CONNECT='TRUE';
    'VDDCR_CPU1_BR25':
      PIN_NUMBER='(0,0,0,0,0,0,0,0,0,0,0,0,0,0,0,0,0,0,0,0,0,0,0,0,BR25,0,0,0,0,0,0,0,0,0,0,0,0,0,0,0)';
      PINUSE='POWER';
      NO_LOAD_CHECK='Both';
      NO_IO_CHECK='Both';
      NO_ASSERT_CHECK='TRUE';
      NO_DIR_CHECK='TRUE';
      ALLOW_CONNECT='TRUE';
    'VDDCR_CPU1_BR27':
      PIN_NUMBER='(0,0,0,0,0,0,0,0,0,0,0,0,0,0,0,0,0,0,0,0,0,0,0,0,BR27,0,0,0,0,0,0,0,0,0,0,0,0,0,0,0)';
      PINUSE='POWER';
      NO_LOAD_CHECK='Both';
      NO_IO_CHECK='Both';
      NO_ASSERT_CHECK='TRUE';
      NO_DIR_CHECK='TRUE';
      ALLOW_CONNECT='TRUE';
    'VDDCR_CPU1_BR29':
      PIN_NUMBER='(0,0,0,0,0,0,0,0,0,0,0,0,0,0,0,0,0,0,0,0,0,0,0,0,BR29,0,0,0,0,0,0,0,0,0,0,0,0,0,0,0)';
      PINUSE='POWER';
      NO_LOAD_CHECK='Both';
      NO_IO_CHECK='Both';
      NO_ASSERT_CHECK='TRUE';
      NO_DIR_CHECK='TRUE';
      ALLOW_CONNECT='TRUE';
    'VDDCR_CPU1_BR31':
      PIN_NUMBER='(0,0,0,0,0,0,0,0,0,0,0,0,0,0,0,0,0,0,0,0,0,0,0,0,BR31,0,0,0,0,0,0,0,0,0,0,0,0,0,0,0)';
      PINUSE='POWER';
      NO_LOAD_CHECK='Both';
      NO_IO_CHECK='Both';
      NO_ASSERT_CHECK='TRUE';
      NO_DIR_CHECK='TRUE';
      ALLOW_CONNECT='TRUE';
    'VDDCR_CPU1_BR33':
      PIN_NUMBER='(0,0,0,0,0,0,0,0,0,0,0,0,0,0,0,0,0,0,0,0,0,0,0,0,BR33,0,0,0,0,0,0,0,0,0,0,0,0,0,0,0)';
      PINUSE='POWER';
      NO_LOAD_CHECK='Both';
      NO_IO_CHECK='Both';
      NO_ASSERT_CHECK='TRUE';
      NO_DIR_CHECK='TRUE';
      ALLOW_CONNECT='TRUE';
    'VDDCR_CPU1_BR35':
      PIN_NUMBER='(0,0,0,0,0,0,0,0,0,0,0,0,0,0,0,0,0,0,0,0,0,0,0,0,BR35,0,0,0,0,0,0,0,0,0,0,0,0,0,0,0)';
      PINUSE='POWER';
      NO_LOAD_CHECK='Both';
      NO_IO_CHECK='Both';
      NO_ASSERT_CHECK='TRUE';
      NO_DIR_CHECK='TRUE';
      ALLOW_CONNECT='TRUE';
    'VDDCR_CPU1_BR40':
      PIN_NUMBER='(0,0,0,0,0,0,0,0,0,0,0,0,0,0,0,0,0,0,0,0,0,0,0,0,BR40,0,0,0,0,0,0,0,0,0,0,0,0,0,0,0)';
      PINUSE='POWER';
      NO_LOAD_CHECK='Both';
      NO_IO_CHECK='Both';
      NO_ASSERT_CHECK='TRUE';
      NO_DIR_CHECK='TRUE';
      ALLOW_CONNECT='TRUE';
    'VDDCR_CPU1_BR42':
      PIN_NUMBER='(0,0,0,0,0,0,0,0,0,0,0,0,0,0,0,0,0,0,0,0,0,0,0,0,BR42,0,0,0,0,0,0,0,0,0,0,0,0,0,0,0)';
      PINUSE='POWER';
      NO_LOAD_CHECK='Both';
      NO_IO_CHECK='Both';
      NO_ASSERT_CHECK='TRUE';
      NO_DIR_CHECK='TRUE';
      ALLOW_CONNECT='TRUE';
    'VDDCR_CPU1_BR44':
      PIN_NUMBER='(0,0,0,0,0,0,0,0,0,0,0,0,0,0,0,0,0,0,0,0,0,0,0,0,BR44,0,0,0,0,0,0,0,0,0,0,0,0,0,0,0)';
      PINUSE='POWER';
      NO_LOAD_CHECK='Both';
      NO_IO_CHECK='Both';
      NO_ASSERT_CHECK='TRUE';
      NO_DIR_CHECK='TRUE';
      ALLOW_CONNECT='TRUE';
    'VDDCR_CPU1_BR46':
      PIN_NUMBER='(0,0,0,0,0,0,0,0,0,0,0,0,0,0,0,0,0,0,0,0,0,0,0,0,BR46,0,0,0,0,0,0,0,0,0,0,0,0,0,0,0)';
      PINUSE='POWER';
      NO_LOAD_CHECK='Both';
      NO_IO_CHECK='Both';
      NO_ASSERT_CHECK='TRUE';
      NO_DIR_CHECK='TRUE';
      ALLOW_CONNECT='TRUE';
    'VDDCR_CPU1_BR48':
      PIN_NUMBER='(0,0,0,0,0,0,0,0,0,0,0,0,0,0,0,0,0,0,0,0,0,0,0,0,BR48,0,0,0,0,0,0,0,0,0,0,0,0,0,0,0)';
      PINUSE='POWER';
      NO_LOAD_CHECK='Both';
      NO_IO_CHECK='Both';
      NO_ASSERT_CHECK='TRUE';
      NO_DIR_CHECK='TRUE';
      ALLOW_CONNECT='TRUE';
    'VDDCR_CPU1_BR50':
      PIN_NUMBER='(0,0,0,0,0,0,0,0,0,0,0,0,0,0,0,0,0,0,0,0,0,0,0,0,BR50,0,0,0,0,0,0,0,0,0,0,0,0,0,0,0)';
      PINUSE='POWER';
      NO_LOAD_CHECK='Both';
      NO_IO_CHECK='Both';
      NO_ASSERT_CHECK='TRUE';
      NO_DIR_CHECK='TRUE';
      ALLOW_CONNECT='TRUE';
    'VDDCR_CPU1_BR52':
      PIN_NUMBER='(0,0,0,0,0,0,0,0,0,0,0,0,0,0,0,0,0,0,0,0,0,0,0,0,BR52,0,0,0,0,0,0,0,0,0,0,0,0,0,0,0)';
      PINUSE='POWER';
      NO_LOAD_CHECK='Both';
      NO_IO_CHECK='Both';
      NO_ASSERT_CHECK='TRUE';
      NO_DIR_CHECK='TRUE';
      ALLOW_CONNECT='TRUE';
    'VDDCR_CPU1_BT23':
      PIN_NUMBER='(0,0,0,0,0,0,0,0,0,0,0,0,0,0,0,0,0,0,0,0,0,0,0,0,BT23,0,0,0,0,0,0,0,0,0,0,0,0,0,0,0)';
      PINUSE='POWER';
      NO_LOAD_CHECK='Both';
      NO_IO_CHECK='Both';
      NO_ASSERT_CHECK='TRUE';
      NO_DIR_CHECK='TRUE';
      ALLOW_CONNECT='TRUE';
    'VDDCR_CPU1_BT24':
      PIN_NUMBER='(0,0,0,0,0,0,0,0,0,0,0,0,0,0,0,0,0,0,0,0,0,0,0,0,BT24,0,0,0,0,0,0,0,0,0,0,0,0,0,0,0)';
      PINUSE='POWER';
      NO_LOAD_CHECK='Both';
      NO_IO_CHECK='Both';
      NO_ASSERT_CHECK='TRUE';
      NO_DIR_CHECK='TRUE';
      ALLOW_CONNECT='TRUE';
    'VDDCR_CPU1_BT26':
      PIN_NUMBER='(0,0,0,0,0,0,0,0,0,0,0,0,0,0,0,0,0,0,0,0,0,0,0,0,BT26,0,0,0,0,0,0,0,0,0,0,0,0,0,0,0)';
      PINUSE='POWER';
      NO_LOAD_CHECK='Both';
      NO_IO_CHECK='Both';
      NO_ASSERT_CHECK='TRUE';
      NO_DIR_CHECK='TRUE';
      ALLOW_CONNECT='TRUE';
    'VDDCR_CPU1_BT27':
      PIN_NUMBER='(0,0,0,0,0,0,0,0,0,0,0,0,0,0,0,0,0,0,0,0,0,0,0,0,BT27,0,0,0,0,0,0,0,0,0,0,0,0,0,0,0)';
      PINUSE='POWER';
      NO_LOAD_CHECK='Both';
      NO_IO_CHECK='Both';
      NO_ASSERT_CHECK='TRUE';
      NO_DIR_CHECK='TRUE';
      ALLOW_CONNECT='TRUE';
    'VDDCR_CPU1_BT29':
      PIN_NUMBER='(0,0,0,0,0,0,0,0,0,0,0,0,0,0,0,0,0,0,0,0,0,0,0,0,BT29,0,0,0,0,0,0,0,0,0,0,0,0,0,0,0)';
      PINUSE='POWER';
      NO_LOAD_CHECK='Both';
      NO_IO_CHECK='Both';
      NO_ASSERT_CHECK='TRUE';
      NO_DIR_CHECK='TRUE';
      ALLOW_CONNECT='TRUE';
    'VDDCR_CPU1_BT30':
      PIN_NUMBER='(0,0,0,0,0,0,0,0,0,0,0,0,0,0,0,0,0,0,0,0,0,0,0,0,BT30,0,0,0,0,0,0,0,0,0,0,0,0,0,0,0)';
      PINUSE='POWER';
      NO_LOAD_CHECK='Both';
      NO_IO_CHECK='Both';
      NO_ASSERT_CHECK='TRUE';
      NO_DIR_CHECK='TRUE';
      ALLOW_CONNECT='TRUE';
    'VDDCR_CPU1_BT32':
      PIN_NUMBER='(0,0,0,0,0,0,0,0,0,0,0,0,0,0,0,0,0,0,0,0,0,0,0,0,BT32,0,0,0,0,0,0,0,0,0,0,0,0,0,0,0)';
      PINUSE='POWER';
      NO_LOAD_CHECK='Both';
      NO_IO_CHECK='Both';
      NO_ASSERT_CHECK='TRUE';
      NO_DIR_CHECK='TRUE';
      ALLOW_CONNECT='TRUE';
    'VDDCR_CPU1_BT33':
      PIN_NUMBER='(0,0,0,0,0,0,0,0,0,0,0,0,0,0,0,0,0,0,0,0,0,0,0,0,BT33,0,0,0,0,0,0,0,0,0,0,0,0,0,0,0)';
      PINUSE='POWER';
      NO_LOAD_CHECK='Both';
      NO_IO_CHECK='Both';
      NO_ASSERT_CHECK='TRUE';
      NO_DIR_CHECK='TRUE';
      ALLOW_CONNECT='TRUE';
    'VDDCR_CPU1_BT43':
      PIN_NUMBER='(0,0,0,0,0,0,0,0,0,0,0,0,0,0,0,0,0,0,0,0,0,0,0,0,BT43,0,0,0,0,0,0,0,0,0,0,0,0,0,0,0)';
      PINUSE='POWER';
      NO_LOAD_CHECK='Both';
      NO_IO_CHECK='Both';
      NO_ASSERT_CHECK='TRUE';
      NO_DIR_CHECK='TRUE';
      ALLOW_CONNECT='TRUE';
    'VDDCR_CPU1_BT44':
      PIN_NUMBER='(0,0,0,0,0,0,0,0,0,0,0,0,0,0,0,0,0,0,0,0,0,0,0,0,BT44,0,0,0,0,0,0,0,0,0,0,0,0,0,0,0)';
      PINUSE='POWER';
      NO_LOAD_CHECK='Both';
      NO_IO_CHECK='Both';
      NO_ASSERT_CHECK='TRUE';
      NO_DIR_CHECK='TRUE';
      ALLOW_CONNECT='TRUE';
    'VDDCR_CPU1_BT46':
      PIN_NUMBER='(0,0,0,0,0,0,0,0,0,0,0,0,0,0,0,0,0,0,0,0,0,0,0,0,BT46,0,0,0,0,0,0,0,0,0,0,0,0,0,0,0)';
      PINUSE='POWER';
      NO_LOAD_CHECK='Both';
      NO_IO_CHECK='Both';
      NO_ASSERT_CHECK='TRUE';
      NO_DIR_CHECK='TRUE';
      ALLOW_CONNECT='TRUE';
    'VDDCR_CPU1_BT47':
      PIN_NUMBER='(0,0,0,0,0,0,0,0,0,0,0,0,0,0,0,0,0,0,0,0,0,0,0,0,BT47,0,0,0,0,0,0,0,0,0,0,0,0,0,0,0)';
      PINUSE='POWER';
      NO_LOAD_CHECK='Both';
      NO_IO_CHECK='Both';
      NO_ASSERT_CHECK='TRUE';
      NO_DIR_CHECK='TRUE';
      ALLOW_CONNECT='TRUE';
    'VDDCR_CPU1_BT49':
      PIN_NUMBER='(0,0,0,0,0,0,0,0,0,0,0,0,0,0,0,0,0,0,0,0,0,0,0,0,BT49,0,0,0,0,0,0,0,0,0,0,0,0,0,0,0)';
      PINUSE='POWER';
      NO_LOAD_CHECK='Both';
      NO_IO_CHECK='Both';
      NO_ASSERT_CHECK='TRUE';
      NO_DIR_CHECK='TRUE';
      ALLOW_CONNECT='TRUE';
    'VDDCR_CPU1_BT50':
      PIN_NUMBER='(0,0,0,0,0,0,0,0,0,0,0,0,0,0,0,0,0,0,0,0,0,0,0,0,BT50,0,0,0,0,0,0,0,0,0,0,0,0,0,0,0)';
      PINUSE='POWER';
      NO_LOAD_CHECK='Both';
      NO_IO_CHECK='Both';
      NO_ASSERT_CHECK='TRUE';
      NO_DIR_CHECK='TRUE';
      ALLOW_CONNECT='TRUE';
    'VDDCR_CPU1_BT52':
      PIN_NUMBER='(0,0,0,0,0,0,0,0,0,0,0,0,0,0,0,0,0,0,0,0,0,0,0,0,BT52,0,0,0,0,0,0,0,0,0,0,0,0,0,0,0)';
      PINUSE='POWER';
      NO_LOAD_CHECK='Both';
      NO_IO_CHECK='Both';
      NO_ASSERT_CHECK='TRUE';
      NO_DIR_CHECK='TRUE';
      ALLOW_CONNECT='TRUE';
    'VDDCR_CPU1_BT53':
      PIN_NUMBER='(0,0,0,0,0,0,0,0,0,0,0,0,0,0,0,0,0,0,0,0,0,0,0,0,BT53,0,0,0,0,0,0,0,0,0,0,0,0,0,0,0)';
      PINUSE='POWER';
      NO_LOAD_CHECK='Both';
      NO_IO_CHECK='Both';
      NO_ASSERT_CHECK='TRUE';
      NO_DIR_CHECK='TRUE';
      ALLOW_CONNECT='TRUE';
    'VDDCR_CPU1_BW35':
      PIN_NUMBER='(0,0,0,0,0,0,0,0,0,0,0,0,0,0,0,0,0,0,0,0,0,0,0,0,BW35,0,0,0,0,0,0,0,0,0,0,0,0,0,0,0)';
      PINUSE='POWER';
      NO_LOAD_CHECK='Both';
      NO_IO_CHECK='Both';
      NO_ASSERT_CHECK='TRUE';
      NO_DIR_CHECK='TRUE';
      ALLOW_CONNECT='TRUE';
    'VDDCR_CPU1_BW36':
      PIN_NUMBER='(0,0,0,0,0,0,0,0,0,0,0,0,0,0,0,0,0,0,0,0,0,0,0,0,BW36,0,0,0,0,0,0,0,0,0,0,0,0,0,0,0)';
      PINUSE='POWER';
      NO_LOAD_CHECK='Both';
      NO_IO_CHECK='Both';
      NO_ASSERT_CHECK='TRUE';
      NO_DIR_CHECK='TRUE';
      ALLOW_CONNECT='TRUE';
    'VDDCR_CPU1_BW40':
      PIN_NUMBER='(0,0,0,0,0,0,0,0,0,0,0,0,0,0,0,0,0,0,0,0,0,0,0,0,BW40,0,0,0,0,0,0,0,0,0,0,0,0,0,0,0)';
      PINUSE='POWER';
      NO_LOAD_CHECK='Both';
      NO_IO_CHECK='Both';
      NO_ASSERT_CHECK='TRUE';
      NO_DIR_CHECK='TRUE';
      ALLOW_CONNECT='TRUE';
    'VDDCR_CPU1_BW41':
      PIN_NUMBER='(0,0,0,0,0,0,0,0,0,0,0,0,0,0,0,0,0,0,0,0,0,0,0,0,BW41,0,0,0,0,0,0,0,0,0,0,0,0,0,0,0)';
      PINUSE='POWER';
      NO_LOAD_CHECK='Both';
      NO_IO_CHECK='Both';
      NO_ASSERT_CHECK='TRUE';
      NO_DIR_CHECK='TRUE';
      ALLOW_CONNECT='TRUE';
    'VDDCR_CPU1_BY23':
      PIN_NUMBER='(0,0,0,0,0,0,0,0,0,0,0,0,0,0,0,0,0,0,0,0,0,0,0,0,BY23,0,0,0,0,0,0,0,0,0,0,0,0,0,0,0)';
      PINUSE='POWER';
      NO_LOAD_CHECK='Both';
      NO_IO_CHECK='Both';
      NO_ASSERT_CHECK='TRUE';
      NO_DIR_CHECK='TRUE';
      ALLOW_CONNECT='TRUE';
    'VDDCR_CPU1_BY24':
      PIN_NUMBER='(0,0,0,0,0,0,0,0,0,0,0,0,0,0,0,0,0,0,0,0,0,0,0,0,BY24,0,0,0,0,0,0,0,0,0,0,0,0,0,0,0)';
      PINUSE='POWER';
      NO_LOAD_CHECK='Both';
      NO_IO_CHECK='Both';
      NO_ASSERT_CHECK='TRUE';
      NO_DIR_CHECK='TRUE';
      ALLOW_CONNECT='TRUE';
    'VDDCR_CPU1_BY26':
      PIN_NUMBER='(0,0,0,0,0,0,0,0,0,0,0,0,0,0,0,0,0,0,0,0,0,0,0,0,BY26,0,0,0,0,0,0,0,0,0,0,0,0,0,0,0)';
      PINUSE='POWER';
      NO_LOAD_CHECK='Both';
      NO_IO_CHECK='Both';
      NO_ASSERT_CHECK='TRUE';
      NO_DIR_CHECK='TRUE';
      ALLOW_CONNECT='TRUE';
    'VDDCR_CPU1_BY27':
      PIN_NUMBER='(0,0,0,0,0,0,0,0,0,0,0,0,0,0,0,0,0,0,0,0,0,0,0,0,BY27,0,0,0,0,0,0,0,0,0,0,0,0,0,0,0)';
      PINUSE='POWER';
      NO_LOAD_CHECK='Both';
      NO_IO_CHECK='Both';
      NO_ASSERT_CHECK='TRUE';
      NO_DIR_CHECK='TRUE';
      ALLOW_CONNECT='TRUE';
    'VDDCR_CPU1_BY29':
      PIN_NUMBER='(0,0,0,0,0,0,0,0,0,0,0,0,0,0,0,0,0,0,0,0,0,0,0,0,BY29,0,0,0,0,0,0,0,0,0,0,0,0,0,0,0)';
      PINUSE='POWER';
      NO_LOAD_CHECK='Both';
      NO_IO_CHECK='Both';
      NO_ASSERT_CHECK='TRUE';
      NO_DIR_CHECK='TRUE';
      ALLOW_CONNECT='TRUE';
    'VDDCR_CPU1_BY30':
      PIN_NUMBER='(0,0,0,0,0,0,0,0,0,0,0,0,0,0,0,0,0,0,0,0,0,0,0,0,BY30,0,0,0,0,0,0,0,0,0,0,0,0,0,0,0)';
      PINUSE='POWER';
      NO_LOAD_CHECK='Both';
      NO_IO_CHECK='Both';
      NO_ASSERT_CHECK='TRUE';
      NO_DIR_CHECK='TRUE';
      ALLOW_CONNECT='TRUE';
    'VDDCR_CPU1_BY32':
      PIN_NUMBER='(0,0,0,0,0,0,0,0,0,0,0,0,0,0,0,0,0,0,0,0,0,0,0,0,BY32,0,0,0,0,0,0,0,0,0,0,0,0,0,0,0)';
      PINUSE='POWER';
      NO_LOAD_CHECK='Both';
      NO_IO_CHECK='Both';
      NO_ASSERT_CHECK='TRUE';
      NO_DIR_CHECK='TRUE';
      ALLOW_CONNECT='TRUE';
    'VDDCR_CPU1_BY33':
      PIN_NUMBER='(0,0,0,0,0,0,0,0,0,0,0,0,0,0,0,0,0,0,0,0,0,0,0,0,BY33,0,0,0,0,0,0,0,0,0,0,0,0,0,0,0)';
      PINUSE='POWER';
      NO_LOAD_CHECK='Both';
      NO_IO_CHECK='Both';
      NO_ASSERT_CHECK='TRUE';
      NO_DIR_CHECK='TRUE';
      ALLOW_CONNECT='TRUE';
    'VDDCR_CPU1_BY43':
      PIN_NUMBER='(0,0,0,0,0,0,0,0,0,0,0,0,0,0,0,0,0,0,0,0,0,0,0,0,BY43,0,0,0,0,0,0,0,0,0,0,0,0,0,0,0)';
      PINUSE='POWER';
      NO_LOAD_CHECK='Both';
      NO_IO_CHECK='Both';
      NO_ASSERT_CHECK='TRUE';
      NO_DIR_CHECK='TRUE';
      ALLOW_CONNECT='TRUE';
    'VDDCR_CPU1_BY44':
      PIN_NUMBER='(0,0,0,0,0,0,0,0,0,0,0,0,0,0,0,0,0,0,0,0,0,0,0,0,BY44,0,0,0,0,0,0,0,0,0,0,0,0,0,0,0)';
      PINUSE='POWER';
      NO_LOAD_CHECK='Both';
      NO_IO_CHECK='Both';
      NO_ASSERT_CHECK='TRUE';
      NO_DIR_CHECK='TRUE';
      ALLOW_CONNECT='TRUE';
    'VDDCR_CPU1_BY46':
      PIN_NUMBER='(0,0,0,0,0,0,0,0,0,0,0,0,0,0,0,0,0,0,0,0,0,0,0,0,BY46,0,0,0,0,0,0,0,0,0,0,0,0,0,0,0)';
      PINUSE='POWER';
      NO_LOAD_CHECK='Both';
      NO_IO_CHECK='Both';
      NO_ASSERT_CHECK='TRUE';
      NO_DIR_CHECK='TRUE';
      ALLOW_CONNECT='TRUE';
    'VDDCR_CPU1_BY47':
      PIN_NUMBER='(0,0,0,0,0,0,0,0,0,0,0,0,0,0,0,0,0,0,0,0,0,0,0,0,BY47,0,0,0,0,0,0,0,0,0,0,0,0,0,0,0)';
      PINUSE='POWER';
      NO_LOAD_CHECK='Both';
      NO_IO_CHECK='Both';
      NO_ASSERT_CHECK='TRUE';
      NO_DIR_CHECK='TRUE';
      ALLOW_CONNECT='TRUE';
    'VDDCR_CPU1_BY49':
      PIN_NUMBER='(0,0,0,0,0,0,0,0,0,0,0,0,0,0,0,0,0,0,0,0,0,0,0,0,BY49,0,0,0,0,0,0,0,0,0,0,0,0,0,0,0)';
      PINUSE='POWER';
      NO_LOAD_CHECK='Both';
      NO_IO_CHECK='Both';
      NO_ASSERT_CHECK='TRUE';
      NO_DIR_CHECK='TRUE';
      ALLOW_CONNECT='TRUE';
    'VDDCR_CPU1_BY50':
      PIN_NUMBER='(0,0,0,0,0,0,0,0,0,0,0,0,0,0,0,0,0,0,0,0,0,0,0,0,BY50,0,0,0,0,0,0,0,0,0,0,0,0,0,0,0)';
      PINUSE='POWER';
      NO_LOAD_CHECK='Both';
      NO_IO_CHECK='Both';
      NO_ASSERT_CHECK='TRUE';
      NO_DIR_CHECK='TRUE';
      ALLOW_CONNECT='TRUE';
    'VDDCR_CPU1_BY52':
      PIN_NUMBER='(0,0,0,0,0,0,0,0,0,0,0,0,0,0,0,0,0,0,0,0,0,0,0,0,BY52,0,0,0,0,0,0,0,0,0,0,0,0,0,0,0)';
      PINUSE='POWER';
      NO_LOAD_CHECK='Both';
      NO_IO_CHECK='Both';
      NO_ASSERT_CHECK='TRUE';
      NO_DIR_CHECK='TRUE';
      ALLOW_CONNECT='TRUE';
    'VDDCR_CPU1_BY53':
      PIN_NUMBER='(0,0,0,0,0,0,0,0,0,0,0,0,0,0,0,0,0,0,0,0,0,0,0,0,BY53,0,0,0,0,0,0,0,0,0,0,0,0,0,0,0)';
      PINUSE='POWER';
      NO_LOAD_CHECK='Both';
      NO_IO_CHECK='Both';
      NO_ASSERT_CHECK='TRUE';
      NO_DIR_CHECK='TRUE';
      ALLOW_CONNECT='TRUE';
    'VDDCR_CPU1_CC35':
      PIN_NUMBER='(0,0,0,0,0,0,0,0,0,0,0,0,0,0,0,0,0,0,0,0,0,0,0,0,CC35,0,0,0,0,0,0,0,0,0,0,0,0,0,0,0)';
      PINUSE='POWER';
      NO_LOAD_CHECK='Both';
      NO_IO_CHECK='Both';
      NO_ASSERT_CHECK='TRUE';
      NO_DIR_CHECK='TRUE';
      ALLOW_CONNECT='TRUE';
    'VDDCR_CPU1_CC36':
      PIN_NUMBER='(0,0,0,0,0,0,0,0,0,0,0,0,0,0,0,0,0,0,0,0,0,0,0,0,CC36,0,0,0,0,0,0,0,0,0,0,0,0,0,0,0)';
      PINUSE='POWER';
      NO_LOAD_CHECK='Both';
      NO_IO_CHECK='Both';
      NO_ASSERT_CHECK='TRUE';
      NO_DIR_CHECK='TRUE';
      ALLOW_CONNECT='TRUE';
    'VDDCR_CPU1_CC40':
      PIN_NUMBER='(0,0,0,0,0,0,0,0,0,0,0,0,0,0,0,0,0,0,0,0,0,0,0,0,CC40,0,0,0,0,0,0,0,0,0,0,0,0,0,0,0)';
      PINUSE='POWER';
      NO_LOAD_CHECK='Both';
      NO_IO_CHECK='Both';
      NO_ASSERT_CHECK='TRUE';
      NO_DIR_CHECK='TRUE';
      ALLOW_CONNECT='TRUE';
    'VDDCR_CPU1_CC41':
      PIN_NUMBER='(0,0,0,0,0,0,0,0,0,0,0,0,0,0,0,0,0,0,0,0,0,0,0,0,CC41,0,0,0,0,0,0,0,0,0,0,0,0,0,0,0)';
      PINUSE='POWER';
      NO_LOAD_CHECK='Both';
      NO_IO_CHECK='Both';
      NO_ASSERT_CHECK='TRUE';
      NO_DIR_CHECK='TRUE';
      ALLOW_CONNECT='TRUE';
    'VDDCR_CPU1_CD23':
      PIN_NUMBER='(0,0,0,0,0,0,0,0,0,0,0,0,0,0,0,0,0,0,0,0,0,0,0,0,CD23,0,0,0,0,0,0,0,0,0,0,0,0,0,0,0)';
      PINUSE='POWER';
      NO_LOAD_CHECK='Both';
      NO_IO_CHECK='Both';
      NO_ASSERT_CHECK='TRUE';
      NO_DIR_CHECK='TRUE';
      ALLOW_CONNECT='TRUE';
    'VDDCR_CPU1_CD24':
      PIN_NUMBER='(0,0,0,0,0,0,0,0,0,0,0,0,0,0,0,0,0,0,0,0,0,0,0,0,CD24,0,0,0,0,0,0,0,0,0,0,0,0,0,0,0)';
      PINUSE='POWER';
      NO_LOAD_CHECK='Both';
      NO_IO_CHECK='Both';
      NO_ASSERT_CHECK='TRUE';
      NO_DIR_CHECK='TRUE';
      ALLOW_CONNECT='TRUE';
    'VDDCR_CPU1_CD26':
      PIN_NUMBER='(0,0,0,0,0,0,0,0,0,0,0,0,0,0,0,0,0,0,0,0,0,0,0,0,CD26,0,0,0,0,0,0,0,0,0,0,0,0,0,0,0)';
      PINUSE='POWER';
      NO_LOAD_CHECK='Both';
      NO_IO_CHECK='Both';
      NO_ASSERT_CHECK='TRUE';
      NO_DIR_CHECK='TRUE';
      ALLOW_CONNECT='TRUE';
    'VDDCR_CPU1_CD27':
      PIN_NUMBER='(0,0,0,0,0,0,0,0,0,0,0,0,0,0,0,0,0,0,0,0,0,0,0,0,CD27,0,0,0,0,0,0,0,0,0,0,0,0,0,0,0)';
      PINUSE='POWER';
      NO_LOAD_CHECK='Both';
      NO_IO_CHECK='Both';
      NO_ASSERT_CHECK='TRUE';
      NO_DIR_CHECK='TRUE';
      ALLOW_CONNECT='TRUE';
    'VDDCR_CPU1_CD29':
      PIN_NUMBER='(0,0,0,0,0,0,0,0,0,0,0,0,0,0,0,0,0,0,0,0,0,0,0,0,CD29,0,0,0,0,0,0,0,0,0,0,0,0,0,0,0)';
      PINUSE='POWER';
      NO_LOAD_CHECK='Both';
      NO_IO_CHECK='Both';
      NO_ASSERT_CHECK='TRUE';
      NO_DIR_CHECK='TRUE';
      ALLOW_CONNECT='TRUE';
    'VDDCR_CPU1_CD30':
      PIN_NUMBER='(0,0,0,0,0,0,0,0,0,0,0,0,0,0,0,0,0,0,0,0,0,0,0,0,CD30,0,0,0,0,0,0,0,0,0,0,0,0,0,0,0)';
      PINUSE='POWER';
      NO_LOAD_CHECK='Both';
      NO_IO_CHECK='Both';
      NO_ASSERT_CHECK='TRUE';
      NO_DIR_CHECK='TRUE';
      ALLOW_CONNECT='TRUE';
    'VDDCR_CPU1_CD32':
      PIN_NUMBER='(0,0,0,0,0,0,0,0,0,0,0,0,0,0,0,0,0,0,0,0,0,0,0,0,CD32,0,0,0,0,0,0,0,0,0,0,0,0,0,0,0)';
      PINUSE='POWER';
      NO_LOAD_CHECK='Both';
      NO_IO_CHECK='Both';
      NO_ASSERT_CHECK='TRUE';
      NO_DIR_CHECK='TRUE';
      ALLOW_CONNECT='TRUE';
    'VDDCR_CPU1_CD33':
      PIN_NUMBER='(0,0,0,0,0,0,0,0,0,0,0,0,0,0,0,0,0,0,0,0,0,0,0,0,CD33,0,0,0,0,0,0,0,0,0,0,0,0,0,0,0)';
      PINUSE='POWER';
      NO_LOAD_CHECK='Both';
      NO_IO_CHECK='Both';
      NO_ASSERT_CHECK='TRUE';
      NO_DIR_CHECK='TRUE';
      ALLOW_CONNECT='TRUE';
    'VDDCR_CPU1_CD43':
      PIN_NUMBER='(0,0,0,0,0,0,0,0,0,0,0,0,0,0,0,0,0,0,0,0,0,0,0,0,CD43,0,0,0,0,0,0,0,0,0,0,0,0,0,0,0)';
      PINUSE='POWER';
      NO_LOAD_CHECK='Both';
      NO_IO_CHECK='Both';
      NO_ASSERT_CHECK='TRUE';
      NO_DIR_CHECK='TRUE';
      ALLOW_CONNECT='TRUE';
    'VDDCR_CPU1_CD44':
      PIN_NUMBER='(0,0,0,0,0,0,0,0,0,0,0,0,0,0,0,0,0,0,0,0,0,0,0,0,CD44,0,0,0,0,0,0,0,0,0,0,0,0,0,0,0)';
      PINUSE='POWER';
      NO_LOAD_CHECK='Both';
      NO_IO_CHECK='Both';
      NO_ASSERT_CHECK='TRUE';
      NO_DIR_CHECK='TRUE';
      ALLOW_CONNECT='TRUE';
    'VDDCR_CPU1_CD46':
      PIN_NUMBER='(0,0,0,0,0,0,0,0,0,0,0,0,0,0,0,0,0,0,0,0,0,0,0,0,CD46,0,0,0,0,0,0,0,0,0,0,0,0,0,0,0)';
      PINUSE='POWER';
      NO_LOAD_CHECK='Both';
      NO_IO_CHECK='Both';
      NO_ASSERT_CHECK='TRUE';
      NO_DIR_CHECK='TRUE';
      ALLOW_CONNECT='TRUE';
    'VDDCR_CPU1_CD47':
      PIN_NUMBER='(0,0,0,0,0,0,0,0,0,0,0,0,0,0,0,0,0,0,0,0,0,0,0,0,CD47,0,0,0,0,0,0,0,0,0,0,0,0,0,0,0)';
      PINUSE='POWER';
      NO_LOAD_CHECK='Both';
      NO_IO_CHECK='Both';
      NO_ASSERT_CHECK='TRUE';
      NO_DIR_CHECK='TRUE';
      ALLOW_CONNECT='TRUE';
    'VDDCR_CPU1_CD49':
      PIN_NUMBER='(0,0,0,0,0,0,0,0,0,0,0,0,0,0,0,0,0,0,0,0,0,0,0,0,CD49,0,0,0,0,0,0,0,0,0,0,0,0,0,0,0)';
      PINUSE='POWER';
      NO_LOAD_CHECK='Both';
      NO_IO_CHECK='Both';
      NO_ASSERT_CHECK='TRUE';
      NO_DIR_CHECK='TRUE';
      ALLOW_CONNECT='TRUE';
    'VDDCR_CPU1_CD50':
      PIN_NUMBER='(0,0,0,0,0,0,0,0,0,0,0,0,0,0,0,0,0,0,0,0,0,0,0,0,CD50,0,0,0,0,0,0,0,0,0,0,0,0,0,0,0)';
      PINUSE='POWER';
      NO_LOAD_CHECK='Both';
      NO_IO_CHECK='Both';
      NO_ASSERT_CHECK='TRUE';
      NO_DIR_CHECK='TRUE';
      ALLOW_CONNECT='TRUE';
    'VDDCR_CPU1_CD52':
      PIN_NUMBER='(0,0,0,0,0,0,0,0,0,0,0,0,0,0,0,0,0,0,0,0,0,0,0,0,CD52,0,0,0,0,0,0,0,0,0,0,0,0,0,0,0)';
      PINUSE='POWER';
      NO_LOAD_CHECK='Both';
      NO_IO_CHECK='Both';
      NO_ASSERT_CHECK='TRUE';
      NO_DIR_CHECK='TRUE';
      ALLOW_CONNECT='TRUE';
    'VDDCR_CPU1_CD53':
      PIN_NUMBER='(0,0,0,0,0,0,0,0,0,0,0,0,0,0,0,0,0,0,0,0,0,0,0,0,CD53,0,0,0,0,0,0,0,0,0,0,0,0,0,0,0)';
      PINUSE='POWER';
      NO_LOAD_CHECK='Both';
      NO_IO_CHECK='Both';
      NO_ASSERT_CHECK='TRUE';
      NO_DIR_CHECK='TRUE';
      ALLOW_CONNECT='TRUE';
    'VDDCR_CPU1_CG35':
      PIN_NUMBER='(0,0,0,0,0,0,0,0,0,0,0,0,0,0,0,0,0,0,0,0,0,0,0,0,CG35,0,0,0,0,0,0,0,0,0,0,0,0,0,0,0)';
      PINUSE='POWER';
      NO_LOAD_CHECK='Both';
      NO_IO_CHECK='Both';
      NO_ASSERT_CHECK='TRUE';
      NO_DIR_CHECK='TRUE';
      ALLOW_CONNECT='TRUE';
    'VDDCR_CPU1_CG36':
      PIN_NUMBER='(0,0,0,0,0,0,0,0,0,0,0,0,0,0,0,0,0,0,0,0,0,0,0,0,CG36,0,0,0,0,0,0,0,0,0,0,0,0,0,0,0)';
      PINUSE='POWER';
      NO_LOAD_CHECK='Both';
      NO_IO_CHECK='Both';
      NO_ASSERT_CHECK='TRUE';
      NO_DIR_CHECK='TRUE';
      ALLOW_CONNECT='TRUE';
    'VDDCR_CPU1_CG40':
      PIN_NUMBER='(0,0,0,0,0,0,0,0,0,0,0,0,0,0,0,0,0,0,0,0,0,0,0,0,CG40,0,0,0,0,0,0,0,0,0,0,0,0,0,0,0)';
      PINUSE='POWER';
      NO_LOAD_CHECK='Both';
      NO_IO_CHECK='Both';
      NO_ASSERT_CHECK='TRUE';
      NO_DIR_CHECK='TRUE';
      ALLOW_CONNECT='TRUE';
    'VDDCR_CPU1_CG41':
      PIN_NUMBER='(0,0,0,0,0,0,0,0,0,0,0,0,0,0,0,0,0,0,0,0,0,0,0,0,CG41,0,0,0,0,0,0,0,0,0,0,0,0,0,0,0)';
      PINUSE='POWER';
      NO_LOAD_CHECK='Both';
      NO_IO_CHECK='Both';
      NO_ASSERT_CHECK='TRUE';
      NO_DIR_CHECK='TRUE';
      ALLOW_CONNECT='TRUE';
    'VDDCR_CPU1_CH23':
      PIN_NUMBER='(0,0,0,0,0,0,0,0,0,0,0,0,0,0,0,0,0,0,0,0,0,0,0,0,CH23,0,0,0,0,0,0,0,0,0,0,0,0,0,0,0)';
      PINUSE='POWER';
      NO_LOAD_CHECK='Both';
      NO_IO_CHECK='Both';
      NO_ASSERT_CHECK='TRUE';
      NO_DIR_CHECK='TRUE';
      ALLOW_CONNECT='TRUE';
    'VDDCR_CPU1_CH24':
      PIN_NUMBER='(0,0,0,0,0,0,0,0,0,0,0,0,0,0,0,0,0,0,0,0,0,0,0,0,CH24,0,0,0,0,0,0,0,0,0,0,0,0,0,0,0)';
      PINUSE='POWER';
      NO_LOAD_CHECK='Both';
      NO_IO_CHECK='Both';
      NO_ASSERT_CHECK='TRUE';
      NO_DIR_CHECK='TRUE';
      ALLOW_CONNECT='TRUE';
    'VDDCR_CPU1_CH26':
      PIN_NUMBER='(0,0,0,0,0,0,0,0,0,0,0,0,0,0,0,0,0,0,0,0,0,0,0,0,CH26,0,0,0,0,0,0,0,0,0,0,0,0,0,0,0)';
      PINUSE='POWER';
      NO_LOAD_CHECK='Both';
      NO_IO_CHECK='Both';
      NO_ASSERT_CHECK='TRUE';
      NO_DIR_CHECK='TRUE';
      ALLOW_CONNECT='TRUE';
    'VDDCR_CPU1_CH27':
      PIN_NUMBER='(0,0,0,0,0,0,0,0,0,0,0,0,0,0,0,0,0,0,0,0,0,0,0,0,CH27,0,0,0,0,0,0,0,0,0,0,0,0,0,0,0)';
      PINUSE='POWER';
      NO_LOAD_CHECK='Both';
      NO_IO_CHECK='Both';
      NO_ASSERT_CHECK='TRUE';
      NO_DIR_CHECK='TRUE';
      ALLOW_CONNECT='TRUE';
    'VDDCR_CPU1_CH29':
      PIN_NUMBER='(0,0,0,0,0,0,0,0,0,0,0,0,0,0,0,0,0,0,0,0,0,0,0,0,CH29,0,0,0,0,0,0,0,0,0,0,0,0,0,0,0)';
      PINUSE='POWER';
      NO_LOAD_CHECK='Both';
      NO_IO_CHECK='Both';
      NO_ASSERT_CHECK='TRUE';
      NO_DIR_CHECK='TRUE';
      ALLOW_CONNECT='TRUE';
    'VDDCR_CPU1_CH30':
      PIN_NUMBER='(0,0,0,0,0,0,0,0,0,0,0,0,0,0,0,0,0,0,0,0,0,0,0,0,CH30,0,0,0,0,0,0,0,0,0,0,0,0,0,0,0)';
      PINUSE='POWER';
      NO_LOAD_CHECK='Both';
      NO_IO_CHECK='Both';
      NO_ASSERT_CHECK='TRUE';
      NO_DIR_CHECK='TRUE';
      ALLOW_CONNECT='TRUE';
    'VDDCR_CPU1_CH32':
      PIN_NUMBER='(0,0,0,0,0,0,0,0,0,0,0,0,0,0,0,0,0,0,0,0,0,0,0,0,CH32,0,0,0,0,0,0,0,0,0,0,0,0,0,0,0)';
      PINUSE='POWER';
      NO_LOAD_CHECK='Both';
      NO_IO_CHECK='Both';
      NO_ASSERT_CHECK='TRUE';
      NO_DIR_CHECK='TRUE';
      ALLOW_CONNECT='TRUE';
    'VDDCR_CPU1_CH33':
      PIN_NUMBER='(0,0,0,0,0,0,0,0,0,0,0,0,0,0,0,0,0,0,0,0,0,0,0,0,CH33,0,0,0,0,0,0,0,0,0,0,0,0,0,0,0)';
      PINUSE='POWER';
      NO_LOAD_CHECK='Both';
      NO_IO_CHECK='Both';
      NO_ASSERT_CHECK='TRUE';
      NO_DIR_CHECK='TRUE';
      ALLOW_CONNECT='TRUE';
    'VDDCR_CPU1_CH43':
      PIN_NUMBER='(0,0,0,0,0,0,0,0,0,0,0,0,0,0,0,0,0,0,0,0,0,0,0,0,CH43,0,0,0,0,0,0,0,0,0,0,0,0,0,0,0)';
      PINUSE='POWER';
      NO_LOAD_CHECK='Both';
      NO_IO_CHECK='Both';
      NO_ASSERT_CHECK='TRUE';
      NO_DIR_CHECK='TRUE';
      ALLOW_CONNECT='TRUE';
    'VDDCR_CPU1_CH44':
      PIN_NUMBER='(0,0,0,0,0,0,0,0,0,0,0,0,0,0,0,0,0,0,0,0,0,0,0,0,CH44,0,0,0,0,0,0,0,0,0,0,0,0,0,0,0)';
      PINUSE='POWER';
      NO_LOAD_CHECK='Both';
      NO_IO_CHECK='Both';
      NO_ASSERT_CHECK='TRUE';
      NO_DIR_CHECK='TRUE';
      ALLOW_CONNECT='TRUE';
    'VDDCR_CPU1_CH46':
      PIN_NUMBER='(0,0,0,0,0,0,0,0,0,0,0,0,0,0,0,0,0,0,0,0,0,0,0,0,CH46,0,0,0,0,0,0,0,0,0,0,0,0,0,0,0)';
      PINUSE='POWER';
      NO_LOAD_CHECK='Both';
      NO_IO_CHECK='Both';
      NO_ASSERT_CHECK='TRUE';
      NO_DIR_CHECK='TRUE';
      ALLOW_CONNECT='TRUE';
    'VDDCR_CPU1_CH47':
      PIN_NUMBER='(0,0,0,0,0,0,0,0,0,0,0,0,0,0,0,0,0,0,0,0,0,0,0,0,CH47,0,0,0,0,0,0,0,0,0,0,0,0,0,0,0)';
      PINUSE='POWER';
      NO_LOAD_CHECK='Both';
      NO_IO_CHECK='Both';
      NO_ASSERT_CHECK='TRUE';
      NO_DIR_CHECK='TRUE';
      ALLOW_CONNECT='TRUE';
    'VDDCR_CPU1_CH49':
      PIN_NUMBER='(0,0,0,0,0,0,0,0,0,0,0,0,0,0,0,0,0,0,0,0,0,0,0,0,CH49,0,0,0,0,0,0,0,0,0,0,0,0,0,0,0)';
      PINUSE='POWER';
      NO_LOAD_CHECK='Both';
      NO_IO_CHECK='Both';
      NO_ASSERT_CHECK='TRUE';
      NO_DIR_CHECK='TRUE';
      ALLOW_CONNECT='TRUE';
    'VDDCR_CPU1_CH50':
      PIN_NUMBER='(0,0,0,0,0,0,0,0,0,0,0,0,0,0,0,0,0,0,0,0,0,0,0,0,CH50,0,0,0,0,0,0,0,0,0,0,0,0,0,0,0)';
      PINUSE='POWER';
      NO_LOAD_CHECK='Both';
      NO_IO_CHECK='Both';
      NO_ASSERT_CHECK='TRUE';
      NO_DIR_CHECK='TRUE';
      ALLOW_CONNECT='TRUE';
    'VDDCR_CPU1_CH52':
      PIN_NUMBER='(0,0,0,0,0,0,0,0,0,0,0,0,0,0,0,0,0,0,0,0,0,0,0,0,CH52,0,0,0,0,0,0,0,0,0,0,0,0,0,0,0)';
      PINUSE='POWER';
      NO_LOAD_CHECK='Both';
      NO_IO_CHECK='Both';
      NO_ASSERT_CHECK='TRUE';
      NO_DIR_CHECK='TRUE';
      ALLOW_CONNECT='TRUE';
    'VDDCR_CPU1_CH53':
      PIN_NUMBER='(0,0,0,0,0,0,0,0,0,0,0,0,0,0,0,0,0,0,0,0,0,0,0,0,CH53,0,0,0,0,0,0,0,0,0,0,0,0,0,0,0)';
      PINUSE='POWER';
      NO_LOAD_CHECK='Both';
      NO_IO_CHECK='Both';
      NO_ASSERT_CHECK='TRUE';
      NO_DIR_CHECK='TRUE';
      ALLOW_CONNECT='TRUE';
    'VDDCR_CPU1_CK35':
      PIN_NUMBER='(0,0,0,0,0,0,0,0,0,0,0,0,0,0,0,0,0,0,0,0,0,0,0,0,CK35,0,0,0,0,0,0,0,0,0,0,0,0,0,0,0)';
      PINUSE='POWER';
      NO_LOAD_CHECK='Both';
      NO_IO_CHECK='Both';
      NO_ASSERT_CHECK='TRUE';
      NO_DIR_CHECK='TRUE';
      ALLOW_CONNECT='TRUE';
    'VDDCR_CPU1_CK36':
      PIN_NUMBER='(0,0,0,0,0,0,0,0,0,0,0,0,0,0,0,0,0,0,0,0,0,0,0,0,CK36,0,0,0,0,0,0,0,0,0,0,0,0,0,0,0)';
      PINUSE='POWER';
      NO_LOAD_CHECK='Both';
      NO_IO_CHECK='Both';
      NO_ASSERT_CHECK='TRUE';
      NO_DIR_CHECK='TRUE';
      ALLOW_CONNECT='TRUE';
    'VDDCR_CPU1_CK40':
      PIN_NUMBER='(0,0,0,0,0,0,0,0,0,0,0,0,0,0,0,0,0,0,0,0,0,0,0,0,CK40,0,0,0,0,0,0,0,0,0,0,0,0,0,0,0)';
      PINUSE='POWER';
      NO_LOAD_CHECK='Both';
      NO_IO_CHECK='Both';
      NO_ASSERT_CHECK='TRUE';
      NO_DIR_CHECK='TRUE';
      ALLOW_CONNECT='TRUE';
    'VDDCR_CPU1_CK41':
      PIN_NUMBER='(0,0,0,0,0,0,0,0,0,0,0,0,0,0,0,0,0,0,0,0,0,0,0,0,CK41,0,0,0,0,0,0,0,0,0,0,0,0,0,0,0)';
      PINUSE='POWER';
      NO_LOAD_CHECK='Both';
      NO_IO_CHECK='Both';
      NO_ASSERT_CHECK='TRUE';
      NO_DIR_CHECK='TRUE';
      ALLOW_CONNECT='TRUE';
    'VDDCR_CPU1_CL29':
      PIN_NUMBER='(0,0,0,0,0,0,0,0,0,0,0,0,0,0,0,0,0,0,0,0,0,0,0,0,CL29,0,0,0,0,0,0,0,0,0,0,0,0,0,0,0)';
      PINUSE='POWER';
      NO_LOAD_CHECK='Both';
      NO_IO_CHECK='Both';
      NO_ASSERT_CHECK='TRUE';
      NO_DIR_CHECK='TRUE';
      ALLOW_CONNECT='TRUE';
    'VDDCR_CPU1_CL30':
      PIN_NUMBER='(0,0,0,0,0,0,0,0,0,0,0,0,0,0,0,0,0,0,0,0,0,0,0,0,CL30,0,0,0,0,0,0,0,0,0,0,0,0,0,0,0)';
      PINUSE='POWER';
      NO_LOAD_CHECK='Both';
      NO_IO_CHECK='Both';
      NO_ASSERT_CHECK='TRUE';
      NO_DIR_CHECK='TRUE';
      ALLOW_CONNECT='TRUE';
    'VDDCR_CPU1_CL32':
      PIN_NUMBER='(0,0,0,0,0,0,0,0,0,0,0,0,0,0,0,0,0,0,0,0,0,0,0,0,CL32,0,0,0,0,0,0,0,0,0,0,0,0,0,0,0)';
      PINUSE='POWER';
      NO_LOAD_CHECK='Both';
      NO_IO_CHECK='Both';
      NO_ASSERT_CHECK='TRUE';
      NO_DIR_CHECK='TRUE';
      ALLOW_CONNECT='TRUE';
    'VDDCR_CPU1_CL33':
      PIN_NUMBER='(0,0,0,0,0,0,0,0,0,0,0,0,0,0,0,0,0,0,0,0,0,0,0,0,CL33,0,0,0,0,0,0,0,0,0,0,0,0,0,0,0)';
      PINUSE='POWER';
      NO_LOAD_CHECK='Both';
      NO_IO_CHECK='Both';
      NO_ASSERT_CHECK='TRUE';
      NO_DIR_CHECK='TRUE';
      ALLOW_CONNECT='TRUE';
    'VDDCR_CPU1_CL43':
      PIN_NUMBER='(0,0,0,0,0,0,0,0,0,0,0,0,0,0,0,0,0,0,0,0,0,0,0,0,CL43,0,0,0,0,0,0,0,0,0,0,0,0,0,0,0)';
      PINUSE='POWER';
      NO_LOAD_CHECK='Both';
      NO_IO_CHECK='Both';
      NO_ASSERT_CHECK='TRUE';
      NO_DIR_CHECK='TRUE';
      ALLOW_CONNECT='TRUE';
    'VDDCR_CPU1_CL44':
      PIN_NUMBER='(0,0,0,0,0,0,0,0,0,0,0,0,0,0,0,0,0,0,0,0,0,0,0,0,CL44,0,0,0,0,0,0,0,0,0,0,0,0,0,0,0)';
      PINUSE='POWER';
      NO_LOAD_CHECK='Both';
      NO_IO_CHECK='Both';
      NO_ASSERT_CHECK='TRUE';
      NO_DIR_CHECK='TRUE';
      ALLOW_CONNECT='TRUE';
    'VDDCR_CPU1_CL46':
      PIN_NUMBER='(0,0,0,0,0,0,0,0,0,0,0,0,0,0,0,0,0,0,0,0,0,0,0,0,CL46,0,0,0,0,0,0,0,0,0,0,0,0,0,0,0)';
      PINUSE='POWER';
      NO_LOAD_CHECK='Both';
      NO_IO_CHECK='Both';
      NO_ASSERT_CHECK='TRUE';
      NO_DIR_CHECK='TRUE';
      ALLOW_CONNECT='TRUE';
    'VDDCR_CPU1_CL47':
      PIN_NUMBER='(0,0,0,0,0,0,0,0,0,0,0,0,0,0,0,0,0,0,0,0,0,0,0,0,CL47,0,0,0,0,0,0,0,0,0,0,0,0,0,0,0)';
      PINUSE='POWER';
      NO_LOAD_CHECK='Both';
      NO_IO_CHECK='Both';
      NO_ASSERT_CHECK='TRUE';
      NO_DIR_CHECK='TRUE';
      ALLOW_CONNECT='TRUE';
    'VDDCR_CPU1_CN35':
      PIN_NUMBER='(0,0,0,0,0,0,0,0,0,0,0,0,0,0,0,0,0,0,0,0,0,0,0,0,CN35,0,0,0,0,0,0,0,0,0,0,0,0,0,0,0)';
      PINUSE='POWER';
      NO_LOAD_CHECK='Both';
      NO_IO_CHECK='Both';
      NO_ASSERT_CHECK='TRUE';
      NO_DIR_CHECK='TRUE';
      ALLOW_CONNECT='TRUE';
    'VDDCR_CPU1_CN36':
      PIN_NUMBER='(0,0,0,0,0,0,0,0,0,0,0,0,0,0,0,0,0,0,0,0,0,0,0,0,CN36,0,0,0,0,0,0,0,0,0,0,0,0,0,0,0)';
      PINUSE='POWER';
      NO_LOAD_CHECK='Both';
      NO_IO_CHECK='Both';
      NO_ASSERT_CHECK='TRUE';
      NO_DIR_CHECK='TRUE';
      ALLOW_CONNECT='TRUE';
    'VDDCR_CPU1_CN40':
      PIN_NUMBER='(0,0,0,0,0,0,0,0,0,0,0,0,0,0,0,0,0,0,0,0,0,0,0,0,CN40,0,0,0,0,0,0,0,0,0,0,0,0,0,0,0)';
      PINUSE='POWER';
      NO_LOAD_CHECK='Both';
      NO_IO_CHECK='Both';
      NO_ASSERT_CHECK='TRUE';
      NO_DIR_CHECK='TRUE';
      ALLOW_CONNECT='TRUE';
    'VDDCR_CPU1_CN41':
      PIN_NUMBER='(0,0,0,0,0,0,0,0,0,0,0,0,0,0,0,0,0,0,0,0,0,0,0,0,CN41,0,0,0,0,0,0,0,0,0,0,0,0,0,0,0)';
      PINUSE='POWER';
      NO_LOAD_CHECK='Both';
      NO_IO_CHECK='Both';
      NO_ASSERT_CHECK='TRUE';
      NO_DIR_CHECK='TRUE';
      ALLOW_CONNECT='TRUE';
    'VDDCR_CPU1_CP23':
      PIN_NUMBER='(0,0,0,0,0,0,0,0,0,0,0,0,0,0,0,0,0,0,0,0,0,0,0,0,CP23,0,0,0,0,0,0,0,0,0,0,0,0,0,0,0)';
      PINUSE='POWER';
      NO_LOAD_CHECK='Both';
      NO_IO_CHECK='Both';
      NO_ASSERT_CHECK='TRUE';
      NO_DIR_CHECK='TRUE';
      ALLOW_CONNECT='TRUE';
    'VDDCR_CPU1_CP24':
      PIN_NUMBER='(0,0,0,0,0,0,0,0,0,0,0,0,0,0,0,0,0,0,0,0,0,0,0,0,CP24,0,0,0,0,0,0,0,0,0,0,0,0,0,0,0)';
      PINUSE='POWER';
      NO_LOAD_CHECK='Both';
      NO_IO_CHECK='Both';
      NO_ASSERT_CHECK='TRUE';
      NO_DIR_CHECK='TRUE';
      ALLOW_CONNECT='TRUE';
    'VDDCR_CPU1_CP26':
      PIN_NUMBER='(0,0,0,0,0,0,0,0,0,0,0,0,0,0,0,0,0,0,0,0,0,0,0,0,CP26,0,0,0,0,0,0,0,0,0,0,0,0,0,0,0)';
      PINUSE='POWER';
      NO_LOAD_CHECK='Both';
      NO_IO_CHECK='Both';
      NO_ASSERT_CHECK='TRUE';
      NO_DIR_CHECK='TRUE';
      ALLOW_CONNECT='TRUE';
    'VDDCR_CPU1_CP27':
      PIN_NUMBER='(0,0,0,0,0,0,0,0,0,0,0,0,0,0,0,0,0,0,0,0,0,0,0,0,CP27,0,0,0,0,0,0,0,0,0,0,0,0,0,0,0)';
      PINUSE='POWER';
      NO_LOAD_CHECK='Both';
      NO_IO_CHECK='Both';
      NO_ASSERT_CHECK='TRUE';
      NO_DIR_CHECK='TRUE';
      ALLOW_CONNECT='TRUE';
    'VDDCR_CPU1_CP29':
      PIN_NUMBER='(0,0,0,0,0,0,0,0,0,0,0,0,0,0,0,0,0,0,0,0,0,0,0,0,CP29,0,0,0,0,0,0,0,0,0,0,0,0,0,0,0)';
      PINUSE='POWER';
      NO_LOAD_CHECK='Both';
      NO_IO_CHECK='Both';
      NO_ASSERT_CHECK='TRUE';
      NO_DIR_CHECK='TRUE';
      ALLOW_CONNECT='TRUE';
    'VDDCR_CPU1_CP30':
      PIN_NUMBER='(0,0,0,0,0,0,0,0,0,0,0,0,0,0,0,0,0,0,0,0,0,0,0,0,CP30,0,0,0,0,0,0,0,0,0,0,0,0,0,0,0)';
      PINUSE='POWER';
      NO_LOAD_CHECK='Both';
      NO_IO_CHECK='Both';
      NO_ASSERT_CHECK='TRUE';
      NO_DIR_CHECK='TRUE';
      ALLOW_CONNECT='TRUE';
    'VDDCR_CPU1_CP32':
      PIN_NUMBER='(0,0,0,0,0,0,0,0,0,0,0,0,0,0,0,0,0,0,0,0,0,0,0,0,CP32,0,0,0,0,0,0,0,0,0,0,0,0,0,0,0)';
      PINUSE='POWER';
      NO_LOAD_CHECK='Both';
      NO_IO_CHECK='Both';
      NO_ASSERT_CHECK='TRUE';
      NO_DIR_CHECK='TRUE';
      ALLOW_CONNECT='TRUE';
    'VDDCR_CPU1_CP33':
      PIN_NUMBER='(0,0,0,0,0,0,0,0,0,0,0,0,0,0,0,0,0,0,0,0,0,0,0,0,CP33,0,0,0,0,0,0,0,0,0,0,0,0,0,0,0)';
      PINUSE='POWER';
      NO_LOAD_CHECK='Both';
      NO_IO_CHECK='Both';
      NO_ASSERT_CHECK='TRUE';
      NO_DIR_CHECK='TRUE';
      ALLOW_CONNECT='TRUE';
    'VDDCR_CPU1_CP43':
      PIN_NUMBER='(0,0,0,0,0,0,0,0,0,0,0,0,0,0,0,0,0,0,0,0,0,0,0,0,CP43,0,0,0,0,0,0,0,0,0,0,0,0,0,0,0)';
      PINUSE='POWER';
      NO_LOAD_CHECK='Both';
      NO_IO_CHECK='Both';
      NO_ASSERT_CHECK='TRUE';
      NO_DIR_CHECK='TRUE';
      ALLOW_CONNECT='TRUE';
    'VDDCR_CPU1_CP44':
      PIN_NUMBER='(0,0,0,0,0,0,0,0,0,0,0,0,0,0,0,0,0,0,0,0,0,0,0,0,CP44,0,0,0,0,0,0,0,0,0,0,0,0,0,0,0)';
      PINUSE='POWER';
      NO_LOAD_CHECK='Both';
      NO_IO_CHECK='Both';
      NO_ASSERT_CHECK='TRUE';
      NO_DIR_CHECK='TRUE';
      ALLOW_CONNECT='TRUE';
    'VDDCR_CPU1_CP46':
      PIN_NUMBER='(0,0,0,0,0,0,0,0,0,0,0,0,0,0,0,0,0,0,0,0,0,0,0,0,CP46,0,0,0,0,0,0,0,0,0,0,0,0,0,0,0)';
      PINUSE='POWER';
      NO_LOAD_CHECK='Both';
      NO_IO_CHECK='Both';
      NO_ASSERT_CHECK='TRUE';
      NO_DIR_CHECK='TRUE';
      ALLOW_CONNECT='TRUE';
    'VDDCR_CPU1_CP47':
      PIN_NUMBER='(0,0,0,0,0,0,0,0,0,0,0,0,0,0,0,0,0,0,0,0,0,0,0,0,CP47,0,0,0,0,0,0,0,0,0,0,0,0,0,0,0)';
      PINUSE='POWER';
      NO_LOAD_CHECK='Both';
      NO_IO_CHECK='Both';
      NO_ASSERT_CHECK='TRUE';
      NO_DIR_CHECK='TRUE';
      ALLOW_CONNECT='TRUE';
    'VDDCR_CPU1_CP49':
      PIN_NUMBER='(0,0,0,0,0,0,0,0,0,0,0,0,0,0,0,0,0,0,0,0,0,0,0,0,CP49,0,0,0,0,0,0,0,0,0,0,0,0,0,0,0)';
      PINUSE='POWER';
      NO_LOAD_CHECK='Both';
      NO_IO_CHECK='Both';
      NO_ASSERT_CHECK='TRUE';
      NO_DIR_CHECK='TRUE';
      ALLOW_CONNECT='TRUE';
    'VDDCR_CPU1_CP50':
      PIN_NUMBER='(0,0,0,0,0,0,0,0,0,0,0,0,0,0,0,0,0,0,0,0,0,0,0,0,CP50,0,0,0,0,0,0,0,0,0,0,0,0,0,0,0)';
      PINUSE='POWER';
      NO_LOAD_CHECK='Both';
      NO_IO_CHECK='Both';
      NO_ASSERT_CHECK='TRUE';
      NO_DIR_CHECK='TRUE';
      ALLOW_CONNECT='TRUE';
    'VDDCR_CPU1_CP52':
      PIN_NUMBER='(0,0,0,0,0,0,0,0,0,0,0,0,0,0,0,0,0,0,0,0,0,0,0,0,CP52,0,0,0,0,0,0,0,0,0,0,0,0,0,0,0)';
      PINUSE='POWER';
      NO_LOAD_CHECK='Both';
      NO_IO_CHECK='Both';
      NO_ASSERT_CHECK='TRUE';
      NO_DIR_CHECK='TRUE';
      ALLOW_CONNECT='TRUE';
    'VDDCR_CPU1_CP53':
      PIN_NUMBER='(0,0,0,0,0,0,0,0,0,0,0,0,0,0,0,0,0,0,0,0,0,0,0,0,CP53,0,0,0,0,0,0,0,0,0,0,0,0,0,0,0)';
      PINUSE='POWER';
      NO_LOAD_CHECK='Both';
      NO_IO_CHECK='Both';
      NO_ASSERT_CHECK='TRUE';
      NO_DIR_CHECK='TRUE';
      ALLOW_CONNECT='TRUE';
    'VDDCR_CPU1_CU35':
      PIN_NUMBER='(0,0,0,0,0,0,0,0,0,0,0,0,0,0,0,0,0,0,0,0,0,0,0,0,CU35,0,0,0,0,0,0,0,0,0,0,0,0,0,0,0)';
      PINUSE='POWER';
      NO_LOAD_CHECK='Both';
      NO_IO_CHECK='Both';
      NO_ASSERT_CHECK='TRUE';
      NO_DIR_CHECK='TRUE';
      ALLOW_CONNECT='TRUE';
    'VDDCR_CPU1_CU36':
      PIN_NUMBER='(0,0,0,0,0,0,0,0,0,0,0,0,0,0,0,0,0,0,0,0,0,0,0,0,CU36,0,0,0,0,0,0,0,0,0,0,0,0,0,0,0)';
      PINUSE='POWER';
      NO_LOAD_CHECK='Both';
      NO_IO_CHECK='Both';
      NO_ASSERT_CHECK='TRUE';
      NO_DIR_CHECK='TRUE';
      ALLOW_CONNECT='TRUE';
    'VDDCR_CPU1_CU40':
      PIN_NUMBER='(0,0,0,0,0,0,0,0,0,0,0,0,0,0,0,0,0,0,0,0,0,0,0,0,CU40,0,0,0,0,0,0,0,0,0,0,0,0,0,0,0)';
      PINUSE='POWER';
      NO_LOAD_CHECK='Both';
      NO_IO_CHECK='Both';
      NO_ASSERT_CHECK='TRUE';
      NO_DIR_CHECK='TRUE';
      ALLOW_CONNECT='TRUE';
    'VDDCR_CPU1_CU41':
      PIN_NUMBER='(0,0,0,0,0,0,0,0,0,0,0,0,0,0,0,0,0,0,0,0,0,0,0,0,CU41,0,0,0,0,0,0,0,0,0,0,0,0,0,0,0)';
      PINUSE='POWER';
      NO_LOAD_CHECK='Both';
      NO_IO_CHECK='Both';
      NO_ASSERT_CHECK='TRUE';
      NO_DIR_CHECK='TRUE';
      ALLOW_CONNECT='TRUE';
    'VDDCR_CPU1_CV23':
      PIN_NUMBER='(0,0,0,0,0,0,0,0,0,0,0,0,0,0,0,0,0,0,0,0,0,0,0,0,CV23,0,0,0,0,0,0,0,0,0,0,0,0,0,0,0)';
      PINUSE='POWER';
      NO_LOAD_CHECK='Both';
      NO_IO_CHECK='Both';
      NO_ASSERT_CHECK='TRUE';
      NO_DIR_CHECK='TRUE';
      ALLOW_CONNECT='TRUE';
    'VDDCR_CPU1_CV24':
      PIN_NUMBER='(0,0,0,0,0,0,0,0,0,0,0,0,0,0,0,0,0,0,0,0,0,0,0,0,CV24,0,0,0,0,0,0,0,0,0,0,0,0,0,0,0)';
      PINUSE='POWER';
      NO_LOAD_CHECK='Both';
      NO_IO_CHECK='Both';
      NO_ASSERT_CHECK='TRUE';
      NO_DIR_CHECK='TRUE';
      ALLOW_CONNECT='TRUE';
    'VDDCR_CPU1_CV26':
      PIN_NUMBER='(0,0,0,0,0,0,0,0,0,0,0,0,0,0,0,0,0,0,0,0,0,0,0,0,CV26,0,0,0,0,0,0,0,0,0,0,0,0,0,0,0)';
      PINUSE='POWER';
      NO_LOAD_CHECK='Both';
      NO_IO_CHECK='Both';
      NO_ASSERT_CHECK='TRUE';
      NO_DIR_CHECK='TRUE';
      ALLOW_CONNECT='TRUE';
    'VDDCR_CPU1_CV27':
      PIN_NUMBER='(0,0,0,0,0,0,0,0,0,0,0,0,0,0,0,0,0,0,0,0,0,0,0,0,CV27,0,0,0,0,0,0,0,0,0,0,0,0,0,0,0)';
      PINUSE='POWER';
      NO_LOAD_CHECK='Both';
      NO_IO_CHECK='Both';
      NO_ASSERT_CHECK='TRUE';
      NO_DIR_CHECK='TRUE';
      ALLOW_CONNECT='TRUE';
    'VDDCR_CPU1_CV29':
      PIN_NUMBER='(0,0,0,0,0,0,0,0,0,0,0,0,0,0,0,0,0,0,0,0,0,0,0,0,CV29,0,0,0,0,0,0,0,0,0,0,0,0,0,0,0)';
      PINUSE='POWER';
      NO_LOAD_CHECK='Both';
      NO_IO_CHECK='Both';
      NO_ASSERT_CHECK='TRUE';
      NO_DIR_CHECK='TRUE';
      ALLOW_CONNECT='TRUE';
    'VDDCR_CPU1_CV30':
      PIN_NUMBER='(0,0,0,0,0,0,0,0,0,0,0,0,0,0,0,0,0,0,0,0,0,0,0,0,CV30,0,0,0,0,0,0,0,0,0,0,0,0,0,0,0)';
      PINUSE='POWER';
      NO_LOAD_CHECK='Both';
      NO_IO_CHECK='Both';
      NO_ASSERT_CHECK='TRUE';
      NO_DIR_CHECK='TRUE';
      ALLOW_CONNECT='TRUE';
    'VDDCR_CPU1_CV32':
      PIN_NUMBER='(0,0,0,0,0,0,0,0,0,0,0,0,0,0,0,0,0,0,0,0,0,0,0,0,CV32,0,0,0,0,0,0,0,0,0,0,0,0,0,0,0)';
      PINUSE='POWER';
      NO_LOAD_CHECK='Both';
      NO_IO_CHECK='Both';
      NO_ASSERT_CHECK='TRUE';
      NO_DIR_CHECK='TRUE';
      ALLOW_CONNECT='TRUE';
    'VDDCR_CPU1_CV33':
      PIN_NUMBER='(0,0,0,0,0,0,0,0,0,0,0,0,0,0,0,0,0,0,0,0,0,0,0,0,CV33,0,0,0,0,0,0,0,0,0,0,0,0,0,0,0)';
      PINUSE='POWER';
      NO_LOAD_CHECK='Both';
      NO_IO_CHECK='Both';
      NO_ASSERT_CHECK='TRUE';
      NO_DIR_CHECK='TRUE';
      ALLOW_CONNECT='TRUE';
    'VDDCR_CPU1_CV43':
      PIN_NUMBER='(0,0,0,0,0,0,0,0,0,0,0,0,0,0,0,0,0,0,0,0,0,0,0,0,CV43,0,0,0,0,0,0,0,0,0,0,0,0,0,0,0)';
      PINUSE='POWER';
      NO_LOAD_CHECK='Both';
      NO_IO_CHECK='Both';
      NO_ASSERT_CHECK='TRUE';
      NO_DIR_CHECK='TRUE';
      ALLOW_CONNECT='TRUE';
    'VDDCR_CPU1_CV44':
      PIN_NUMBER='(0,0,0,0,0,0,0,0,0,0,0,0,0,0,0,0,0,0,0,0,0,0,0,0,CV44,0,0,0,0,0,0,0,0,0,0,0,0,0,0,0)';
      PINUSE='POWER';
      NO_LOAD_CHECK='Both';
      NO_IO_CHECK='Both';
      NO_ASSERT_CHECK='TRUE';
      NO_DIR_CHECK='TRUE';
      ALLOW_CONNECT='TRUE';
    'VDDCR_CPU1_CV46':
      PIN_NUMBER='(0,0,0,0,0,0,0,0,0,0,0,0,0,0,0,0,0,0,0,0,0,0,0,0,CV46,0,0,0,0,0,0,0,0,0,0,0,0,0,0,0)';
      PINUSE='POWER';
      NO_LOAD_CHECK='Both';
      NO_IO_CHECK='Both';
      NO_ASSERT_CHECK='TRUE';
      NO_DIR_CHECK='TRUE';
      ALLOW_CONNECT='TRUE';
    'VDDCR_CPU1_CV47':
      PIN_NUMBER='(0,0,0,0,0,0,0,0,0,0,0,0,0,0,0,0,0,0,0,0,0,0,0,0,CV47,0,0,0,0,0,0,0,0,0,0,0,0,0,0,0)';
      PINUSE='POWER';
      NO_LOAD_CHECK='Both';
      NO_IO_CHECK='Both';
      NO_ASSERT_CHECK='TRUE';
      NO_DIR_CHECK='TRUE';
      ALLOW_CONNECT='TRUE';
    'VDDCR_CPU1_CV49':
      PIN_NUMBER='(0,0,0,0,0,0,0,0,0,0,0,0,0,0,0,0,0,0,0,0,0,0,0,0,CV49,0,0,0,0,0,0,0,0,0,0,0,0,0,0,0)';
      PINUSE='POWER';
      NO_LOAD_CHECK='Both';
      NO_IO_CHECK='Both';
      NO_ASSERT_CHECK='TRUE';
      NO_DIR_CHECK='TRUE';
      ALLOW_CONNECT='TRUE';
    'VDDCR_CPU1_CV50':
      PIN_NUMBER='(0,0,0,0,0,0,0,0,0,0,0,0,0,0,0,0,0,0,0,0,0,0,0,0,CV50,0,0,0,0,0,0,0,0,0,0,0,0,0,0,0)';
      PINUSE='POWER';
      NO_LOAD_CHECK='Both';
      NO_IO_CHECK='Both';
      NO_ASSERT_CHECK='TRUE';
      NO_DIR_CHECK='TRUE';
      ALLOW_CONNECT='TRUE';
    'VDDCR_CPU1_CV52':
      PIN_NUMBER='(0,0,0,0,0,0,0,0,0,0,0,0,0,0,0,0,0,0,0,0,0,0,0,0,CV52,0,0,0,0,0,0,0,0,0,0,0,0,0,0,0)';
      PINUSE='POWER';
      NO_LOAD_CHECK='Both';
      NO_IO_CHECK='Both';
      NO_ASSERT_CHECK='TRUE';
      NO_DIR_CHECK='TRUE';
      ALLOW_CONNECT='TRUE';
    'VDDCR_CPU1_CV53':
      PIN_NUMBER='(0,0,0,0,0,0,0,0,0,0,0,0,0,0,0,0,0,0,0,0,0,0,0,0,CV53,0,0,0,0,0,0,0,0,0,0,0,0,0,0,0)';
      PINUSE='POWER';
      NO_LOAD_CHECK='Both';
      NO_IO_CHECK='Both';
      NO_ASSERT_CHECK='TRUE';
      NO_DIR_CHECK='TRUE';
      ALLOW_CONNECT='TRUE';
    'VDDCR_CPU1_DA35':
      PIN_NUMBER='(0,0,0,0,0,0,0,0,0,0,0,0,0,0,0,0,0,0,0,0,0,0,0,0,DA35,0,0,0,0,0,0,0,0,0,0,0,0,0,0,0)';
      PINUSE='POWER';
      NO_LOAD_CHECK='Both';
      NO_IO_CHECK='Both';
      NO_ASSERT_CHECK='TRUE';
      NO_DIR_CHECK='TRUE';
      ALLOW_CONNECT='TRUE';
    'VDDCR_CPU1_DA36':
      PIN_NUMBER='(0,0,0,0,0,0,0,0,0,0,0,0,0,0,0,0,0,0,0,0,0,0,0,0,DA36,0,0,0,0,0,0,0,0,0,0,0,0,0,0,0)';
      PINUSE='POWER';
      NO_LOAD_CHECK='Both';
      NO_IO_CHECK='Both';
      NO_ASSERT_CHECK='TRUE';
      NO_DIR_CHECK='TRUE';
      ALLOW_CONNECT='TRUE';
    'VDDCR_CPU1_DA40':
      PIN_NUMBER='(0,0,0,0,0,0,0,0,0,0,0,0,0,0,0,0,0,0,0,0,0,0,0,0,DA40,0,0,0,0,0,0,0,0,0,0,0,0,0,0,0)';
      PINUSE='POWER';
      NO_LOAD_CHECK='Both';
      NO_IO_CHECK='Both';
      NO_ASSERT_CHECK='TRUE';
      NO_DIR_CHECK='TRUE';
      ALLOW_CONNECT='TRUE';
    'VDDCR_CPU1_DA41':
      PIN_NUMBER='(0,0,0,0,0,0,0,0,0,0,0,0,0,0,0,0,0,0,0,0,0,0,0,0,DA41,0,0,0,0,0,0,0,0,0,0,0,0,0,0,0)';
      PINUSE='POWER';
      NO_LOAD_CHECK='Both';
      NO_IO_CHECK='Both';
      NO_ASSERT_CHECK='TRUE';
      NO_DIR_CHECK='TRUE';
      ALLOW_CONNECT='TRUE';
    'VDDCR_CPU1_DB23':
      PIN_NUMBER='(0,0,0,0,0,0,0,0,0,0,0,0,0,0,0,0,0,0,0,0,0,0,0,0,DB23,0,0,0,0,0,0,0,0,0,0,0,0,0,0,0)';
      PINUSE='POWER';
      NO_LOAD_CHECK='Both';
      NO_IO_CHECK='Both';
      NO_ASSERT_CHECK='TRUE';
      NO_DIR_CHECK='TRUE';
      ALLOW_CONNECT='TRUE';
    'VDDCR_CPU1_DB24':
      PIN_NUMBER='(0,0,0,0,0,0,0,0,0,0,0,0,0,0,0,0,0,0,0,0,0,0,0,0,DB24,0,0,0,0,0,0,0,0,0,0,0,0,0,0,0)';
      PINUSE='POWER';
      NO_LOAD_CHECK='Both';
      NO_IO_CHECK='Both';
      NO_ASSERT_CHECK='TRUE';
      NO_DIR_CHECK='TRUE';
      ALLOW_CONNECT='TRUE';
    'VDDCR_CPU1_DB26':
      PIN_NUMBER='(0,0,0,0,0,0,0,0,0,0,0,0,0,0,0,0,0,0,0,0,0,0,0,0,DB26,0,0,0,0,0,0,0,0,0,0,0,0,0,0,0)';
      PINUSE='POWER';
      NO_LOAD_CHECK='Both';
      NO_IO_CHECK='Both';
      NO_ASSERT_CHECK='TRUE';
      NO_DIR_CHECK='TRUE';
      ALLOW_CONNECT='TRUE';
    'VDDCR_CPU1_DB27':
      PIN_NUMBER='(0,0,0,0,0,0,0,0,0,0,0,0,0,0,0,0,0,0,0,0,0,0,0,0,DB27,0,0,0,0,0,0,0,0,0,0,0,0,0,0,0)';
      PINUSE='POWER';
      NO_LOAD_CHECK='Both';
      NO_IO_CHECK='Both';
      NO_ASSERT_CHECK='TRUE';
      NO_DIR_CHECK='TRUE';
      ALLOW_CONNECT='TRUE';
    'VDDCR_CPU1_DB29':
      PIN_NUMBER='(0,0,0,0,0,0,0,0,0,0,0,0,0,0,0,0,0,0,0,0,0,0,0,0,DB29,0,0,0,0,0,0,0,0,0,0,0,0,0,0,0)';
      PINUSE='POWER';
      NO_LOAD_CHECK='Both';
      NO_IO_CHECK='Both';
      NO_ASSERT_CHECK='TRUE';
      NO_DIR_CHECK='TRUE';
      ALLOW_CONNECT='TRUE';
    'VDDCR_CPU1_DB30':
      PIN_NUMBER='(0,0,0,0,0,0,0,0,0,0,0,0,0,0,0,0,0,0,0,0,0,0,0,0,DB30,0,0,0,0,0,0,0,0,0,0,0,0,0,0,0)';
      PINUSE='POWER';
      NO_LOAD_CHECK='Both';
      NO_IO_CHECK='Both';
      NO_ASSERT_CHECK='TRUE';
      NO_DIR_CHECK='TRUE';
      ALLOW_CONNECT='TRUE';
    'VDDCR_CPU1_DB32':
      PIN_NUMBER='(0,0,0,0,0,0,0,0,0,0,0,0,0,0,0,0,0,0,0,0,0,0,0,0,DB32,0,0,0,0,0,0,0,0,0,0,0,0,0,0,0)';
      PINUSE='POWER';
      NO_LOAD_CHECK='Both';
      NO_IO_CHECK='Both';
      NO_ASSERT_CHECK='TRUE';
      NO_DIR_CHECK='TRUE';
      ALLOW_CONNECT='TRUE';
    'VDDCR_CPU1_DB33':
      PIN_NUMBER='(0,0,0,0,0,0,0,0,0,0,0,0,0,0,0,0,0,0,0,0,0,0,0,0,DB33,0,0,0,0,0,0,0,0,0,0,0,0,0,0,0)';
      PINUSE='POWER';
      NO_LOAD_CHECK='Both';
      NO_IO_CHECK='Both';
      NO_ASSERT_CHECK='TRUE';
      NO_DIR_CHECK='TRUE';
      ALLOW_CONNECT='TRUE';
    'VDDCR_CPU1_DB43':
      PIN_NUMBER='(0,0,0,0,0,0,0,0,0,0,0,0,0,0,0,0,0,0,0,0,0,0,0,0,DB43,0,0,0,0,0,0,0,0,0,0,0,0,0,0,0)';
      PINUSE='POWER';
      NO_LOAD_CHECK='Both';
      NO_IO_CHECK='Both';
      NO_ASSERT_CHECK='TRUE';
      NO_DIR_CHECK='TRUE';
      ALLOW_CONNECT='TRUE';
    'VDDCR_CPU1_DB44':
      PIN_NUMBER='(0,0,0,0,0,0,0,0,0,0,0,0,0,0,0,0,0,0,0,0,0,0,0,0,DB44,0,0,0,0,0,0,0,0,0,0,0,0,0,0,0)';
      PINUSE='POWER';
      NO_LOAD_CHECK='Both';
      NO_IO_CHECK='Both';
      NO_ASSERT_CHECK='TRUE';
      NO_DIR_CHECK='TRUE';
      ALLOW_CONNECT='TRUE';
    'VDDCR_CPU1_DB46':
      PIN_NUMBER='(0,0,0,0,0,0,0,0,0,0,0,0,0,0,0,0,0,0,0,0,0,0,0,0,DB46,0,0,0,0,0,0,0,0,0,0,0,0,0,0,0)';
      PINUSE='POWER';
      NO_LOAD_CHECK='Both';
      NO_IO_CHECK='Both';
      NO_ASSERT_CHECK='TRUE';
      NO_DIR_CHECK='TRUE';
      ALLOW_CONNECT='TRUE';
    'VDDCR_CPU1_DB47':
      PIN_NUMBER='(0,0,0,0,0,0,0,0,0,0,0,0,0,0,0,0,0,0,0,0,0,0,0,0,DB47,0,0,0,0,0,0,0,0,0,0,0,0,0,0,0)';
      PINUSE='POWER';
      NO_LOAD_CHECK='Both';
      NO_IO_CHECK='Both';
      NO_ASSERT_CHECK='TRUE';
      NO_DIR_CHECK='TRUE';
      ALLOW_CONNECT='TRUE';
    'VDDCR_CPU1_DB49':
      PIN_NUMBER='(0,0,0,0,0,0,0,0,0,0,0,0,0,0,0,0,0,0,0,0,0,0,0,0,DB49,0,0,0,0,0,0,0,0,0,0,0,0,0,0,0)';
      PINUSE='POWER';
      NO_LOAD_CHECK='Both';
      NO_IO_CHECK='Both';
      NO_ASSERT_CHECK='TRUE';
      NO_DIR_CHECK='TRUE';
      ALLOW_CONNECT='TRUE';
    'VDDCR_CPU1_DB50':
      PIN_NUMBER='(0,0,0,0,0,0,0,0,0,0,0,0,0,0,0,0,0,0,0,0,0,0,0,0,DB50,0,0,0,0,0,0,0,0,0,0,0,0,0,0,0)';
      PINUSE='POWER';
      NO_LOAD_CHECK='Both';
      NO_IO_CHECK='Both';
      NO_ASSERT_CHECK='TRUE';
      NO_DIR_CHECK='TRUE';
      ALLOW_CONNECT='TRUE';
    'VDDCR_CPU1_DB52':
      PIN_NUMBER='(0,0,0,0,0,0,0,0,0,0,0,0,0,0,0,0,0,0,0,0,0,0,0,0,DB52,0,0,0,0,0,0,0,0,0,0,0,0,0,0,0)';
      PINUSE='POWER';
      NO_LOAD_CHECK='Both';
      NO_IO_CHECK='Both';
      NO_ASSERT_CHECK='TRUE';
      NO_DIR_CHECK='TRUE';
      ALLOW_CONNECT='TRUE';
    'VDDCR_CPU1_DB53':
      PIN_NUMBER='(0,0,0,0,0,0,0,0,0,0,0,0,0,0,0,0,0,0,0,0,0,0,0,0,DB53,0,0,0,0,0,0,0,0,0,0,0,0,0,0,0)';
      PINUSE='POWER';
      NO_LOAD_CHECK='Both';
      NO_IO_CHECK='Both';
      NO_ASSERT_CHECK='TRUE';
      NO_DIR_CHECK='TRUE';
      ALLOW_CONNECT='TRUE';
    'VDDCR_CPU1_DC35':
      PIN_NUMBER='(0,0,0,0,0,0,0,0,0,0,0,0,0,0,0,0,0,0,0,0,0,0,0,0,DC35,0,0,0,0,0,0,0,0,0,0,0,0,0,0,0)';
      PINUSE='POWER';
      NO_LOAD_CHECK='Both';
      NO_IO_CHECK='Both';
      NO_ASSERT_CHECK='TRUE';
      NO_DIR_CHECK='TRUE';
      ALLOW_CONNECT='TRUE';
    'VDDCR_CPU1_DC36':
      PIN_NUMBER='(0,0,0,0,0,0,0,0,0,0,0,0,0,0,0,0,0,0,0,0,0,0,0,0,DC36,0,0,0,0,0,0,0,0,0,0,0,0,0,0,0)';
      PINUSE='POWER';
      NO_LOAD_CHECK='Both';
      NO_IO_CHECK='Both';
      NO_ASSERT_CHECK='TRUE';
      NO_DIR_CHECK='TRUE';
      ALLOW_CONNECT='TRUE';
    'VDDCR_CPU1_DC40':
      PIN_NUMBER='(0,0,0,0,0,0,0,0,0,0,0,0,0,0,0,0,0,0,0,0,0,0,0,0,DC40,0,0,0,0,0,0,0,0,0,0,0,0,0,0,0)';
      PINUSE='POWER';
      NO_LOAD_CHECK='Both';
      NO_IO_CHECK='Both';
      NO_ASSERT_CHECK='TRUE';
      NO_DIR_CHECK='TRUE';
      ALLOW_CONNECT='TRUE';
    'VDDCR_CPU1_DC41':
      PIN_NUMBER='(0,0,0,0,0,0,0,0,0,0,0,0,0,0,0,0,0,0,0,0,0,0,0,0,DC41,0,0,0,0,0,0,0,0,0,0,0,0,0,0,0)';
      PINUSE='POWER';
      NO_LOAD_CHECK='Both';
      NO_IO_CHECK='Both';
      NO_ASSERT_CHECK='TRUE';
      NO_DIR_CHECK='TRUE';
      ALLOW_CONNECT='TRUE';
    'VDDCR_CPU1_DD22':
      PIN_NUMBER='(0,0,0,0,0,0,0,0,0,0,0,0,0,0,0,0,0,0,0,0,0,0,0,0,DD22,0,0,0,0,0,0,0,0,0,0,0,0,0,0,0)';
      PINUSE='POWER';
      NO_LOAD_CHECK='Both';
      NO_IO_CHECK='Both';
      NO_ASSERT_CHECK='TRUE';
      NO_DIR_CHECK='TRUE';
      ALLOW_CONNECT='TRUE';
    'VDDCR_CPU1_DD25':
      PIN_NUMBER='(0,0,0,0,0,0,0,0,0,0,0,0,0,0,0,0,0,0,0,0,0,0,0,0,DD25,0,0,0,0,0,0,0,0,0,0,0,0,0,0,0)';
      PINUSE='POWER';
      NO_LOAD_CHECK='Both';
      NO_IO_CHECK='Both';
      NO_ASSERT_CHECK='TRUE';
      NO_DIR_CHECK='TRUE';
      ALLOW_CONNECT='TRUE';
    'VDDCR_CPU1_DD28':
      PIN_NUMBER='(0,0,0,0,0,0,0,0,0,0,0,0,0,0,0,0,0,0,0,0,0,0,0,0,DD28,0,0,0,0,0,0,0,0,0,0,0,0,0,0,0)';
      PINUSE='POWER';
      NO_LOAD_CHECK='Both';
      NO_IO_CHECK='Both';
      NO_ASSERT_CHECK='TRUE';
      NO_DIR_CHECK='TRUE';
      ALLOW_CONNECT='TRUE';
    'VDDCR_CPU1_DD31':
      PIN_NUMBER='(0,0,0,0,0,0,0,0,0,0,0,0,0,0,0,0,0,0,0,0,0,0,0,0,DD31,0,0,0,0,0,0,0,0,0,0,0,0,0,0,0)';
      PINUSE='POWER';
      NO_LOAD_CHECK='Both';
      NO_IO_CHECK='Both';
      NO_ASSERT_CHECK='TRUE';
      NO_DIR_CHECK='TRUE';
      ALLOW_CONNECT='TRUE';
    'VDDCR_CPU1_DD34':
      PIN_NUMBER='(0,0,0,0,0,0,0,0,0,0,0,0,0,0,0,0,0,0,0,0,0,0,0,0,DD34,0,0,0,0,0,0,0,0,0,0,0,0,0,0,0)';
      PINUSE='POWER';
      NO_LOAD_CHECK='Both';
      NO_IO_CHECK='Both';
      NO_ASSERT_CHECK='TRUE';
      NO_DIR_CHECK='TRUE';
      ALLOW_CONNECT='TRUE';
    'VDDCR_CPU1_DD42':
      PIN_NUMBER='(0,0,0,0,0,0,0,0,0,0,0,0,0,0,0,0,0,0,0,0,0,0,0,0,DD42,0,0,0,0,0,0,0,0,0,0,0,0,0,0,0)';
      PINUSE='POWER';
      NO_LOAD_CHECK='Both';
      NO_IO_CHECK='Both';
      NO_ASSERT_CHECK='TRUE';
      NO_DIR_CHECK='TRUE';
      ALLOW_CONNECT='TRUE';
    'VDDCR_CPU1_DD45':
      PIN_NUMBER='(0,0,0,0,0,0,0,0,0,0,0,0,0,0,0,0,0,0,0,0,0,0,0,0,DD45,0,0,0,0,0,0,0,0,0,0,0,0,0,0,0)';
      PINUSE='POWER';
      NO_LOAD_CHECK='Both';
      NO_IO_CHECK='Both';
      NO_ASSERT_CHECK='TRUE';
      NO_DIR_CHECK='TRUE';
      ALLOW_CONNECT='TRUE';
    'VDDCR_CPU1_DD48':
      PIN_NUMBER='(0,0,0,0,0,0,0,0,0,0,0,0,0,0,0,0,0,0,0,0,0,0,0,0,DD48,0,0,0,0,0,0,0,0,0,0,0,0,0,0,0)';
      PINUSE='POWER';
      NO_LOAD_CHECK='Both';
      NO_IO_CHECK='Both';
      NO_ASSERT_CHECK='TRUE';
      NO_DIR_CHECK='TRUE';
      ALLOW_CONNECT='TRUE';
    'VDDCR_CPU1_DD51':
      PIN_NUMBER='(0,0,0,0,0,0,0,0,0,0,0,0,0,0,0,0,0,0,0,0,0,0,0,0,DD51,0,0,0,0,0,0,0,0,0,0,0,0,0,0,0)';
      PINUSE='POWER';
      NO_LOAD_CHECK='Both';
      NO_IO_CHECK='Both';
      NO_ASSERT_CHECK='TRUE';
      NO_DIR_CHECK='TRUE';
      ALLOW_CONNECT='TRUE';
    'VDDCR_CPU1_DD54':
      PIN_NUMBER='(0,0,0,0,0,0,0,0,0,0,0,0,0,0,0,0,0,0,0,0,0,0,0,0,DD54,0,0,0,0,0,0,0,0,0,0,0,0,0,0,0)';
      PINUSE='POWER';
      NO_LOAD_CHECK='Both';
      NO_IO_CHECK='Both';
      NO_ASSERT_CHECK='TRUE';
      NO_DIR_CHECK='TRUE';
      ALLOW_CONNECT='TRUE';
    'VDDCR_CPU1_DE22':
      PIN_NUMBER='(0,0,0,0,0,0,0,0,0,0,0,0,0,0,0,0,0,0,0,0,0,0,0,0,DE22,0,0,0,0,0,0,0,0,0,0,0,0,0,0,0)';
      PINUSE='POWER';
      NO_LOAD_CHECK='Both';
      NO_IO_CHECK='Both';
      NO_ASSERT_CHECK='TRUE';
      NO_DIR_CHECK='TRUE';
      ALLOW_CONNECT='TRUE';
    'VDDCR_CPU1_DE25':
      PIN_NUMBER='(0,0,0,0,0,0,0,0,0,0,0,0,0,0,0,0,0,0,0,0,0,0,0,0,DE25,0,0,0,0,0,0,0,0,0,0,0,0,0,0,0)';
      PINUSE='POWER';
      NO_LOAD_CHECK='Both';
      NO_IO_CHECK='Both';
      NO_ASSERT_CHECK='TRUE';
      NO_DIR_CHECK='TRUE';
      ALLOW_CONNECT='TRUE';
    'VDDCR_CPU1_DE28':
      PIN_NUMBER='(0,0,0,0,0,0,0,0,0,0,0,0,0,0,0,0,0,0,0,0,0,0,0,0,DE28,0,0,0,0,0,0,0,0,0,0,0,0,0,0,0)';
      PINUSE='POWER';
      NO_LOAD_CHECK='Both';
      NO_IO_CHECK='Both';
      NO_ASSERT_CHECK='TRUE';
      NO_DIR_CHECK='TRUE';
      ALLOW_CONNECT='TRUE';
    'VDDCR_CPU1_DE31':
      PIN_NUMBER='(0,0,0,0,0,0,0,0,0,0,0,0,0,0,0,0,0,0,0,0,0,0,0,0,DE31,0,0,0,0,0,0,0,0,0,0,0,0,0,0,0)';
      PINUSE='POWER';
      NO_LOAD_CHECK='Both';
      NO_IO_CHECK='Both';
      NO_ASSERT_CHECK='TRUE';
      NO_DIR_CHECK='TRUE';
      ALLOW_CONNECT='TRUE';
    'VDDCR_CPU1_DE34':
      PIN_NUMBER='(0,0,0,0,0,0,0,0,0,0,0,0,0,0,0,0,0,0,0,0,0,0,0,0,DE34,0,0,0,0,0,0,0,0,0,0,0,0,0,0,0)';
      PINUSE='POWER';
      NO_LOAD_CHECK='Both';
      NO_IO_CHECK='Both';
      NO_ASSERT_CHECK='TRUE';
      NO_DIR_CHECK='TRUE';
      ALLOW_CONNECT='TRUE';
    'VDDCR_CPU1_DE35':
      PIN_NUMBER='(0,0,0,0,0,0,0,0,0,0,0,0,0,0,0,0,0,0,0,0,0,0,0,0,DE35,0,0,0,0,0,0,0,0,0,0,0,0,0,0,0)';
      PINUSE='POWER';
      NO_LOAD_CHECK='Both';
      NO_IO_CHECK='Both';
      NO_ASSERT_CHECK='TRUE';
      NO_DIR_CHECK='TRUE';
      ALLOW_CONNECT='TRUE';
    'VDDCR_CPU1_DE41':
      PIN_NUMBER='(0,0,0,0,0,0,0,0,0,0,0,0,0,0,0,0,0,0,0,0,0,0,0,0,DE41,0,0,0,0,0,0,0,0,0,0,0,0,0,0,0)';
      PINUSE='POWER';
      NO_LOAD_CHECK='Both';
      NO_IO_CHECK='Both';
      NO_ASSERT_CHECK='TRUE';
      NO_DIR_CHECK='TRUE';
      ALLOW_CONNECT='TRUE';
    'VDDCR_CPU1_DE42':
      PIN_NUMBER='(0,0,0,0,0,0,0,0,0,0,0,0,0,0,0,0,0,0,0,0,0,0,0,0,DE42,0,0,0,0,0,0,0,0,0,0,0,0,0,0,0)';
      PINUSE='POWER';
      NO_LOAD_CHECK='Both';
      NO_IO_CHECK='Both';
      NO_ASSERT_CHECK='TRUE';
      NO_DIR_CHECK='TRUE';
      ALLOW_CONNECT='TRUE';
    'VDDCR_CPU1_DE45':
      PIN_NUMBER='(0,0,0,0,0,0,0,0,0,0,0,0,0,0,0,0,0,0,0,0,0,0,0,0,DE45,0,0,0,0,0,0,0,0,0,0,0,0,0,0,0)';
      PINUSE='POWER';
      NO_LOAD_CHECK='Both';
      NO_IO_CHECK='Both';
      NO_ASSERT_CHECK='TRUE';
      NO_DIR_CHECK='TRUE';
      ALLOW_CONNECT='TRUE';
    'VDDCR_CPU1_DE48':
      PIN_NUMBER='(0,0,0,0,0,0,0,0,0,0,0,0,0,0,0,0,0,0,0,0,0,0,0,0,DE48,0,0,0,0,0,0,0,0,0,0,0,0,0,0,0)';
      PINUSE='POWER';
      NO_LOAD_CHECK='Both';
      NO_IO_CHECK='Both';
      NO_ASSERT_CHECK='TRUE';
      NO_DIR_CHECK='TRUE';
      ALLOW_CONNECT='TRUE';
    'VDDCR_CPU1_DE51':
      PIN_NUMBER='(0,0,0,0,0,0,0,0,0,0,0,0,0,0,0,0,0,0,0,0,0,0,0,0,DE51,0,0,0,0,0,0,0,0,0,0,0,0,0,0,0)';
      PINUSE='POWER';
      NO_LOAD_CHECK='Both';
      NO_IO_CHECK='Both';
      NO_ASSERT_CHECK='TRUE';
      NO_DIR_CHECK='TRUE';
      ALLOW_CONNECT='TRUE';
    'VDDCR_CPU1_DE54':
      PIN_NUMBER='(0,0,0,0,0,0,0,0,0,0,0,0,0,0,0,0,0,0,0,0,0,0,0,0,DE54,0,0,0,0,0,0,0,0,0,0,0,0,0,0,0)';
      PINUSE='POWER';
      NO_LOAD_CHECK='Both';
      NO_IO_CHECK='Both';
      NO_ASSERT_CHECK='TRUE';
      NO_DIR_CHECK='TRUE';
      ALLOW_CONNECT='TRUE';
    'VDDCR_CPU1_DG19':
      PIN_NUMBER='(0,0,0,0,0,0,0,0,0,0,0,0,0,0,0,0,0,0,0,0,0,0,0,0,DG19,0,0,0,0,0,0,0,0,0,0,0,0,0,0,0)';
      PINUSE='POWER';
      NO_LOAD_CHECK='Both';
      NO_IO_CHECK='Both';
      NO_ASSERT_CHECK='TRUE';
      NO_DIR_CHECK='TRUE';
      ALLOW_CONNECT='TRUE';
    'VDDCR_CPU1_DG57':
      PIN_NUMBER='(0,0,0,0,0,0,0,0,0,0,0,0,0,0,0,0,0,0,0,0,0,0,0,0,DG57,0,0,0,0,0,0,0,0,0,0,0,0,0,0,0)';
      PINUSE='POWER';
      NO_LOAD_CHECK='Both';
      NO_IO_CHECK='Both';
      NO_ASSERT_CHECK='TRUE';
      NO_DIR_CHECK='TRUE';
      ALLOW_CONNECT='TRUE';
    'VDDCR_CPU1_DH19':
      PIN_NUMBER='(0,0,0,0,0,0,0,0,0,0,0,0,0,0,0,0,0,0,0,0,0,0,0,0,DH19,0,0,0,0,0,0,0,0,0,0,0,0,0,0,0)';
      PINUSE='POWER';
      NO_LOAD_CHECK='Both';
      NO_IO_CHECK='Both';
      NO_ASSERT_CHECK='TRUE';
      NO_DIR_CHECK='TRUE';
      ALLOW_CONNECT='TRUE';
    'VDDCR_CPU1_DH20':
      PIN_NUMBER='(0,0,0,0,0,0,0,0,0,0,0,0,0,0,0,0,0,0,0,0,0,0,0,0,DH20,0,0,0,0,0,0,0,0,0,0,0,0,0,0,0)';
      PINUSE='POWER';
      NO_LOAD_CHECK='Both';
      NO_IO_CHECK='Both';
      NO_ASSERT_CHECK='TRUE';
      NO_DIR_CHECK='TRUE';
      ALLOW_CONNECT='TRUE';
    'VDDCR_CPU1_DH22':
      PIN_NUMBER='(0,0,0,0,0,0,0,0,0,0,0,0,0,0,0,0,0,0,0,0,0,0,0,0,DH22,0,0,0,0,0,0,0,0,0,0,0,0,0,0,0)';
      PINUSE='POWER';
      NO_LOAD_CHECK='Both';
      NO_IO_CHECK='Both';
      NO_ASSERT_CHECK='TRUE';
      NO_DIR_CHECK='TRUE';
      ALLOW_CONNECT='TRUE';
    'VDDCR_CPU1_DH23':
      PIN_NUMBER='(0,0,0,0,0,0,0,0,0,0,0,0,0,0,0,0,0,0,0,0,0,0,0,0,DH23,0,0,0,0,0,0,0,0,0,0,0,0,0,0,0)';
      PINUSE='POWER';
      NO_LOAD_CHECK='Both';
      NO_IO_CHECK='Both';
      NO_ASSERT_CHECK='TRUE';
      NO_DIR_CHECK='TRUE';
      ALLOW_CONNECT='TRUE';
    'VDDCR_CPU1_DH25':
      PIN_NUMBER='(0,0,0,0,0,0,0,0,0,0,0,0,0,0,0,0,0,0,0,0,0,0,0,0,DH25,0,0,0,0,0,0,0,0,0,0,0,0,0,0,0)';
      PINUSE='POWER';
      NO_LOAD_CHECK='Both';
      NO_IO_CHECK='Both';
      NO_ASSERT_CHECK='TRUE';
      NO_DIR_CHECK='TRUE';
      ALLOW_CONNECT='TRUE';
    'VDDCR_CPU1_DH26':
      PIN_NUMBER='(0,0,0,0,0,0,0,0,0,0,0,0,0,0,0,0,0,0,0,0,0,0,0,0,DH26,0,0,0,0,0,0,0,0,0,0,0,0,0,0,0)';
      PINUSE='POWER';
      NO_LOAD_CHECK='Both';
      NO_IO_CHECK='Both';
      NO_ASSERT_CHECK='TRUE';
      NO_DIR_CHECK='TRUE';
      ALLOW_CONNECT='TRUE';
    'VDDCR_CPU1_DH28':
      PIN_NUMBER='(0,0,0,0,0,0,0,0,0,0,0,0,0,0,0,0,0,0,0,0,0,0,0,0,DH28,0,0,0,0,0,0,0,0,0,0,0,0,0,0,0)';
      PINUSE='POWER';
      NO_LOAD_CHECK='Both';
      NO_IO_CHECK='Both';
      NO_ASSERT_CHECK='TRUE';
      NO_DIR_CHECK='TRUE';
      ALLOW_CONNECT='TRUE';
    'VDDCR_CPU1_DH29':
      PIN_NUMBER='(0,0,0,0,0,0,0,0,0,0,0,0,0,0,0,0,0,0,0,0,0,0,0,0,DH29,0,0,0,0,0,0,0,0,0,0,0,0,0,0,0)';
      PINUSE='POWER';
      NO_LOAD_CHECK='Both';
      NO_IO_CHECK='Both';
      NO_ASSERT_CHECK='TRUE';
      NO_DIR_CHECK='TRUE';
      ALLOW_CONNECT='TRUE';
    'VDDCR_CPU1_DH31':
      PIN_NUMBER='(0,0,0,0,0,0,0,0,0,0,0,0,0,0,0,0,0,0,0,0,0,0,0,0,DH31,0,0,0,0,0,0,0,0,0,0,0,0,0,0,0)';
      PINUSE='POWER';
      NO_LOAD_CHECK='Both';
      NO_IO_CHECK='Both';
      NO_ASSERT_CHECK='TRUE';
      NO_DIR_CHECK='TRUE';
      ALLOW_CONNECT='TRUE';
    'VDDCR_CPU1_DH32':
      PIN_NUMBER='(0,0,0,0,0,0,0,0,0,0,0,0,0,0,0,0,0,0,0,0,0,0,0,0,DH32,0,0,0,0,0,0,0,0,0,0,0,0,0,0,0)';
      PINUSE='POWER';
      NO_LOAD_CHECK='Both';
      NO_IO_CHECK='Both';
      NO_ASSERT_CHECK='TRUE';
      NO_DIR_CHECK='TRUE';
      ALLOW_CONNECT='TRUE';
    'VDDCR_CPU1_DH34':
      PIN_NUMBER='(0,0,0,0,0,0,0,0,0,0,0,0,0,0,0,0,0,0,0,0,0,0,0,0,DH34,0,0,0,0,0,0,0,0,0,0,0,0,0,0,0)';
      PINUSE='POWER';
      NO_LOAD_CHECK='Both';
      NO_IO_CHECK='Both';
      NO_ASSERT_CHECK='TRUE';
      NO_DIR_CHECK='TRUE';
      ALLOW_CONNECT='TRUE';
    'VDDCR_CPU1_DH35':
      PIN_NUMBER='(0,0,0,0,0,0,0,0,0,0,0,0,0,0,0,0,0,0,0,0,0,0,0,0,DH35,0,0,0,0,0,0,0,0,0,0,0,0,0,0,0)';
      PINUSE='POWER';
      NO_LOAD_CHECK='Both';
      NO_IO_CHECK='Both';
      NO_ASSERT_CHECK='TRUE';
      NO_DIR_CHECK='TRUE';
      ALLOW_CONNECT='TRUE';
    'VDDCR_CPU1_DH41':
      PIN_NUMBER='(0,0,0,0,0,0,0,0,0,0,0,0,0,0,0,0,0,0,0,0,0,0,0,0,DH41,0,0,0,0,0,0,0,0,0,0,0,0,0,0,0)';
      PINUSE='POWER';
      NO_LOAD_CHECK='Both';
      NO_IO_CHECK='Both';
      NO_ASSERT_CHECK='TRUE';
      NO_DIR_CHECK='TRUE';
      ALLOW_CONNECT='TRUE';
    'VDDCR_CPU1_DH42':
      PIN_NUMBER='(0,0,0,0,0,0,0,0,0,0,0,0,0,0,0,0,0,0,0,0,0,0,0,0,DH42,0,0,0,0,0,0,0,0,0,0,0,0,0,0,0)';
      PINUSE='POWER';
      NO_LOAD_CHECK='Both';
      NO_IO_CHECK='Both';
      NO_ASSERT_CHECK='TRUE';
      NO_DIR_CHECK='TRUE';
      ALLOW_CONNECT='TRUE';
    'VDDCR_CPU1_DH44':
      PIN_NUMBER='(0,0,0,0,0,0,0,0,0,0,0,0,0,0,0,0,0,0,0,0,0,0,0,0,DH44,0,0,0,0,0,0,0,0,0,0,0,0,0,0,0)';
      PINUSE='POWER';
      NO_LOAD_CHECK='Both';
      NO_IO_CHECK='Both';
      NO_ASSERT_CHECK='TRUE';
      NO_DIR_CHECK='TRUE';
      ALLOW_CONNECT='TRUE';
    'VDDCR_CPU1_DH53':
      PIN_NUMBER='(0,0,0,0,0,0,0,0,0,0,0,0,0,0,0,0,0,0,0,0,0,0,0,0,DH53,0,0,0,0,0,0,0,0,0,0,0,0,0,0,0)';
      PINUSE='POWER';
      NO_LOAD_CHECK='Both';
      NO_IO_CHECK='Both';
      NO_ASSERT_CHECK='TRUE';
      NO_DIR_CHECK='TRUE';
      ALLOW_CONNECT='TRUE';
    'VDDCR_CPU1_DH54':
      PIN_NUMBER='(0,0,0,0,0,0,0,0,0,0,0,0,0,0,0,0,0,0,0,0,0,0,0,0,DH54,0,0,0,0,0,0,0,0,0,0,0,0,0,0,0)';
      PINUSE='POWER';
      NO_LOAD_CHECK='Both';
      NO_IO_CHECK='Both';
      NO_ASSERT_CHECK='TRUE';
      NO_DIR_CHECK='TRUE';
      ALLOW_CONNECT='TRUE';
    'VDDCR_CPU1_DH56':
      PIN_NUMBER='(0,0,0,0,0,0,0,0,0,0,0,0,0,0,0,0,0,0,0,0,0,0,0,0,DH56,0,0,0,0,0,0,0,0,0,0,0,0,0,0,0)';
      PINUSE='POWER';
      NO_LOAD_CHECK='Both';
      NO_IO_CHECK='Both';
      NO_ASSERT_CHECK='TRUE';
      NO_DIR_CHECK='TRUE';
      ALLOW_CONNECT='TRUE';
    'VDDCR_CPU1_DH57':
      PIN_NUMBER='(0,0,0,0,0,0,0,0,0,0,0,0,0,0,0,0,0,0,0,0,0,0,0,0,DH57,0,0,0,0,0,0,0,0,0,0,0,0,0,0,0)';
      PINUSE='POWER';
      NO_LOAD_CHECK='Both';
      NO_IO_CHECK='Both';
      NO_ASSERT_CHECK='TRUE';
      NO_DIR_CHECK='TRUE';
      ALLOW_CONNECT='TRUE';
    'VDDCR_CPU1_DH45':
      PIN_NUMBER='(0,0,0,0,0,0,0,0,0,0,0,0,0,0,0,0,0,0,0,0,0,0,0,0,DH45,0,0,0,0,0,0,0,0,0,0,0,0,0,0,0)';
      PINUSE='POWER';
      NO_LOAD_CHECK='Both';
      NO_IO_CHECK='Both';
      NO_ASSERT_CHECK='TRUE';
      NO_DIR_CHECK='TRUE';
      ALLOW_CONNECT='TRUE';
    'VDDCR_CPU1_DH47':
      PIN_NUMBER='(0,0,0,0,0,0,0,0,0,0,0,0,0,0,0,0,0,0,0,0,0,0,0,0,DH47,0,0,0,0,0,0,0,0,0,0,0,0,0,0,0)';
      PINUSE='POWER';
      NO_LOAD_CHECK='Both';
      NO_IO_CHECK='Both';
      NO_ASSERT_CHECK='TRUE';
      NO_DIR_CHECK='TRUE';
      ALLOW_CONNECT='TRUE';
    'VDDCR_CPU1_DH48':
      PIN_NUMBER='(0,0,0,0,0,0,0,0,0,0,0,0,0,0,0,0,0,0,0,0,0,0,0,0,DH48,0,0,0,0,0,0,0,0,0,0,0,0,0,0,0)';
      PINUSE='POWER';
      NO_LOAD_CHECK='Both';
      NO_IO_CHECK='Both';
      NO_ASSERT_CHECK='TRUE';
      NO_DIR_CHECK='TRUE';
      ALLOW_CONNECT='TRUE';
    'VDDCR_CPU1_DH50':
      PIN_NUMBER='(0,0,0,0,0,0,0,0,0,0,0,0,0,0,0,0,0,0,0,0,0,0,0,0,DH50,0,0,0,0,0,0,0,0,0,0,0,0,0,0,0)';
      PINUSE='POWER';
      NO_LOAD_CHECK='Both';
      NO_IO_CHECK='Both';
      NO_ASSERT_CHECK='TRUE';
      NO_DIR_CHECK='TRUE';
      ALLOW_CONNECT='TRUE';
    'VDDCR_CPU1_DH51':
      PIN_NUMBER='(0,0,0,0,0,0,0,0,0,0,0,0,0,0,0,0,0,0,0,0,0,0,0,0,DH51,0,0,0,0,0,0,0,0,0,0,0,0,0,0,0)';
      PINUSE='POWER';
      NO_LOAD_CHECK='Both';
      NO_IO_CHECK='Both';
      NO_ASSERT_CHECK='TRUE';
      NO_DIR_CHECK='TRUE';
      ALLOW_CONNECT='TRUE';
    'VDDCR_CPU1_BP24':
      PIN_NUMBER='(0,0,0,0,0,0,0,0,0,0,0,0,0,0,0,0,0,0,0,0,0,0,0,0,BP24,0,0,0,0,0,0,0,0,0,0,0,0,0,0,0)';
      PINUSE='POWER';
      NO_LOAD_CHECK='Both';
      NO_IO_CHECK='Both';
      NO_ASSERT_CHECK='TRUE';
      NO_DIR_CHECK='TRUE';
      ALLOW_CONNECT='TRUE';
    'VDDCR_CPU1_BP28':
      PIN_NUMBER='(0,0,0,0,0,0,0,0,0,0,0,0,0,0,0,0,0,0,0,0,0,0,0,0,BP28,0,0,0,0,0,0,0,0,0,0,0,0,0,0,0)';
      PINUSE='POWER';
      NO_LOAD_CHECK='Both';
      NO_IO_CHECK='Both';
      NO_ASSERT_CHECK='TRUE';
      NO_DIR_CHECK='TRUE';
      ALLOW_CONNECT='TRUE';
    'VDDCR_CPU1_BP32':
      PIN_NUMBER='(0,0,0,0,0,0,0,0,0,0,0,0,0,0,0,0,0,0,0,0,0,0,0,0,BP32,0,0,0,0,0,0,0,0,0,0,0,0,0,0,0)';
      PINUSE='POWER';
      NO_LOAD_CHECK='Both';
      NO_IO_CHECK='Both';
      NO_ASSERT_CHECK='TRUE';
      NO_DIR_CHECK='TRUE';
      ALLOW_CONNECT='TRUE';
    'VDDCR_CPU1_BN27':
      PIN_NUMBER='(0,0,0,0,0,0,0,0,0,0,0,0,0,0,0,0,0,0,0,0,0,0,0,0,BN27,0,0,0,0,0,0,0,0,0,0,0,0,0,0,0)';
      PINUSE='POWER';
      NO_LOAD_CHECK='Both';
      NO_IO_CHECK='Both';
      NO_ASSERT_CHECK='TRUE';
      NO_DIR_CHECK='TRUE';
      ALLOW_CONNECT='TRUE';
    'VDDCR_CPU1_BN35':
      PIN_NUMBER='(0,0,0,0,0,0,0,0,0,0,0,0,0,0,0,0,0,0,0,0,0,0,0,0,BN35,0,0,0,0,0,0,0,0,0,0,0,0,0,0,0)';
      PINUSE='POWER';
      NO_LOAD_CHECK='Both';
      NO_IO_CHECK='Both';
      NO_ASSERT_CHECK='TRUE';
      NO_DIR_CHECK='TRUE';
      ALLOW_CONNECT='TRUE';
    'VDDCR_CPU1_BN46':
      PIN_NUMBER='(0,0,0,0,0,0,0,0,0,0,0,0,0,0,0,0,0,0,0,0,0,0,0,0,BN46,0,0,0,0,0,0,0,0,0,0,0,0,0,0,0)';
      PINUSE='POWER';
      NO_LOAD_CHECK='Both';
      NO_IO_CHECK='Both';
      NO_ASSERT_CHECK='TRUE';
      NO_DIR_CHECK='TRUE';
      ALLOW_CONNECT='TRUE';
    'VDDCR_SOC_B5':
      PIN_NUMBER='(0,0,0,0,0,0,0,0,0,0,0,0,0,0,0,0,0,0,0,0,0,0,0,0,0,B5,0,0,0,0,0,0,0,0,0,0,0,0,0,0)';
      PINUSE='POWER';
      NO_LOAD_CHECK='Both';
      NO_IO_CHECK='Both';
      NO_ASSERT_CHECK='TRUE';
      NO_DIR_CHECK='TRUE';
      ALLOW_CONNECT='TRUE';
    'VDDCR_SOC_C4':
      PIN_NUMBER='(0,0,0,0,0,0,0,0,0,0,0,0,0,0,0,0,0,0,0,0,0,0,0,0,0,C4,0,0,0,0,0,0,0,0,0,0,0,0,0,0)';
      PINUSE='POWER';
      NO_LOAD_CHECK='Both';
      NO_IO_CHECK='Both';
      NO_ASSERT_CHECK='TRUE';
      NO_DIR_CHECK='TRUE';
      ALLOW_CONNECT='TRUE';
    'VDDCR_SOC_E4':
      PIN_NUMBER='(0,0,0,0,0,0,0,0,0,0,0,0,0,0,0,0,0,0,0,0,0,0,0,0,0,E4,0,0,0,0,0,0,0,0,0,0,0,0,0,0)';
      PINUSE='POWER';
      NO_LOAD_CHECK='Both';
      NO_IO_CHECK='Both';
      NO_ASSERT_CHECK='TRUE';
      NO_DIR_CHECK='TRUE';
      ALLOW_CONNECT='TRUE';
    'VDDCR_SOC_E11':
      PIN_NUMBER='(0,0,0,0,0,0,0,0,0,0,0,0,0,0,0,0,0,0,0,0,0,0,0,0,0,E11,0,0,0,0,0,0,0,0,0,0,0,0,0,0)';
      PINUSE='POWER';
      NO_LOAD_CHECK='Both';
      NO_IO_CHECK='Both';
      NO_ASSERT_CHECK='TRUE';
      NO_DIR_CHECK='TRUE';
      ALLOW_CONNECT='TRUE';
    'VDDCR_SOC_H5':
      PIN_NUMBER='(0,0,0,0,0,0,0,0,0,0,0,0,0,0,0,0,0,0,0,0,0,0,0,0,0,H5,0,0,0,0,0,0,0,0,0,0,0,0,0,0)';
      PINUSE='POWER';
      NO_LOAD_CHECK='Both';
      NO_IO_CHECK='Both';
      NO_ASSERT_CHECK='TRUE';
      NO_DIR_CHECK='TRUE';
      ALLOW_CONNECT='TRUE';
    'VDDCR_SOC_H12':
      PIN_NUMBER='(0,0,0,0,0,0,0,0,0,0,0,0,0,0,0,0,0,0,0,0,0,0,0,0,0,H12,0,0,0,0,0,0,0,0,0,0,0,0,0,0)';
      PINUSE='POWER';
      NO_LOAD_CHECK='Both';
      NO_IO_CHECK='Both';
      NO_ASSERT_CHECK='TRUE';
      NO_DIR_CHECK='TRUE';
      ALLOW_CONNECT='TRUE';
    'VDDCR_SOC_H19':
      PIN_NUMBER='(0,0,0,0,0,0,0,0,0,0,0,0,0,0,0,0,0,0,0,0,0,0,0,0,0,H19,0,0,0,0,0,0,0,0,0,0,0,0,0,0)';
      PINUSE='POWER';
      NO_LOAD_CHECK='Both';
      NO_IO_CHECK='Both';
      NO_ASSERT_CHECK='TRUE';
      NO_DIR_CHECK='TRUE';
      ALLOW_CONNECT='TRUE';
    'VDDCR_SOC_K22':
      PIN_NUMBER='(0,0,0,0,0,0,0,0,0,0,0,0,0,0,0,0,0,0,0,0,0,0,0,0,0,K22,0,0,0,0,0,0,0,0,0,0,0,0,0,0)';
      PINUSE='POWER';
      NO_LOAD_CHECK='Both';
      NO_IO_CHECK='Both';
      NO_ASSERT_CHECK='TRUE';
      NO_DIR_CHECK='TRUE';
      ALLOW_CONNECT='TRUE';
    'VDDCR_SOC_L4':
      PIN_NUMBER='(0,0,0,0,0,0,0,0,0,0,0,0,0,0,0,0,0,0,0,0,0,0,0,0,0,L4,0,0,0,0,0,0,0,0,0,0,0,0,0,0)';
      PINUSE='POWER';
      NO_LOAD_CHECK='Both';
      NO_IO_CHECK='Both';
      NO_ASSERT_CHECK='TRUE';
      NO_DIR_CHECK='TRUE';
      ALLOW_CONNECT='TRUE';
    'VDDCR_SOC_L11':
      PIN_NUMBER='(0,0,0,0,0,0,0,0,0,0,0,0,0,0,0,0,0,0,0,0,0,0,0,0,0,L11,0,0,0,0,0,0,0,0,0,0,0,0,0,0)';
      PINUSE='POWER';
      NO_LOAD_CHECK='Both';
      NO_IO_CHECK='Both';
      NO_ASSERT_CHECK='TRUE';
      NO_DIR_CHECK='TRUE';
      ALLOW_CONNECT='TRUE';
    'VDDCR_SOC_L18':
      PIN_NUMBER='(0,0,0,0,0,0,0,0,0,0,0,0,0,0,0,0,0,0,0,0,0,0,0,0,0,L18,0,0,0,0,0,0,0,0,0,0,0,0,0,0)';
      PINUSE='POWER';
      NO_LOAD_CHECK='Both';
      NO_IO_CHECK='Both';
      NO_ASSERT_CHECK='TRUE';
      NO_DIR_CHECK='TRUE';
      ALLOW_CONNECT='TRUE';
    'VDDCR_SOC_P5':
      PIN_NUMBER='(0,0,0,0,0,0,0,0,0,0,0,0,0,0,0,0,0,0,0,0,0,0,0,0,0,P5,0,0,0,0,0,0,0,0,0,0,0,0,0,0)';
      PINUSE='POWER';
      NO_LOAD_CHECK='Both';
      NO_IO_CHECK='Both';
      NO_ASSERT_CHECK='TRUE';
      NO_DIR_CHECK='TRUE';
      ALLOW_CONNECT='TRUE';
    'VDDCR_SOC_P12':
      PIN_NUMBER='(0,0,0,0,0,0,0,0,0,0,0,0,0,0,0,0,0,0,0,0,0,0,0,0,0,P12,0,0,0,0,0,0,0,0,0,0,0,0,0,0)';
      PINUSE='POWER';
      NO_LOAD_CHECK='Both';
      NO_IO_CHECK='Both';
      NO_ASSERT_CHECK='TRUE';
      NO_DIR_CHECK='TRUE';
      ALLOW_CONNECT='TRUE';
    'VDDCR_SOC_P19':
      PIN_NUMBER='(0,0,0,0,0,0,0,0,0,0,0,0,0,0,0,0,0,0,0,0,0,0,0,0,0,P19,0,0,0,0,0,0,0,0,0,0,0,0,0,0)';
      PINUSE='POWER';
      NO_LOAD_CHECK='Both';
      NO_IO_CHECK='Both';
      NO_ASSERT_CHECK='TRUE';
      NO_DIR_CHECK='TRUE';
      ALLOW_CONNECT='TRUE';
    'VDDCR_SOC_P22':
      PIN_NUMBER='(0,0,0,0,0,0,0,0,0,0,0,0,0,0,0,0,0,0,0,0,0,0,0,0,0,P22,0,0,0,0,0,0,0,0,0,0,0,0,0,0)';
      PINUSE='POWER';
      NO_LOAD_CHECK='Both';
      NO_IO_CHECK='Both';
      NO_ASSERT_CHECK='TRUE';
      NO_DIR_CHECK='TRUE';
      ALLOW_CONNECT='TRUE';
    'VDDCR_SOC_U4':
      PIN_NUMBER='(0,0,0,0,0,0,0,0,0,0,0,0,0,0,0,0,0,0,0,0,0,0,0,0,0,U4,0,0,0,0,0,0,0,0,0,0,0,0,0,0)';
      PINUSE='POWER';
      NO_LOAD_CHECK='Both';
      NO_IO_CHECK='Both';
      NO_ASSERT_CHECK='TRUE';
      NO_DIR_CHECK='TRUE';
      ALLOW_CONNECT='TRUE';
    'VDDCR_SOC_U11':
      PIN_NUMBER='(0,0,0,0,0,0,0,0,0,0,0,0,0,0,0,0,0,0,0,0,0,0,0,0,0,U11,0,0,0,0,0,0,0,0,0,0,0,0,0,0)';
      PINUSE='POWER';
      NO_LOAD_CHECK='Both';
      NO_IO_CHECK='Both';
      NO_ASSERT_CHECK='TRUE';
      NO_DIR_CHECK='TRUE';
      ALLOW_CONNECT='TRUE';
    'VDDCR_SOC_U18':
      PIN_NUMBER='(0,0,0,0,0,0,0,0,0,0,0,0,0,0,0,0,0,0,0,0,0,0,0,0,0,U18,0,0,0,0,0,0,0,0,0,0,0,0,0,0)';
      PINUSE='POWER';
      NO_LOAD_CHECK='Both';
      NO_IO_CHECK='Both';
      NO_ASSERT_CHECK='TRUE';
      NO_DIR_CHECK='TRUE';
      ALLOW_CONNECT='TRUE';
    'VDDCR_SOC_V22':
      PIN_NUMBER='(0,0,0,0,0,0,0,0,0,0,0,0,0,0,0,0,0,0,0,0,0,0,0,0,0,V22,0,0,0,0,0,0,0,0,0,0,0,0,0,0)';
      PINUSE='POWER';
      NO_LOAD_CHECK='Both';
      NO_IO_CHECK='Both';
      NO_ASSERT_CHECK='TRUE';
      NO_DIR_CHECK='TRUE';
      ALLOW_CONNECT='TRUE';
    'VDDCR_SOC_Y5':
      PIN_NUMBER='(0,0,0,0,0,0,0,0,0,0,0,0,0,0,0,0,0,0,0,0,0,0,0,0,0,Y5,0,0,0,0,0,0,0,0,0,0,0,0,0,0)';
      PINUSE='POWER';
      NO_LOAD_CHECK='Both';
      NO_IO_CHECK='Both';
      NO_ASSERT_CHECK='TRUE';
      NO_DIR_CHECK='TRUE';
      ALLOW_CONNECT='TRUE';
    'VDDCR_SOC_Y12':
      PIN_NUMBER='(0,0,0,0,0,0,0,0,0,0,0,0,0,0,0,0,0,0,0,0,0,0,0,0,0,Y12,0,0,0,0,0,0,0,0,0,0,0,0,0,0)';
      PINUSE='POWER';
      NO_LOAD_CHECK='Both';
      NO_IO_CHECK='Both';
      NO_ASSERT_CHECK='TRUE';
      NO_DIR_CHECK='TRUE';
      ALLOW_CONNECT='TRUE';
    'VDDCR_SOC_Y19':
      PIN_NUMBER='(0,0,0,0,0,0,0,0,0,0,0,0,0,0,0,0,0,0,0,0,0,0,0,0,0,Y19,0,0,0,0,0,0,0,0,0,0,0,0,0,0)';
      PINUSE='POWER';
      NO_LOAD_CHECK='Both';
      NO_IO_CHECK='Both';
      NO_ASSERT_CHECK='TRUE';
      NO_DIR_CHECK='TRUE';
      ALLOW_CONNECT='TRUE';
    'VDDCR_SOC_AA22':
      PIN_NUMBER='(0,0,0,0,0,0,0,0,0,0,0,0,0,0,0,0,0,0,0,0,0,0,0,0,0,AA22,0,0,0,0,0,0,0,0,0,0,0,0,0,0)';
      PINUSE='POWER';
      NO_LOAD_CHECK='Both';
      NO_IO_CHECK='Both';
      NO_ASSERT_CHECK='TRUE';
      NO_DIR_CHECK='TRUE';
      ALLOW_CONNECT='TRUE';
    'VDDCR_SOC_AC4':
      PIN_NUMBER='(0,0,0,0,0,0,0,0,0,0,0,0,0,0,0,0,0,0,0,0,0,0,0,0,0,AC4,0,0,0,0,0,0,0,0,0,0,0,0,0,0)';
      PINUSE='POWER';
      NO_LOAD_CHECK='Both';
      NO_IO_CHECK='Both';
      NO_ASSERT_CHECK='TRUE';
      NO_DIR_CHECK='TRUE';
      ALLOW_CONNECT='TRUE';
    'VDDCR_SOC_AC11':
      PIN_NUMBER='(0,0,0,0,0,0,0,0,0,0,0,0,0,0,0,0,0,0,0,0,0,0,0,0,0,AC11,0,0,0,0,0,0,0,0,0,0,0,0,0,0)';
      PINUSE='POWER';
      NO_LOAD_CHECK='Both';
      NO_IO_CHECK='Both';
      NO_ASSERT_CHECK='TRUE';
      NO_DIR_CHECK='TRUE';
      ALLOW_CONNECT='TRUE';
    'VDDCR_SOC_AC18':
      PIN_NUMBER='(0,0,0,0,0,0,0,0,0,0,0,0,0,0,0,0,0,0,0,0,0,0,0,0,0,AC18,0,0,0,0,0,0,0,0,0,0,0,0,0,0)';
      PINUSE='POWER';
      NO_LOAD_CHECK='Both';
      NO_IO_CHECK='Both';
      NO_ASSERT_CHECK='TRUE';
      NO_DIR_CHECK='TRUE';
      ALLOW_CONNECT='TRUE';
    'VDDCR_SOC_AD22':
      PIN_NUMBER='(0,0,0,0,0,0,0,0,0,0,0,0,0,0,0,0,0,0,0,0,0,0,0,0,0,AD22,0,0,0,0,0,0,0,0,0,0,0,0,0,0)';
      PINUSE='POWER';
      NO_LOAD_CHECK='Both';
      NO_IO_CHECK='Both';
      NO_ASSERT_CHECK='TRUE';
      NO_DIR_CHECK='TRUE';
      ALLOW_CONNECT='TRUE';
    'VDDCR_SOC_AF5':
      PIN_NUMBER='(0,0,0,0,0,0,0,0,0,0,0,0,0,0,0,0,0,0,0,0,0,0,0,0,0,AF5,0,0,0,0,0,0,0,0,0,0,0,0,0,0)';
      PINUSE='POWER';
      NO_LOAD_CHECK='Both';
      NO_IO_CHECK='Both';
      NO_ASSERT_CHECK='TRUE';
      NO_DIR_CHECK='TRUE';
      ALLOW_CONNECT='TRUE';
    'VDDCR_SOC_AF12':
      PIN_NUMBER='(0,0,0,0,0,0,0,0,0,0,0,0,0,0,0,0,0,0,0,0,0,0,0,0,0,AF12,0,0,0,0,0,0,0,0,0,0,0,0,0,0)';
      PINUSE='POWER';
      NO_LOAD_CHECK='Both';
      NO_IO_CHECK='Both';
      NO_ASSERT_CHECK='TRUE';
      NO_DIR_CHECK='TRUE';
      ALLOW_CONNECT='TRUE';
    'VDDCR_SOC_AF19':
      PIN_NUMBER='(0,0,0,0,0,0,0,0,0,0,0,0,0,0,0,0,0,0,0,0,0,0,0,0,0,AF19,0,0,0,0,0,0,0,0,0,0,0,0,0,0)';
      PINUSE='POWER';
      NO_LOAD_CHECK='Both';
      NO_IO_CHECK='Both';
      NO_ASSERT_CHECK='TRUE';
      NO_DIR_CHECK='TRUE';
      ALLOW_CONNECT='TRUE';
    'VDDCR_SOC_AH22':
      PIN_NUMBER='(0,0,0,0,0,0,0,0,0,0,0,0,0,0,0,0,0,0,0,0,0,0,0,0,0,AH22,0,0,0,0,0,0,0,0,0,0,0,0,0,0)';
      PINUSE='POWER';
      NO_LOAD_CHECK='Both';
      NO_IO_CHECK='Both';
      NO_ASSERT_CHECK='TRUE';
      NO_DIR_CHECK='TRUE';
      ALLOW_CONNECT='TRUE';
    'VDDCR_SOC_AJ4':
      PIN_NUMBER='(0,0,0,0,0,0,0,0,0,0,0,0,0,0,0,0,0,0,0,0,0,0,0,0,0,AJ4,0,0,0,0,0,0,0,0,0,0,0,0,0,0)';
      PINUSE='POWER';
      NO_LOAD_CHECK='Both';
      NO_IO_CHECK='Both';
      NO_ASSERT_CHECK='TRUE';
      NO_DIR_CHECK='TRUE';
      ALLOW_CONNECT='TRUE';
    'VDDCR_SOC_AJ11':
      PIN_NUMBER='(0,0,0,0,0,0,0,0,0,0,0,0,0,0,0,0,0,0,0,0,0,0,0,0,0,AJ11,0,0,0,0,0,0,0,0,0,0,0,0,0,0)';
      PINUSE='POWER';
      NO_LOAD_CHECK='Both';
      NO_IO_CHECK='Both';
      NO_ASSERT_CHECK='TRUE';
      NO_DIR_CHECK='TRUE';
      ALLOW_CONNECT='TRUE';
    'VDDCR_SOC_AJ18':
      PIN_NUMBER='(0,0,0,0,0,0,0,0,0,0,0,0,0,0,0,0,0,0,0,0,0,0,0,0,0,AJ18,0,0,0,0,0,0,0,0,0,0,0,0,0,0)';
      PINUSE='POWER';
      NO_LOAD_CHECK='Both';
      NO_IO_CHECK='Both';
      NO_ASSERT_CHECK='TRUE';
      NO_DIR_CHECK='TRUE';
      ALLOW_CONNECT='TRUE';
    'VDDCR_SOC_AM5':
      PIN_NUMBER='(0,0,0,0,0,0,0,0,0,0,0,0,0,0,0,0,0,0,0,0,0,0,0,0,0,AM5,0,0,0,0,0,0,0,0,0,0,0,0,0,0)';
      PINUSE='POWER';
      NO_LOAD_CHECK='Both';
      NO_IO_CHECK='Both';
      NO_ASSERT_CHECK='TRUE';
      NO_DIR_CHECK='TRUE';
      ALLOW_CONNECT='TRUE';
    'VDDCR_SOC_AM12':
      PIN_NUMBER='(0,0,0,0,0,0,0,0,0,0,0,0,0,0,0,0,0,0,0,0,0,0,0,0,0,AM12,0,0,0,0,0,0,0,0,0,0,0,0,0,0)';
      PINUSE='POWER';
      NO_LOAD_CHECK='Both';
      NO_IO_CHECK='Both';
      NO_ASSERT_CHECK='TRUE';
      NO_DIR_CHECK='TRUE';
      ALLOW_CONNECT='TRUE';
    'VDDCR_SOC_AM19':
      PIN_NUMBER='(0,0,0,0,0,0,0,0,0,0,0,0,0,0,0,0,0,0,0,0,0,0,0,0,0,AM19,0,0,0,0,0,0,0,0,0,0,0,0,0,0)';
      PINUSE='POWER';
      NO_LOAD_CHECK='Both';
      NO_IO_CHECK='Both';
      NO_ASSERT_CHECK='TRUE';
      NO_DIR_CHECK='TRUE';
      ALLOW_CONNECT='TRUE';
    'VDDCR_SOC_AM22':
      PIN_NUMBER='(0,0,0,0,0,0,0,0,0,0,0,0,0,0,0,0,0,0,0,0,0,0,0,0,0,AM22,0,0,0,0,0,0,0,0,0,0,0,0,0,0)';
      PINUSE='POWER';
      NO_LOAD_CHECK='Both';
      NO_IO_CHECK='Both';
      NO_ASSERT_CHECK='TRUE';
      NO_DIR_CHECK='TRUE';
      ALLOW_CONNECT='TRUE';
    'VDDCR_SOC_AR4':
      PIN_NUMBER='(0,0,0,0,0,0,0,0,0,0,0,0,0,0,0,0,0,0,0,0,0,0,0,0,0,AR4,0,0,0,0,0,0,0,0,0,0,0,0,0,0)';
      PINUSE='POWER';
      NO_LOAD_CHECK='Both';
      NO_IO_CHECK='Both';
      NO_ASSERT_CHECK='TRUE';
      NO_DIR_CHECK='TRUE';
      ALLOW_CONNECT='TRUE';
    'VDDCR_SOC_AR11':
      PIN_NUMBER='(0,0,0,0,0,0,0,0,0,0,0,0,0,0,0,0,0,0,0,0,0,0,0,0,0,AR11,0,0,0,0,0,0,0,0,0,0,0,0,0,0)';
      PINUSE='POWER';
      NO_LOAD_CHECK='Both';
      NO_IO_CHECK='Both';
      NO_ASSERT_CHECK='TRUE';
      NO_DIR_CHECK='TRUE';
      ALLOW_CONNECT='TRUE';
    'VDDCR_SOC_AR18':
      PIN_NUMBER='(0,0,0,0,0,0,0,0,0,0,0,0,0,0,0,0,0,0,0,0,0,0,0,0,0,AR18,0,0,0,0,0,0,0,0,0,0,0,0,0,0)';
      PINUSE='POWER';
      NO_LOAD_CHECK='Both';
      NO_IO_CHECK='Both';
      NO_ASSERT_CHECK='TRUE';
      NO_DIR_CHECK='TRUE';
      ALLOW_CONNECT='TRUE';
    'VDDCR_SOC_AT22':
      PIN_NUMBER='(0,0,0,0,0,0,0,0,0,0,0,0,0,0,0,0,0,0,0,0,0,0,0,0,0,AT22,0,0,0,0,0,0,0,0,0,0,0,0,0,0)';
      PINUSE='POWER';
      NO_LOAD_CHECK='Both';
      NO_IO_CHECK='Both';
      NO_ASSERT_CHECK='TRUE';
      NO_DIR_CHECK='TRUE';
      ALLOW_CONNECT='TRUE';
    'VDDCR_SOC_AU23':
      PIN_NUMBER='(0,0,0,0,0,0,0,0,0,0,0,0,0,0,0,0,0,0,0,0,0,0,0,0,0,AU23,0,0,0,0,0,0,0,0,0,0,0,0,0,0)';
      PINUSE='POWER';
      NO_LOAD_CHECK='Both';
      NO_IO_CHECK='Both';
      NO_ASSERT_CHECK='TRUE';
      NO_DIR_CHECK='TRUE';
      ALLOW_CONNECT='TRUE';
    'VDDCR_SOC_AU27':
      PIN_NUMBER='(0,0,0,0,0,0,0,0,0,0,0,0,0,0,0,0,0,0,0,0,0,0,0,0,0,AU27,0,0,0,0,0,0,0,0,0,0,0,0,0,0)';
      PINUSE='POWER';
      NO_LOAD_CHECK='Both';
      NO_IO_CHECK='Both';
      NO_ASSERT_CHECK='TRUE';
      NO_DIR_CHECK='TRUE';
      ALLOW_CONNECT='TRUE';
    'VDDCR_SOC_AU31':
      PIN_NUMBER='(0,0,0,0,0,0,0,0,0,0,0,0,0,0,0,0,0,0,0,0,0,0,0,0,0,AU31,0,0,0,0,0,0,0,0,0,0,0,0,0,0)';
      PINUSE='POWER';
      NO_LOAD_CHECK='Both';
      NO_IO_CHECK='Both';
      NO_ASSERT_CHECK='TRUE';
      NO_DIR_CHECK='TRUE';
      ALLOW_CONNECT='TRUE';
    'VDDCR_SOC_AU35':
      PIN_NUMBER='(0,0,0,0,0,0,0,0,0,0,0,0,0,0,0,0,0,0,0,0,0,0,0,0,0,AU35,0,0,0,0,0,0,0,0,0,0,0,0,0,0)';
      PINUSE='POWER';
      NO_LOAD_CHECK='Both';
      NO_IO_CHECK='Both';
      NO_ASSERT_CHECK='TRUE';
      NO_DIR_CHECK='TRUE';
      ALLOW_CONNECT='TRUE';
    'VDDCR_SOC_AU40':
      PIN_NUMBER='(0,0,0,0,0,0,0,0,0,0,0,0,0,0,0,0,0,0,0,0,0,0,0,0,0,AU40,0,0,0,0,0,0,0,0,0,0,0,0,0,0)';
      PINUSE='POWER';
      NO_LOAD_CHECK='Both';
      NO_IO_CHECK='Both';
      NO_ASSERT_CHECK='TRUE';
      NO_DIR_CHECK='TRUE';
      ALLOW_CONNECT='TRUE';
    'VDDCR_SOC_AV5':
      PIN_NUMBER='(0,0,0,0,0,0,0,0,0,0,0,0,0,0,0,0,0,0,0,0,0,0,0,0,0,AV5,0,0,0,0,0,0,0,0,0,0,0,0,0,0)';
      PINUSE='POWER';
      NO_LOAD_CHECK='Both';
      NO_IO_CHECK='Both';
      NO_ASSERT_CHECK='TRUE';
      NO_DIR_CHECK='TRUE';
      ALLOW_CONNECT='TRUE';
    'VDDCR_SOC_AV12':
      PIN_NUMBER='(0,0,0,0,0,0,0,0,0,0,0,0,0,0,0,0,0,0,0,0,0,0,0,0,0,AV12,0,0,0,0,0,0,0,0,0,0,0,0,0,0)';
      PINUSE='POWER';
      NO_LOAD_CHECK='Both';
      NO_IO_CHECK='Both';
      NO_ASSERT_CHECK='TRUE';
      NO_DIR_CHECK='TRUE';
      ALLOW_CONNECT='TRUE';
    'VDDCR_SOC_AV19':
      PIN_NUMBER='(0,0,0,0,0,0,0,0,0,0,0,0,0,0,0,0,0,0,0,0,0,0,0,0,0,AV19,0,0,0,0,0,0,0,0,0,0,0,0,0,0)';
      PINUSE='POWER';
      NO_LOAD_CHECK='Both';
      NO_IO_CHECK='Both';
      NO_ASSERT_CHECK='TRUE';
      NO_DIR_CHECK='TRUE';
      ALLOW_CONNECT='TRUE';
    'VDDCR_SOC_AV22':
      PIN_NUMBER='(0,0,0,0,0,0,0,0,0,0,0,0,0,0,0,0,0,0,0,0,0,0,0,0,0,AV22,0,0,0,0,0,0,0,0,0,0,0,0,0,0)';
      PINUSE='POWER';
      NO_LOAD_CHECK='Both';
      NO_IO_CHECK='Both';
      NO_ASSERT_CHECK='TRUE';
      NO_DIR_CHECK='TRUE';
      ALLOW_CONNECT='TRUE';
    'VDDCR_SOC_AV24':
      PIN_NUMBER='(0,0,0,0,0,0,0,0,0,0,0,0,0,0,0,0,0,0,0,0,0,0,0,0,0,AV24,0,0,0,0,0,0,0,0,0,0,0,0,0,0)';
      PINUSE='POWER';
      NO_LOAD_CHECK='Both';
      NO_IO_CHECK='Both';
      NO_ASSERT_CHECK='TRUE';
      NO_DIR_CHECK='TRUE';
      ALLOW_CONNECT='TRUE';
    'VDDCR_SOC_AV26':
      PIN_NUMBER='(0,0,0,0,0,0,0,0,0,0,0,0,0,0,0,0,0,0,0,0,0,0,0,0,0,AV26,0,0,0,0,0,0,0,0,0,0,0,0,0,0)';
      PINUSE='POWER';
      NO_LOAD_CHECK='Both';
      NO_IO_CHECK='Both';
      NO_ASSERT_CHECK='TRUE';
      NO_DIR_CHECK='TRUE';
      ALLOW_CONNECT='TRUE';
    'VDDCR_SOC_AV28':
      PIN_NUMBER='(0,0,0,0,0,0,0,0,0,0,0,0,0,0,0,0,0,0,0,0,0,0,0,0,0,AV28,0,0,0,0,0,0,0,0,0,0,0,0,0,0)';
      PINUSE='POWER';
      NO_LOAD_CHECK='Both';
      NO_IO_CHECK='Both';
      NO_ASSERT_CHECK='TRUE';
      NO_DIR_CHECK='TRUE';
      ALLOW_CONNECT='TRUE';
    'VDDCR_SOC_AV30':
      PIN_NUMBER='(0,0,0,0,0,0,0,0,0,0,0,0,0,0,0,0,0,0,0,0,0,0,0,0,0,AV30,0,0,0,0,0,0,0,0,0,0,0,0,0,0)';
      PINUSE='POWER';
      NO_LOAD_CHECK='Both';
      NO_IO_CHECK='Both';
      NO_ASSERT_CHECK='TRUE';
      NO_DIR_CHECK='TRUE';
      ALLOW_CONNECT='TRUE';
    'VDDCR_SOC_AV32':
      PIN_NUMBER='(0,0,0,0,0,0,0,0,0,0,0,0,0,0,0,0,0,0,0,0,0,0,0,0,0,AV32,0,0,0,0,0,0,0,0,0,0,0,0,0,0)';
      PINUSE='POWER';
      NO_LOAD_CHECK='Both';
      NO_IO_CHECK='Both';
      NO_ASSERT_CHECK='TRUE';
      NO_DIR_CHECK='TRUE';
      ALLOW_CONNECT='TRUE';
    'VDDCR_SOC_AV34':
      PIN_NUMBER='(0,0,0,0,0,0,0,0,0,0,0,0,0,0,0,0,0,0,0,0,0,0,0,0,0,AV34,0,0,0,0,0,0,0,0,0,0,0,0,0,0)';
      PINUSE='POWER';
      NO_LOAD_CHECK='Both';
      NO_IO_CHECK='Both';
      NO_ASSERT_CHECK='TRUE';
      NO_DIR_CHECK='TRUE';
      ALLOW_CONNECT='TRUE';
    'VDDCR_SOC_AV36':
      PIN_NUMBER='(0,0,0,0,0,0,0,0,0,0,0,0,0,0,0,0,0,0,0,0,0,0,0,0,0,AV36,0,0,0,0,0,0,0,0,0,0,0,0,0,0)';
      PINUSE='POWER';
      NO_LOAD_CHECK='Both';
      NO_IO_CHECK='Both';
      NO_ASSERT_CHECK='TRUE';
      NO_DIR_CHECK='TRUE';
      ALLOW_CONNECT='TRUE';
    'VDDCR_SOC_AV39':
      PIN_NUMBER='(0,0,0,0,0,0,0,0,0,0,0,0,0,0,0,0,0,0,0,0,0,0,0,0,0,AV39,0,0,0,0,0,0,0,0,0,0,0,0,0,0)';
      PINUSE='POWER';
      NO_LOAD_CHECK='Both';
      NO_IO_CHECK='Both';
      NO_ASSERT_CHECK='TRUE';
      NO_DIR_CHECK='TRUE';
      ALLOW_CONNECT='TRUE';
    'VDDCR_SOC_AV41':
      PIN_NUMBER='(0,0,0,0,0,0,0,0,0,0,0,0,0,0,0,0,0,0,0,0,0,0,0,0,0,AV41,0,0,0,0,0,0,0,0,0,0,0,0,0,0)';
      PINUSE='POWER';
      NO_LOAD_CHECK='Both';
      NO_IO_CHECK='Both';
      NO_ASSERT_CHECK='TRUE';
      NO_DIR_CHECK='TRUE';
      ALLOW_CONNECT='TRUE';
    'VDDCR_SOC_AV43':
      PIN_NUMBER='(0,0,0,0,0,0,0,0,0,0,0,0,0,0,0,0,0,0,0,0,0,0,0,0,0,AV43,0,0,0,0,0,0,0,0,0,0,0,0,0,0)';
      PINUSE='POWER';
      NO_LOAD_CHECK='Both';
      NO_IO_CHECK='Both';
      NO_ASSERT_CHECK='TRUE';
      NO_DIR_CHECK='TRUE';
      ALLOW_CONNECT='TRUE';
    'VDDCR_SOC_AV45':
      PIN_NUMBER='(0,0,0,0,0,0,0,0,0,0,0,0,0,0,0,0,0,0,0,0,0,0,0,0,0,AV45,0,0,0,0,0,0,0,0,0,0,0,0,0,0)';
      PINUSE='POWER';
      NO_LOAD_CHECK='Both';
      NO_IO_CHECK='Both';
      NO_ASSERT_CHECK='TRUE';
      NO_DIR_CHECK='TRUE';
      ALLOW_CONNECT='TRUE';
    'VDDCR_SOC_AV47':
      PIN_NUMBER='(0,0,0,0,0,0,0,0,0,0,0,0,0,0,0,0,0,0,0,0,0,0,0,0,0,AV47,0,0,0,0,0,0,0,0,0,0,0,0,0,0)';
      PINUSE='POWER';
      NO_LOAD_CHECK='Both';
      NO_IO_CHECK='Both';
      NO_ASSERT_CHECK='TRUE';
      NO_DIR_CHECK='TRUE';
      ALLOW_CONNECT='TRUE';
    'VDDCR_SOC_AW23':
      PIN_NUMBER='(0,0,0,0,0,0,0,0,0,0,0,0,0,0,0,0,0,0,0,0,0,0,0,0,0,AW23,0,0,0,0,0,0,0,0,0,0,0,0,0,0)';
      PINUSE='POWER';
      NO_LOAD_CHECK='Both';
      NO_IO_CHECK='Both';
      NO_ASSERT_CHECK='TRUE';
      NO_DIR_CHECK='TRUE';
      ALLOW_CONNECT='TRUE';
    'VDDCR_SOC_AW25':
      PIN_NUMBER='(0,0,0,0,0,0,0,0,0,0,0,0,0,0,0,0,0,0,0,0,0,0,0,0,0,AW25,0,0,0,0,0,0,0,0,0,0,0,0,0,0)';
      PINUSE='POWER';
      NO_LOAD_CHECK='Both';
      NO_IO_CHECK='Both';
      NO_ASSERT_CHECK='TRUE';
      NO_DIR_CHECK='TRUE';
      ALLOW_CONNECT='TRUE';
    'VDDCR_SOC_AW27':
      PIN_NUMBER='(0,0,0,0,0,0,0,0,0,0,0,0,0,0,0,0,0,0,0,0,0,0,0,0,0,AW27,0,0,0,0,0,0,0,0,0,0,0,0,0,0)';
      PINUSE='POWER';
      NO_LOAD_CHECK='Both';
      NO_IO_CHECK='Both';
      NO_ASSERT_CHECK='TRUE';
      NO_DIR_CHECK='TRUE';
      ALLOW_CONNECT='TRUE';
    'VDDCR_SOC_AW48':
      PIN_NUMBER='(0,0,0,0,0,0,0,0,0,0,0,0,0,0,0,0,0,0,0,0,0,0,0,0,0,AW48,0,0,0,0,0,0,0,0,0,0,0,0,0,0)';
      PINUSE='POWER';
      NO_LOAD_CHECK='Both';
      NO_IO_CHECK='Both';
      NO_ASSERT_CHECK='TRUE';
      NO_DIR_CHECK='TRUE';
      ALLOW_CONNECT='TRUE';
    'VDDCR_SOC_AY22':
      PIN_NUMBER='(0,0,0,0,0,0,0,0,0,0,0,0,0,0,0,0,0,0,0,0,0,0,0,0,0,AY22,0,0,0,0,0,0,0,0,0,0,0,0,0,0)';
      PINUSE='POWER';
      NO_LOAD_CHECK='Both';
      NO_IO_CHECK='Both';
      NO_ASSERT_CHECK='TRUE';
      NO_DIR_CHECK='TRUE';
      ALLOW_CONNECT='TRUE';
    'VDDCR_SOC_AY24':
      PIN_NUMBER='(0,0,0,0,0,0,0,0,0,0,0,0,0,0,0,0,0,0,0,0,0,0,0,0,0,AY24,0,0,0,0,0,0,0,0,0,0,0,0,0,0)';
      PINUSE='POWER';
      NO_LOAD_CHECK='Both';
      NO_IO_CHECK='Both';
      NO_ASSERT_CHECK='TRUE';
      NO_DIR_CHECK='TRUE';
      ALLOW_CONNECT='TRUE';
    'VDDCR_SOC_AY26':
      PIN_NUMBER='(0,0,0,0,0,0,0,0,0,0,0,0,0,0,0,0,0,0,0,0,0,0,0,0,0,AY26,0,0,0,0,0,0,0,0,0,0,0,0,0,0)';
      PINUSE='POWER';
      NO_LOAD_CHECK='Both';
      NO_IO_CHECK='Both';
      NO_ASSERT_CHECK='TRUE';
      NO_DIR_CHECK='TRUE';
      ALLOW_CONNECT='TRUE';
    'VDDCR_SOC_AY28':
      PIN_NUMBER='(0,0,0,0,0,0,0,0,0,0,0,0,0,0,0,0,0,0,0,0,0,0,0,0,0,AY28,0,0,0,0,0,0,0,0,0,0,0,0,0,0)';
      PINUSE='POWER';
      NO_LOAD_CHECK='Both';
      NO_IO_CHECK='Both';
      NO_ASSERT_CHECK='TRUE';
      NO_DIR_CHECK='TRUE';
      ALLOW_CONNECT='TRUE';
    'VDDCR_SOC_AY49':
      PIN_NUMBER='(0,0,0,0,0,0,0,0,0,0,0,0,0,0,0,0,0,0,0,0,0,0,0,0,0,AY49,0,0,0,0,0,0,0,0,0,0,0,0,0,0)';
      PINUSE='POWER';
      NO_LOAD_CHECK='Both';
      NO_IO_CHECK='Both';
      NO_ASSERT_CHECK='TRUE';
      NO_DIR_CHECK='TRUE';
      ALLOW_CONNECT='TRUE';
    'VDDCR_SOC_BA4':
      PIN_NUMBER='(0,0,0,0,0,0,0,0,0,0,0,0,0,0,0,0,0,0,0,0,0,0,0,0,0,BA4,0,0,0,0,0,0,0,0,0,0,0,0,0,0)';
      PINUSE='POWER';
      NO_LOAD_CHECK='Both';
      NO_IO_CHECK='Both';
      NO_ASSERT_CHECK='TRUE';
      NO_DIR_CHECK='TRUE';
      ALLOW_CONNECT='TRUE';
    'VDDCR_SOC_BA11':
      PIN_NUMBER='(0,0,0,0,0,0,0,0,0,0,0,0,0,0,0,0,0,0,0,0,0,0,0,0,0,BA11,0,0,0,0,0,0,0,0,0,0,0,0,0,0)';
      PINUSE='POWER';
      NO_LOAD_CHECK='Both';
      NO_IO_CHECK='Both';
      NO_ASSERT_CHECK='TRUE';
      NO_DIR_CHECK='TRUE';
      ALLOW_CONNECT='TRUE';
    'VDDCR_SOC_BA18':
      PIN_NUMBER='(0,0,0,0,0,0,0,0,0,0,0,0,0,0,0,0,0,0,0,0,0,0,0,0,0,BA18,0,0,0,0,0,0,0,0,0,0,0,0,0,0)';
      PINUSE='POWER';
      NO_LOAD_CHECK='Both';
      NO_IO_CHECK='Both';
      NO_ASSERT_CHECK='TRUE';
      NO_DIR_CHECK='TRUE';
      ALLOW_CONNECT='TRUE';
    'VDDCR_SOC_BA23':
      PIN_NUMBER='(0,0,0,0,0,0,0,0,0,0,0,0,0,0,0,0,0,0,0,0,0,0,0,0,0,BA23,0,0,0,0,0,0,0,0,0,0,0,0,0,0)';
      PINUSE='POWER';
      NO_LOAD_CHECK='Both';
      NO_IO_CHECK='Both';
      NO_ASSERT_CHECK='TRUE';
      NO_DIR_CHECK='TRUE';
      ALLOW_CONNECT='TRUE';
    'VDDCR_SOC_BA25':
      PIN_NUMBER='(0,0,0,0,0,0,0,0,0,0,0,0,0,0,0,0,0,0,0,0,0,0,0,0,0,BA25,0,0,0,0,0,0,0,0,0,0,0,0,0,0)';
      PINUSE='POWER';
      NO_LOAD_CHECK='Both';
      NO_IO_CHECK='Both';
      NO_ASSERT_CHECK='TRUE';
      NO_DIR_CHECK='TRUE';
      ALLOW_CONNECT='TRUE';
    'VDDCR_SOC_BA27':
      PIN_NUMBER='(0,0,0,0,0,0,0,0,0,0,0,0,0,0,0,0,0,0,0,0,0,0,0,0,0,BA27,0,0,0,0,0,0,0,0,0,0,0,0,0,0)';
      PINUSE='POWER';
      NO_LOAD_CHECK='Both';
      NO_IO_CHECK='Both';
      NO_ASSERT_CHECK='TRUE';
      NO_DIR_CHECK='TRUE';
      ALLOW_CONNECT='TRUE';
    'VDDCR_SOC_BA48':
      PIN_NUMBER='(0,0,0,0,0,0,0,0,0,0,0,0,0,0,0,0,0,0,0,0,0,0,0,0,0,BA48,0,0,0,0,0,0,0,0,0,0,0,0,0,0)';
      PINUSE='POWER';
      NO_LOAD_CHECK='Both';
      NO_IO_CHECK='Both';
      NO_ASSERT_CHECK='TRUE';
      NO_DIR_CHECK='TRUE';
      ALLOW_CONNECT='TRUE';
    'VDDCR_SOC_BB22':
      PIN_NUMBER='(0,0,0,0,0,0,0,0,0,0,0,0,0,0,0,0,0,0,0,0,0,0,0,0,0,BB22,0,0,0,0,0,0,0,0,0,0,0,0,0,0)';
      PINUSE='POWER';
      NO_LOAD_CHECK='Both';
      NO_IO_CHECK='Both';
      NO_ASSERT_CHECK='TRUE';
      NO_DIR_CHECK='TRUE';
      ALLOW_CONNECT='TRUE';
    'VDDCR_SOC_BB24':
      PIN_NUMBER='(0,0,0,0,0,0,0,0,0,0,0,0,0,0,0,0,0,0,0,0,0,0,0,0,0,BB24,0,0,0,0,0,0,0,0,0,0,0,0,0,0)';
      PINUSE='POWER';
      NO_LOAD_CHECK='Both';
      NO_IO_CHECK='Both';
      NO_ASSERT_CHECK='TRUE';
      NO_DIR_CHECK='TRUE';
      ALLOW_CONNECT='TRUE';
    'VDDCR_SOC_BB26':
      PIN_NUMBER='(0,0,0,0,0,0,0,0,0,0,0,0,0,0,0,0,0,0,0,0,0,0,0,0,0,BB26,0,0,0,0,0,0,0,0,0,0,0,0,0,0)';
      PINUSE='POWER';
      NO_LOAD_CHECK='Both';
      NO_IO_CHECK='Both';
      NO_ASSERT_CHECK='TRUE';
      NO_DIR_CHECK='TRUE';
      ALLOW_CONNECT='TRUE';
    'VDDCR_SOC_BB28':
      PIN_NUMBER='(0,0,0,0,0,0,0,0,0,0,0,0,0,0,0,0,0,0,0,0,0,0,0,0,0,BB28,0,0,0,0,0,0,0,0,0,0,0,0,0,0)';
      PINUSE='POWER';
      NO_LOAD_CHECK='Both';
      NO_IO_CHECK='Both';
      NO_ASSERT_CHECK='TRUE';
      NO_DIR_CHECK='TRUE';
      ALLOW_CONNECT='TRUE';
    'VDDCR_SOC_BB49':
      PIN_NUMBER='(0,0,0,0,0,0,0,0,0,0,0,0,0,0,0,0,0,0,0,0,0,0,0,0,0,BB49,0,0,0,0,0,0,0,0,0,0,0,0,0,0)';
      PINUSE='POWER';
      NO_LOAD_CHECK='Both';
      NO_IO_CHECK='Both';
      NO_ASSERT_CHECK='TRUE';
      NO_DIR_CHECK='TRUE';
      ALLOW_CONNECT='TRUE';
    'VDDCR_SOC_BC23':
      PIN_NUMBER='(0,0,0,0,0,0,0,0,0,0,0,0,0,0,0,0,0,0,0,0,0,0,0,0,0,BC23,0,0,0,0,0,0,0,0,0,0,0,0,0,0)';
      PINUSE='POWER';
      NO_LOAD_CHECK='Both';
      NO_IO_CHECK='Both';
      NO_ASSERT_CHECK='TRUE';
      NO_DIR_CHECK='TRUE';
      ALLOW_CONNECT='TRUE';
    'VDDCR_SOC_BC25':
      PIN_NUMBER='(0,0,0,0,0,0,0,0,0,0,0,0,0,0,0,0,0,0,0,0,0,0,0,0,0,BC25,0,0,0,0,0,0,0,0,0,0,0,0,0,0)';
      PINUSE='POWER';
      NO_LOAD_CHECK='Both';
      NO_IO_CHECK='Both';
      NO_ASSERT_CHECK='TRUE';
      NO_DIR_CHECK='TRUE';
      ALLOW_CONNECT='TRUE';
    'VDDCR_SOC_BC27':
      PIN_NUMBER='(0,0,0,0,0,0,0,0,0,0,0,0,0,0,0,0,0,0,0,0,0,0,0,0,0,BC27,0,0,0,0,0,0,0,0,0,0,0,0,0,0)';
      PINUSE='POWER';
      NO_LOAD_CHECK='Both';
      NO_IO_CHECK='Both';
      NO_ASSERT_CHECK='TRUE';
      NO_DIR_CHECK='TRUE';
      ALLOW_CONNECT='TRUE';
    'VDDCR_SOC_BC48':
      PIN_NUMBER='(0,0,0,0,0,0,0,0,0,0,0,0,0,0,0,0,0,0,0,0,0,0,0,0,0,BC48,0,0,0,0,0,0,0,0,0,0,0,0,0,0)';
      PINUSE='POWER';
      NO_LOAD_CHECK='Both';
      NO_IO_CHECK='Both';
      NO_ASSERT_CHECK='TRUE';
      NO_DIR_CHECK='TRUE';
      ALLOW_CONNECT='TRUE';
    'VDDCR_SOC_BD5':
      PIN_NUMBER='(0,0,0,0,0,0,0,0,0,0,0,0,0,0,0,0,0,0,0,0,0,0,0,0,0,BD5,0,0,0,0,0,0,0,0,0,0,0,0,0,0)';
      PINUSE='POWER';
      NO_LOAD_CHECK='Both';
      NO_IO_CHECK='Both';
      NO_ASSERT_CHECK='TRUE';
      NO_DIR_CHECK='TRUE';
      ALLOW_CONNECT='TRUE';
    'VDDCR_SOC_BD12':
      PIN_NUMBER='(0,0,0,0,0,0,0,0,0,0,0,0,0,0,0,0,0,0,0,0,0,0,0,0,0,BD12,0,0,0,0,0,0,0,0,0,0,0,0,0,0)';
      PINUSE='POWER';
      NO_LOAD_CHECK='Both';
      NO_IO_CHECK='Both';
      NO_ASSERT_CHECK='TRUE';
      NO_DIR_CHECK='TRUE';
      ALLOW_CONNECT='TRUE';
    'VDDCR_SOC_BD19':
      PIN_NUMBER='(0,0,0,0,0,0,0,0,0,0,0,0,0,0,0,0,0,0,0,0,0,0,0,0,0,BD19,0,0,0,0,0,0,0,0,0,0,0,0,0,0)';
      PINUSE='POWER';
      NO_LOAD_CHECK='Both';
      NO_IO_CHECK='Both';
      NO_ASSERT_CHECK='TRUE';
      NO_DIR_CHECK='TRUE';
      ALLOW_CONNECT='TRUE';
    'VDDCR_SOC_BD22':
      PIN_NUMBER='(0,0,0,0,0,0,0,0,0,0,0,0,0,0,0,0,0,0,0,0,0,0,0,0,0,BD22,0,0,0,0,0,0,0,0,0,0,0,0,0,0)';
      PINUSE='POWER';
      NO_LOAD_CHECK='Both';
      NO_IO_CHECK='Both';
      NO_ASSERT_CHECK='TRUE';
      NO_DIR_CHECK='TRUE';
      ALLOW_CONNECT='TRUE';
    'VDDCR_SOC_BD24':
      PIN_NUMBER='(0,0,0,0,0,0,0,0,0,0,0,0,0,0,0,0,0,0,0,0,0,0,0,0,0,BD24,0,0,0,0,0,0,0,0,0,0,0,0,0,0)';
      PINUSE='POWER';
      NO_LOAD_CHECK='Both';
      NO_IO_CHECK='Both';
      NO_ASSERT_CHECK='TRUE';
      NO_DIR_CHECK='TRUE';
      ALLOW_CONNECT='TRUE';
    'VDDCR_SOC_BD26':
      PIN_NUMBER='(0,0,0,0,0,0,0,0,0,0,0,0,0,0,0,0,0,0,0,0,0,0,0,0,0,BD26,0,0,0,0,0,0,0,0,0,0,0,0,0,0)';
      PINUSE='POWER';
      NO_LOAD_CHECK='Both';
      NO_IO_CHECK='Both';
      NO_ASSERT_CHECK='TRUE';
      NO_DIR_CHECK='TRUE';
      ALLOW_CONNECT='TRUE';
    'VDDCR_SOC_BD28':
      PIN_NUMBER='(0,0,0,0,0,0,0,0,0,0,0,0,0,0,0,0,0,0,0,0,0,0,0,0,0,BD28,0,0,0,0,0,0,0,0,0,0,0,0,0,0)';
      PINUSE='POWER';
      NO_LOAD_CHECK='Both';
      NO_IO_CHECK='Both';
      NO_ASSERT_CHECK='TRUE';
      NO_DIR_CHECK='TRUE';
      ALLOW_CONNECT='TRUE';
    'VDDCR_SOC_BD48':
      PIN_NUMBER='(0,0,0,0,0,0,0,0,0,0,0,0,0,0,0,0,0,0,0,0,0,0,0,0,0,BD48,0,0,0,0,0,0,0,0,0,0,0,0,0,0)';
      PINUSE='POWER';
      NO_LOAD_CHECK='Both';
      NO_IO_CHECK='Both';
      NO_ASSERT_CHECK='TRUE';
      NO_DIR_CHECK='TRUE';
      ALLOW_CONNECT='TRUE';
    'VDDCR_SOC_BF23':
      PIN_NUMBER='(0,0,0,0,0,0,0,0,0,0,0,0,0,0,0,0,0,0,0,0,0,0,0,0,0,BF23,0,0,0,0,0,0,0,0,0,0,0,0,0,0)';
      PINUSE='POWER';
      NO_LOAD_CHECK='Both';
      NO_IO_CHECK='Both';
      NO_ASSERT_CHECK='TRUE';
      NO_DIR_CHECK='TRUE';
      ALLOW_CONNECT='TRUE';
    'VDDCR_SOC_BF25':
      PIN_NUMBER='(0,0,0,0,0,0,0,0,0,0,0,0,0,0,0,0,0,0,0,0,0,0,0,0,0,BF25,0,0,0,0,0,0,0,0,0,0,0,0,0,0)';
      PINUSE='POWER';
      NO_LOAD_CHECK='Both';
      NO_IO_CHECK='Both';
      NO_ASSERT_CHECK='TRUE';
      NO_DIR_CHECK='TRUE';
      ALLOW_CONNECT='TRUE';
    'VDDCR_SOC_BF27':
      PIN_NUMBER='(0,0,0,0,0,0,0,0,0,0,0,0,0,0,0,0,0,0,0,0,0,0,0,0,0,BF27,0,0,0,0,0,0,0,0,0,0,0,0,0,0)';
      PINUSE='POWER';
      NO_LOAD_CHECK='Both';
      NO_IO_CHECK='Both';
      NO_ASSERT_CHECK='TRUE';
      NO_DIR_CHECK='TRUE';
      ALLOW_CONNECT='TRUE';
    'VDDCR_SOC_BF48':
      PIN_NUMBER='(0,0,0,0,0,0,0,0,0,0,0,0,0,0,0,0,0,0,0,0,0,0,0,0,0,BF48,0,0,0,0,0,0,0,0,0,0,0,0,0,0)';
      PINUSE='POWER';
      NO_LOAD_CHECK='Both';
      NO_IO_CHECK='Both';
      NO_ASSERT_CHECK='TRUE';
      NO_DIR_CHECK='TRUE';
      ALLOW_CONNECT='TRUE';
    'VDDCR_SOC_BM5':
      PIN_NUMBER='(0,0,0,0,0,0,0,0,0,0,0,0,0,0,0,0,0,0,0,0,0,0,0,0,0,BM5,0,0,0,0,0,0,0,0,0,0,0,0,0,0)';
      PINUSE='POWER';
      NO_LOAD_CHECK='Both';
      NO_IO_CHECK='Both';
      NO_ASSERT_CHECK='TRUE';
      NO_DIR_CHECK='TRUE';
      ALLOW_CONNECT='TRUE';
    'VDDCR_SOC_BJ48':
      PIN_NUMBER='(0,0,0,0,0,0,0,0,0,0,0,0,0,0,0,0,0,0,0,0,0,0,0,0,0,BJ48,0,0,0,0,0,0,0,0,0,0,0,0,0,0)';
      PINUSE='POWER';
      NO_LOAD_CHECK='Both';
      NO_IO_CHECK='Both';
      NO_ASSERT_CHECK='TRUE';
      NO_DIR_CHECK='TRUE';
      ALLOW_CONNECT='TRUE';
    'VDDCR_SOC_BJ11':
      PIN_NUMBER='(0,0,0,0,0,0,0,0,0,0,0,0,0,0,0,0,0,0,0,0,0,0,0,0,0,BJ11,0,0,0,0,0,0,0,0,0,0,0,0,0,0)';
      PINUSE='POWER';
      NO_LOAD_CHECK='Both';
      NO_IO_CHECK='Both';
      NO_ASSERT_CHECK='TRUE';
      NO_DIR_CHECK='TRUE';
      ALLOW_CONNECT='TRUE';
    'VDDCR_SOC_BJ4':
      PIN_NUMBER='(0,0,0,0,0,0,0,0,0,0,0,0,0,0,0,0,0,0,0,0,0,0,0,0,0,BJ4,0,0,0,0,0,0,0,0,0,0,0,0,0,0)';
      PINUSE='POWER';
      NO_LOAD_CHECK='Both';
      NO_IO_CHECK='Both';
      NO_ASSERT_CHECK='TRUE';
      NO_DIR_CHECK='TRUE';
      ALLOW_CONNECT='TRUE';
    'VDDCR_SOC_BH48':
      PIN_NUMBER='(0,0,0,0,0,0,0,0,0,0,0,0,0,0,0,0,0,0,0,0,0,0,0,0,0,BH48,0,0,0,0,0,0,0,0,0,0,0,0,0,0)';
      PINUSE='POWER';
      NO_LOAD_CHECK='Both';
      NO_IO_CHECK='Both';
      NO_ASSERT_CHECK='TRUE';
      NO_DIR_CHECK='TRUE';
      ALLOW_CONNECT='TRUE';
    'VDDCR_SOC_BH25':
      PIN_NUMBER='(0,0,0,0,0,0,0,0,0,0,0,0,0,0,0,0,0,0,0,0,0,0,0,0,0,BH25,0,0,0,0,0,0,0,0,0,0,0,0,0,0)';
      PINUSE='POWER';
      NO_LOAD_CHECK='Both';
      NO_IO_CHECK='Both';
      NO_ASSERT_CHECK='TRUE';
      NO_DIR_CHECK='TRUE';
      ALLOW_CONNECT='TRUE';
    'VDDCR_SOC_BH23':
      PIN_NUMBER='(0,0,0,0,0,0,0,0,0,0,0,0,0,0,0,0,0,0,0,0,0,0,0,0,0,BH23,0,0,0,0,0,0,0,0,0,0,0,0,0,0)';
      PINUSE='POWER';
      NO_LOAD_CHECK='Both';
      NO_IO_CHECK='Both';
      NO_ASSERT_CHECK='TRUE';
      NO_DIR_CHECK='TRUE';
      ALLOW_CONNECT='TRUE';
    'VDDCR_SOC_BG48':
      PIN_NUMBER='(0,0,0,0,0,0,0,0,0,0,0,0,0,0,0,0,0,0,0,0,0,0,0,0,0,BG48,0,0,0,0,0,0,0,0,0,0,0,0,0,0)';
      PINUSE='POWER';
      NO_LOAD_CHECK='Both';
      NO_IO_CHECK='Both';
      NO_ASSERT_CHECK='TRUE';
      NO_DIR_CHECK='TRUE';
      ALLOW_CONNECT='TRUE';
    'VDDCR_SOC_BG28':
      PIN_NUMBER='(0,0,0,0,0,0,0,0,0,0,0,0,0,0,0,0,0,0,0,0,0,0,0,0,0,BG28,0,0,0,0,0,0,0,0,0,0,0,0,0,0)';
      PINUSE='POWER';
      NO_LOAD_CHECK='Both';
      NO_IO_CHECK='Both';
      NO_ASSERT_CHECK='TRUE';
      NO_DIR_CHECK='TRUE';
      ALLOW_CONNECT='TRUE';
    'VDDCR_SOC_BG26':
      PIN_NUMBER='(0,0,0,0,0,0,0,0,0,0,0,0,0,0,0,0,0,0,0,0,0,0,0,0,0,BG26,0,0,0,0,0,0,0,0,0,0,0,0,0,0)';
      PINUSE='POWER';
      NO_LOAD_CHECK='Both';
      NO_IO_CHECK='Both';
      NO_ASSERT_CHECK='TRUE';
      NO_DIR_CHECK='TRUE';
      ALLOW_CONNECT='TRUE';
    'VDDCR_SOC_BG24':
      PIN_NUMBER='(0,0,0,0,0,0,0,0,0,0,0,0,0,0,0,0,0,0,0,0,0,0,0,0,0,BG24,0,0,0,0,0,0,0,0,0,0,0,0,0,0)';
      PINUSE='POWER';
      NO_LOAD_CHECK='Both';
      NO_IO_CHECK='Both';
      NO_ASSERT_CHECK='TRUE';
      NO_DIR_CHECK='TRUE';
      ALLOW_CONNECT='TRUE';
    'VDDCR_SOC_BG22':
      PIN_NUMBER='(0,0,0,0,0,0,0,0,0,0,0,0,0,0,0,0,0,0,0,0,0,0,0,0,0,BG22,0,0,0,0,0,0,0,0,0,0,0,0,0,0)';
      PINUSE='POWER';
      NO_LOAD_CHECK='Both';
      NO_IO_CHECK='Both';
      NO_ASSERT_CHECK='TRUE';
      NO_DIR_CHECK='TRUE';
      ALLOW_CONNECT='TRUE';
    'VDDIO_H57':
      PIN_NUMBER='(0,0,0,0,0,0,0,0,0,0,0,0,0,0,0,0,0,0,0,0,0,0,0,0,0,0,H57,0,0,0,0,0,0,0,0,0,0,0,0,0)';
      PINUSE='POWER';
      NO_LOAD_CHECK='Both';
      NO_IO_CHECK='Both';
      NO_ASSERT_CHECK='TRUE';
      NO_DIR_CHECK='TRUE';
      ALLOW_CONNECT='TRUE';
    'VDDIO_H64':
      PIN_NUMBER='(0,0,0,0,0,0,0,0,0,0,0,0,0,0,0,0,0,0,0,0,0,0,0,0,0,0,H64,0,0,0,0,0,0,0,0,0,0,0,0,0)';
      PINUSE='POWER';
      NO_LOAD_CHECK='Both';
      NO_IO_CHECK='Both';
      NO_ASSERT_CHECK='TRUE';
      NO_DIR_CHECK='TRUE';
      ALLOW_CONNECT='TRUE';
    'VDDIO_H71':
      PIN_NUMBER='(0,0,0,0,0,0,0,0,0,0,0,0,0,0,0,0,0,0,0,0,0,0,0,0,0,0,H71,0,0,0,0,0,0,0,0,0,0,0,0,0)';
      PINUSE='POWER';
      NO_LOAD_CHECK='Both';
      NO_IO_CHECK='Both';
      NO_ASSERT_CHECK='TRUE';
      NO_DIR_CHECK='TRUE';
      ALLOW_CONNECT='TRUE';
    'VDDIO_K54':
      PIN_NUMBER='(0,0,0,0,0,0,0,0,0,0,0,0,0,0,0,0,0,0,0,0,0,0,0,0,0,0,K54,0,0,0,0,0,0,0,0,0,0,0,0,0)';
      PINUSE='POWER';
      NO_LOAD_CHECK='Both';
      NO_IO_CHECK='Both';
      NO_ASSERT_CHECK='TRUE';
      NO_DIR_CHECK='TRUE';
      ALLOW_CONNECT='TRUE';
    'VDDIO_L58':
      PIN_NUMBER='(0,0,0,0,0,0,0,0,0,0,0,0,0,0,0,0,0,0,0,0,0,0,0,0,0,0,L58,0,0,0,0,0,0,0,0,0,0,0,0,0)';
      PINUSE='POWER';
      NO_LOAD_CHECK='Both';
      NO_IO_CHECK='Both';
      NO_ASSERT_CHECK='TRUE';
      NO_DIR_CHECK='TRUE';
      ALLOW_CONNECT='TRUE';
    'VDDIO_L65':
      PIN_NUMBER='(0,0,0,0,0,0,0,0,0,0,0,0,0,0,0,0,0,0,0,0,0,0,0,0,0,0,L65,0,0,0,0,0,0,0,0,0,0,0,0,0)';
      PINUSE='POWER';
      NO_LOAD_CHECK='Both';
      NO_IO_CHECK='Both';
      NO_ASSERT_CHECK='TRUE';
      NO_DIR_CHECK='TRUE';
      ALLOW_CONNECT='TRUE';
    'VDDIO_L72':
      PIN_NUMBER='(0,0,0,0,0,0,0,0,0,0,0,0,0,0,0,0,0,0,0,0,0,0,0,0,0,0,L72,0,0,0,0,0,0,0,0,0,0,0,0,0)';
      PINUSE='POWER';
      NO_LOAD_CHECK='Both';
      NO_IO_CHECK='Both';
      NO_ASSERT_CHECK='TRUE';
      NO_DIR_CHECK='TRUE';
      ALLOW_CONNECT='TRUE';
    'VDDIO_P54':
      PIN_NUMBER='(0,0,0,0,0,0,0,0,0,0,0,0,0,0,0,0,0,0,0,0,0,0,0,0,0,0,P54,0,0,0,0,0,0,0,0,0,0,0,0,0)';
      PINUSE='POWER';
      NO_LOAD_CHECK='Both';
      NO_IO_CHECK='Both';
      NO_ASSERT_CHECK='TRUE';
      NO_DIR_CHECK='TRUE';
      ALLOW_CONNECT='TRUE';
    'VDDIO_P57':
      PIN_NUMBER='(0,0,0,0,0,0,0,0,0,0,0,0,0,0,0,0,0,0,0,0,0,0,0,0,0,0,P57,0,0,0,0,0,0,0,0,0,0,0,0,0)';
      PINUSE='POWER';
      NO_LOAD_CHECK='Both';
      NO_IO_CHECK='Both';
      NO_ASSERT_CHECK='TRUE';
      NO_DIR_CHECK='TRUE';
      ALLOW_CONNECT='TRUE';
    'VDDIO_P64':
      PIN_NUMBER='(0,0,0,0,0,0,0,0,0,0,0,0,0,0,0,0,0,0,0,0,0,0,0,0,0,0,P64,0,0,0,0,0,0,0,0,0,0,0,0,0)';
      PINUSE='POWER';
      NO_LOAD_CHECK='Both';
      NO_IO_CHECK='Both';
      NO_ASSERT_CHECK='TRUE';
      NO_DIR_CHECK='TRUE';
      ALLOW_CONNECT='TRUE';
    'VDDIO_P71':
      PIN_NUMBER='(0,0,0,0,0,0,0,0,0,0,0,0,0,0,0,0,0,0,0,0,0,0,0,0,0,0,P71,0,0,0,0,0,0,0,0,0,0,0,0,0)';
      PINUSE='POWER';
      NO_LOAD_CHECK='Both';
      NO_IO_CHECK='Both';
      NO_ASSERT_CHECK='TRUE';
      NO_DIR_CHECK='TRUE';
      ALLOW_CONNECT='TRUE';
    'VDDIO_U58':
      PIN_NUMBER='(0,0,0,0,0,0,0,0,0,0,0,0,0,0,0,0,0,0,0,0,0,0,0,0,0,0,U58,0,0,0,0,0,0,0,0,0,0,0,0,0)';
      PINUSE='POWER';
      NO_LOAD_CHECK='Both';
      NO_IO_CHECK='Both';
      NO_ASSERT_CHECK='TRUE';
      NO_DIR_CHECK='TRUE';
      ALLOW_CONNECT='TRUE';
    'VDDIO_U65':
      PIN_NUMBER='(0,0,0,0,0,0,0,0,0,0,0,0,0,0,0,0,0,0,0,0,0,0,0,0,0,0,U65,0,0,0,0,0,0,0,0,0,0,0,0,0)';
      PINUSE='POWER';
      NO_LOAD_CHECK='Both';
      NO_IO_CHECK='Both';
      NO_ASSERT_CHECK='TRUE';
      NO_DIR_CHECK='TRUE';
      ALLOW_CONNECT='TRUE';
    'VDDIO_U72':
      PIN_NUMBER='(0,0,0,0,0,0,0,0,0,0,0,0,0,0,0,0,0,0,0,0,0,0,0,0,0,0,U72,0,0,0,0,0,0,0,0,0,0,0,0,0)';
      PINUSE='POWER';
      NO_LOAD_CHECK='Both';
      NO_IO_CHECK='Both';
      NO_ASSERT_CHECK='TRUE';
      NO_DIR_CHECK='TRUE';
      ALLOW_CONNECT='TRUE';
    'VDDIO_V54':
      PIN_NUMBER='(0,0,0,0,0,0,0,0,0,0,0,0,0,0,0,0,0,0,0,0,0,0,0,0,0,0,V54,0,0,0,0,0,0,0,0,0,0,0,0,0)';
      PINUSE='POWER';
      NO_LOAD_CHECK='Both';
      NO_IO_CHECK='Both';
      NO_ASSERT_CHECK='TRUE';
      NO_DIR_CHECK='TRUE';
      ALLOW_CONNECT='TRUE';
    'VDDIO_Y57':
      PIN_NUMBER='(0,0,0,0,0,0,0,0,0,0,0,0,0,0,0,0,0,0,0,0,0,0,0,0,0,0,Y57,0,0,0,0,0,0,0,0,0,0,0,0,0)';
      PINUSE='POWER';
      NO_LOAD_CHECK='Both';
      NO_IO_CHECK='Both';
      NO_ASSERT_CHECK='TRUE';
      NO_DIR_CHECK='TRUE';
      ALLOW_CONNECT='TRUE';
    'VDDIO_Y64':
      PIN_NUMBER='(0,0,0,0,0,0,0,0,0,0,0,0,0,0,0,0,0,0,0,0,0,0,0,0,0,0,Y64,0,0,0,0,0,0,0,0,0,0,0,0,0)';
      PINUSE='POWER';
      NO_LOAD_CHECK='Both';
      NO_IO_CHECK='Both';
      NO_ASSERT_CHECK='TRUE';
      NO_DIR_CHECK='TRUE';
      ALLOW_CONNECT='TRUE';
    'VDDIO_Y71':
      PIN_NUMBER='(0,0,0,0,0,0,0,0,0,0,0,0,0,0,0,0,0,0,0,0,0,0,0,0,0,0,Y71,0,0,0,0,0,0,0,0,0,0,0,0,0)';
      PINUSE='POWER';
      NO_LOAD_CHECK='Both';
      NO_IO_CHECK='Both';
      NO_ASSERT_CHECK='TRUE';
      NO_DIR_CHECK='TRUE';
      ALLOW_CONNECT='TRUE';
    'VDDIO_AA54':
      PIN_NUMBER='(0,0,0,0,0,0,0,0,0,0,0,0,0,0,0,0,0,0,0,0,0,0,0,0,0,0,AA54,0,0,0,0,0,0,0,0,0,0,0,0,0)';
      PINUSE='POWER';
      NO_LOAD_CHECK='Both';
      NO_IO_CHECK='Both';
      NO_ASSERT_CHECK='TRUE';
      NO_DIR_CHECK='TRUE';
      ALLOW_CONNECT='TRUE';
    'VDDIO_AC58':
      PIN_NUMBER='(0,0,0,0,0,0,0,0,0,0,0,0,0,0,0,0,0,0,0,0,0,0,0,0,0,0,AC58,0,0,0,0,0,0,0,0,0,0,0,0,0)';
      PINUSE='POWER';
      NO_LOAD_CHECK='Both';
      NO_IO_CHECK='Both';
      NO_ASSERT_CHECK='TRUE';
      NO_DIR_CHECK='TRUE';
      ALLOW_CONNECT='TRUE';
    'VDDIO_AC65':
      PIN_NUMBER='(0,0,0,0,0,0,0,0,0,0,0,0,0,0,0,0,0,0,0,0,0,0,0,0,0,0,AC65,0,0,0,0,0,0,0,0,0,0,0,0,0)';
      PINUSE='POWER';
      NO_LOAD_CHECK='Both';
      NO_IO_CHECK='Both';
      NO_ASSERT_CHECK='TRUE';
      NO_DIR_CHECK='TRUE';
      ALLOW_CONNECT='TRUE';
    'VDDIO_AC72':
      PIN_NUMBER='(0,0,0,0,0,0,0,0,0,0,0,0,0,0,0,0,0,0,0,0,0,0,0,0,0,0,AC72,0,0,0,0,0,0,0,0,0,0,0,0,0)';
      PINUSE='POWER';
      NO_LOAD_CHECK='Both';
      NO_IO_CHECK='Both';
      NO_ASSERT_CHECK='TRUE';
      NO_DIR_CHECK='TRUE';
      ALLOW_CONNECT='TRUE';
    'VDDIO_AD54':
      PIN_NUMBER='(0,0,0,0,0,0,0,0,0,0,0,0,0,0,0,0,0,0,0,0,0,0,0,0,0,0,AD54,0,0,0,0,0,0,0,0,0,0,0,0,0)';
      PINUSE='POWER';
      NO_LOAD_CHECK='Both';
      NO_IO_CHECK='Both';
      NO_ASSERT_CHECK='TRUE';
      NO_DIR_CHECK='TRUE';
      ALLOW_CONNECT='TRUE';
    'VDDIO_AF57':
      PIN_NUMBER='(0,0,0,0,0,0,0,0,0,0,0,0,0,0,0,0,0,0,0,0,0,0,0,0,0,0,AF57,0,0,0,0,0,0,0,0,0,0,0,0,0)';
      PINUSE='POWER';
      NO_LOAD_CHECK='Both';
      NO_IO_CHECK='Both';
      NO_ASSERT_CHECK='TRUE';
      NO_DIR_CHECK='TRUE';
      ALLOW_CONNECT='TRUE';
    'VDDIO_AF64':
      PIN_NUMBER='(0,0,0,0,0,0,0,0,0,0,0,0,0,0,0,0,0,0,0,0,0,0,0,0,0,0,AF64,0,0,0,0,0,0,0,0,0,0,0,0,0)';
      PINUSE='POWER';
      NO_LOAD_CHECK='Both';
      NO_IO_CHECK='Both';
      NO_ASSERT_CHECK='TRUE';
      NO_DIR_CHECK='TRUE';
      ALLOW_CONNECT='TRUE';
    'VDDIO_AF71':
      PIN_NUMBER='(0,0,0,0,0,0,0,0,0,0,0,0,0,0,0,0,0,0,0,0,0,0,0,0,0,0,AF71,0,0,0,0,0,0,0,0,0,0,0,0,0)';
      PINUSE='POWER';
      NO_LOAD_CHECK='Both';
      NO_IO_CHECK='Both';
      NO_ASSERT_CHECK='TRUE';
      NO_DIR_CHECK='TRUE';
      ALLOW_CONNECT='TRUE';
    'VDDIO_AH54':
      PIN_NUMBER='(0,0,0,0,0,0,0,0,0,0,0,0,0,0,0,0,0,0,0,0,0,0,0,0,0,0,AH54,0,0,0,0,0,0,0,0,0,0,0,0,0)';
      PINUSE='POWER';
      NO_LOAD_CHECK='Both';
      NO_IO_CHECK='Both';
      NO_ASSERT_CHECK='TRUE';
      NO_DIR_CHECK='TRUE';
      ALLOW_CONNECT='TRUE';
    'VDDIO_AJ58':
      PIN_NUMBER='(0,0,0,0,0,0,0,0,0,0,0,0,0,0,0,0,0,0,0,0,0,0,0,0,0,0,AJ58,0,0,0,0,0,0,0,0,0,0,0,0,0)';
      PINUSE='POWER';
      NO_LOAD_CHECK='Both';
      NO_IO_CHECK='Both';
      NO_ASSERT_CHECK='TRUE';
      NO_DIR_CHECK='TRUE';
      ALLOW_CONNECT='TRUE';
    'VDDIO_AJ65':
      PIN_NUMBER='(0,0,0,0,0,0,0,0,0,0,0,0,0,0,0,0,0,0,0,0,0,0,0,0,0,0,AJ65,0,0,0,0,0,0,0,0,0,0,0,0,0)';
      PINUSE='POWER';
      NO_LOAD_CHECK='Both';
      NO_IO_CHECK='Both';
      NO_ASSERT_CHECK='TRUE';
      NO_DIR_CHECK='TRUE';
      ALLOW_CONNECT='TRUE';
    'VDDIO_AJ72':
      PIN_NUMBER='(0,0,0,0,0,0,0,0,0,0,0,0,0,0,0,0,0,0,0,0,0,0,0,0,0,0,AJ72,0,0,0,0,0,0,0,0,0,0,0,0,0)';
      PINUSE='POWER';
      NO_LOAD_CHECK='Both';
      NO_IO_CHECK='Both';
      NO_ASSERT_CHECK='TRUE';
      NO_DIR_CHECK='TRUE';
      ALLOW_CONNECT='TRUE';
    'VDDIO_AM54':
      PIN_NUMBER='(0,0,0,0,0,0,0,0,0,0,0,0,0,0,0,0,0,0,0,0,0,0,0,0,0,0,AM54,0,0,0,0,0,0,0,0,0,0,0,0,0)';
      PINUSE='POWER';
      NO_LOAD_CHECK='Both';
      NO_IO_CHECK='Both';
      NO_ASSERT_CHECK='TRUE';
      NO_DIR_CHECK='TRUE';
      ALLOW_CONNECT='TRUE';
    'VDDIO_AM57':
      PIN_NUMBER='(0,0,0,0,0,0,0,0,0,0,0,0,0,0,0,0,0,0,0,0,0,0,0,0,0,0,AM57,0,0,0,0,0,0,0,0,0,0,0,0,0)';
      PINUSE='POWER';
      NO_LOAD_CHECK='Both';
      NO_IO_CHECK='Both';
      NO_ASSERT_CHECK='TRUE';
      NO_DIR_CHECK='TRUE';
      ALLOW_CONNECT='TRUE';
    'VDDIO_AM64':
      PIN_NUMBER='(0,0,0,0,0,0,0,0,0,0,0,0,0,0,0,0,0,0,0,0,0,0,0,0,0,0,AM64,0,0,0,0,0,0,0,0,0,0,0,0,0)';
      PINUSE='POWER';
      NO_LOAD_CHECK='Both';
      NO_IO_CHECK='Both';
      NO_ASSERT_CHECK='TRUE';
      NO_DIR_CHECK='TRUE';
      ALLOW_CONNECT='TRUE';
    'VDDIO_AM71':
      PIN_NUMBER='(0,0,0,0,0,0,0,0,0,0,0,0,0,0,0,0,0,0,0,0,0,0,0,0,0,0,AM71,0,0,0,0,0,0,0,0,0,0,0,0,0)';
      PINUSE='POWER';
      NO_LOAD_CHECK='Both';
      NO_IO_CHECK='Both';
      NO_ASSERT_CHECK='TRUE';
      NO_DIR_CHECK='TRUE';
      ALLOW_CONNECT='TRUE';
    'VDDIO_AR58':
      PIN_NUMBER='(0,0,0,0,0,0,0,0,0,0,0,0,0,0,0,0,0,0,0,0,0,0,0,0,0,0,AR58,0,0,0,0,0,0,0,0,0,0,0,0,0)';
      PINUSE='POWER';
      NO_LOAD_CHECK='Both';
      NO_IO_CHECK='Both';
      NO_ASSERT_CHECK='TRUE';
      NO_DIR_CHECK='TRUE';
      ALLOW_CONNECT='TRUE';
    'VDDIO_AR65':
      PIN_NUMBER='(0,0,0,0,0,0,0,0,0,0,0,0,0,0,0,0,0,0,0,0,0,0,0,0,0,0,AR65,0,0,0,0,0,0,0,0,0,0,0,0,0)';
      PINUSE='POWER';
      NO_LOAD_CHECK='Both';
      NO_IO_CHECK='Both';
      NO_ASSERT_CHECK='TRUE';
      NO_DIR_CHECK='TRUE';
      ALLOW_CONNECT='TRUE';
    'VDDIO_AR72':
      PIN_NUMBER='(0,0,0,0,0,0,0,0,0,0,0,0,0,0,0,0,0,0,0,0,0,0,0,0,0,0,AR72,0,0,0,0,0,0,0,0,0,0,0,0,0)';
      PINUSE='POWER';
      NO_LOAD_CHECK='Both';
      NO_IO_CHECK='Both';
      NO_ASSERT_CHECK='TRUE';
      NO_DIR_CHECK='TRUE';
      ALLOW_CONNECT='TRUE';
    'VDDIO_AV57':
      PIN_NUMBER='(0,0,0,0,0,0,0,0,0,0,0,0,0,0,0,0,0,0,0,0,0,0,0,0,0,0,AV57,0,0,0,0,0,0,0,0,0,0,0,0,0)';
      PINUSE='POWER';
      NO_LOAD_CHECK='Both';
      NO_IO_CHECK='Both';
      NO_ASSERT_CHECK='TRUE';
      NO_DIR_CHECK='TRUE';
      ALLOW_CONNECT='TRUE';
    'VDDIO_AV64':
      PIN_NUMBER='(0,0,0,0,0,0,0,0,0,0,0,0,0,0,0,0,0,0,0,0,0,0,0,0,0,0,AV64,0,0,0,0,0,0,0,0,0,0,0,0,0)';
      PINUSE='POWER';
      NO_LOAD_CHECK='Both';
      NO_IO_CHECK='Both';
      NO_ASSERT_CHECK='TRUE';
      NO_DIR_CHECK='TRUE';
      ALLOW_CONNECT='TRUE';
    'VDDIO_AV71':
      PIN_NUMBER='(0,0,0,0,0,0,0,0,0,0,0,0,0,0,0,0,0,0,0,0,0,0,0,0,0,0,AV71,0,0,0,0,0,0,0,0,0,0,0,0,0)';
      PINUSE='POWER';
      NO_LOAD_CHECK='Both';
      NO_IO_CHECK='Both';
      NO_ASSERT_CHECK='TRUE';
      NO_DIR_CHECK='TRUE';
      ALLOW_CONNECT='TRUE';
    'VDDIO_BA58':
      PIN_NUMBER='(0,0,0,0,0,0,0,0,0,0,0,0,0,0,0,0,0,0,0,0,0,0,0,0,0,0,BA58,0,0,0,0,0,0,0,0,0,0,0,0,0)';
      PINUSE='POWER';
      NO_LOAD_CHECK='Both';
      NO_IO_CHECK='Both';
      NO_ASSERT_CHECK='TRUE';
      NO_DIR_CHECK='TRUE';
      ALLOW_CONNECT='TRUE';
    'VDDIO_BA65':
      PIN_NUMBER='(0,0,0,0,0,0,0,0,0,0,0,0,0,0,0,0,0,0,0,0,0,0,0,0,0,0,BA65,0,0,0,0,0,0,0,0,0,0,0,0,0)';
      PINUSE='POWER';
      NO_LOAD_CHECK='Both';
      NO_IO_CHECK='Both';
      NO_ASSERT_CHECK='TRUE';
      NO_DIR_CHECK='TRUE';
      ALLOW_CONNECT='TRUE';
    'VDDIO_BA72':
      PIN_NUMBER='(0,0,0,0,0,0,0,0,0,0,0,0,0,0,0,0,0,0,0,0,0,0,0,0,0,0,BA72,0,0,0,0,0,0,0,0,0,0,0,0,0)';
      PINUSE='POWER';
      NO_LOAD_CHECK='Both';
      NO_IO_CHECK='Both';
      NO_ASSERT_CHECK='TRUE';
      NO_DIR_CHECK='TRUE';
      ALLOW_CONNECT='TRUE';
    'VDDIO_BD50':
      PIN_NUMBER='(0,0,0,0,0,0,0,0,0,0,0,0,0,0,0,0,0,0,0,0,0,0,0,0,0,0,BD50,0,0,0,0,0,0,0,0,0,0,0,0,0)';
      PINUSE='POWER';
      NO_LOAD_CHECK='Both';
      NO_IO_CHECK='Both';
      NO_ASSERT_CHECK='TRUE';
      NO_DIR_CHECK='TRUE';
      ALLOW_CONNECT='TRUE';
    'VDDIO_BD52':
      PIN_NUMBER='(0,0,0,0,0,0,0,0,0,0,0,0,0,0,0,0,0,0,0,0,0,0,0,0,0,0,BD52,0,0,0,0,0,0,0,0,0,0,0,0,0)';
      PINUSE='POWER';
      NO_LOAD_CHECK='Both';
      NO_IO_CHECK='Both';
      NO_ASSERT_CHECK='TRUE';
      NO_DIR_CHECK='TRUE';
      ALLOW_CONNECT='TRUE';
    'VDDIO_BD54':
      PIN_NUMBER='(0,0,0,0,0,0,0,0,0,0,0,0,0,0,0,0,0,0,0,0,0,0,0,0,0,0,BD54,0,0,0,0,0,0,0,0,0,0,0,0,0)';
      PINUSE='POWER';
      NO_LOAD_CHECK='Both';
      NO_IO_CHECK='Both';
      NO_ASSERT_CHECK='TRUE';
      NO_DIR_CHECK='TRUE';
      ALLOW_CONNECT='TRUE';
    'VDDIO_BF51':
      PIN_NUMBER='(0,0,0,0,0,0,0,0,0,0,0,0,0,0,0,0,0,0,0,0,0,0,0,0,0,0,BF51,0,0,0,0,0,0,0,0,0,0,0,0,0)';
      PINUSE='POWER';
      NO_LOAD_CHECK='Both';
      NO_IO_CHECK='Both';
      NO_ASSERT_CHECK='TRUE';
      NO_DIR_CHECK='TRUE';
      ALLOW_CONNECT='TRUE';
    'VDDIO_BF53':
      PIN_NUMBER='(0,0,0,0,0,0,0,0,0,0,0,0,0,0,0,0,0,0,0,0,0,0,0,0,0,0,BF53,0,0,0,0,0,0,0,0,0,0,0,0,0)';
      PINUSE='POWER';
      NO_LOAD_CHECK='Both';
      NO_IO_CHECK='Both';
      NO_ASSERT_CHECK='TRUE';
      NO_DIR_CHECK='TRUE';
      ALLOW_CONNECT='TRUE';
    'VDDIO_BF57':
      PIN_NUMBER='(0,0,0,0,0,0,0,0,0,0,0,0,0,0,0,0,0,0,0,0,0,0,0,0,0,0,BF57,0,0,0,0,0,0,0,0,0,0,0,0,0)';
      PINUSE='POWER';
      NO_LOAD_CHECK='Both';
      NO_IO_CHECK='Both';
      NO_ASSERT_CHECK='TRUE';
      NO_DIR_CHECK='TRUE';
      ALLOW_CONNECT='TRUE';
    'VDDIO_BF64':
      PIN_NUMBER='(0,0,0,0,0,0,0,0,0,0,0,0,0,0,0,0,0,0,0,0,0,0,0,0,0,0,BF64,0,0,0,0,0,0,0,0,0,0,0,0,0)';
      PINUSE='POWER';
      NO_LOAD_CHECK='Both';
      NO_IO_CHECK='Both';
      NO_ASSERT_CHECK='TRUE';
      NO_DIR_CHECK='TRUE';
      ALLOW_CONNECT='TRUE';
    'VDDIO_BF71':
      PIN_NUMBER='(0,0,0,0,0,0,0,0,0,0,0,0,0,0,0,0,0,0,0,0,0,0,0,0,0,0,BF71,0,0,0,0,0,0,0,0,0,0,0,0,0)';
      PINUSE='POWER';
      NO_LOAD_CHECK='Both';
      NO_IO_CHECK='Both';
      NO_ASSERT_CHECK='TRUE';
      NO_DIR_CHECK='TRUE';
      ALLOW_CONNECT='TRUE';
    'VDDIO_BG50':
      PIN_NUMBER='(0,0,0,0,0,0,0,0,0,0,0,0,0,0,0,0,0,0,0,0,0,0,0,0,0,0,BG50,0,0,0,0,0,0,0,0,0,0,0,0,0)';
      PINUSE='POWER';
      NO_LOAD_CHECK='Both';
      NO_IO_CHECK='Both';
      NO_ASSERT_CHECK='TRUE';
      NO_DIR_CHECK='TRUE';
      ALLOW_CONNECT='TRUE';
    'VDDIO_BG52':
      PIN_NUMBER='(0,0,0,0,0,0,0,0,0,0,0,0,0,0,0,0,0,0,0,0,0,0,0,0,0,0,BG52,0,0,0,0,0,0,0,0,0,0,0,0,0)';
      PINUSE='POWER';
      NO_LOAD_CHECK='Both';
      NO_IO_CHECK='Both';
      NO_ASSERT_CHECK='TRUE';
      NO_DIR_CHECK='TRUE';
      ALLOW_CONNECT='TRUE';
    'VDDIO_BG54':
      PIN_NUMBER='(0,0,0,0,0,0,0,0,0,0,0,0,0,0,0,0,0,0,0,0,0,0,0,0,0,0,BG54,0,0,0,0,0,0,0,0,0,0,0,0,0)';
      PINUSE='POWER';
      NO_LOAD_CHECK='Both';
      NO_IO_CHECK='Both';
      NO_ASSERT_CHECK='TRUE';
      NO_DIR_CHECK='TRUE';
      ALLOW_CONNECT='TRUE';
    'VDDIO_BH51':
      PIN_NUMBER='(0,0,0,0,0,0,0,0,0,0,0,0,0,0,0,0,0,0,0,0,0,0,0,0,0,0,BH51,0,0,0,0,0,0,0,0,0,0,0,0,0)';
      PINUSE='POWER';
      NO_LOAD_CHECK='Both';
      NO_IO_CHECK='Both';
      NO_ASSERT_CHECK='TRUE';
      NO_DIR_CHECK='TRUE';
      ALLOW_CONNECT='TRUE';
    'VDDIO_BH53':
      PIN_NUMBER='(0,0,0,0,0,0,0,0,0,0,0,0,0,0,0,0,0,0,0,0,0,0,0,0,0,0,BH53,0,0,0,0,0,0,0,0,0,0,0,0,0)';
      PINUSE='POWER';
      NO_LOAD_CHECK='Both';
      NO_IO_CHECK='Both';
      NO_ASSERT_CHECK='TRUE';
      NO_DIR_CHECK='TRUE';
      ALLOW_CONNECT='TRUE';
    'VDDIO_BJ50':
      PIN_NUMBER='(0,0,0,0,0,0,0,0,0,0,0,0,0,0,0,0,0,0,0,0,0,0,0,0,0,0,BJ50,0,0,0,0,0,0,0,0,0,0,0,0,0)';
      PINUSE='POWER';
      NO_LOAD_CHECK='Both';
      NO_IO_CHECK='Both';
      NO_ASSERT_CHECK='TRUE';
      NO_DIR_CHECK='TRUE';
      ALLOW_CONNECT='TRUE';
    'VDDIO_BJ52':
      PIN_NUMBER='(0,0,0,0,0,0,0,0,0,0,0,0,0,0,0,0,0,0,0,0,0,0,0,0,0,0,BJ52,0,0,0,0,0,0,0,0,0,0,0,0,0)';
      PINUSE='POWER';
      NO_LOAD_CHECK='Both';
      NO_IO_CHECK='Both';
      NO_ASSERT_CHECK='TRUE';
      NO_DIR_CHECK='TRUE';
      ALLOW_CONNECT='TRUE';
    'VDDIO_BJ54':
      PIN_NUMBER='(0,0,0,0,0,0,0,0,0,0,0,0,0,0,0,0,0,0,0,0,0,0,0,0,0,0,BJ54,0,0,0,0,0,0,0,0,0,0,0,0,0)';
      PINUSE='POWER';
      NO_LOAD_CHECK='Both';
      NO_IO_CHECK='Both';
      NO_ASSERT_CHECK='TRUE';
      NO_DIR_CHECK='TRUE';
      ALLOW_CONNECT='TRUE';
    'VDDIO_BJ58':
      PIN_NUMBER='(0,0,0,0,0,0,0,0,0,0,0,0,0,0,0,0,0,0,0,0,0,0,0,0,0,0,BJ58,0,0,0,0,0,0,0,0,0,0,0,0,0)';
      PINUSE='POWER';
      NO_LOAD_CHECK='Both';
      NO_IO_CHECK='Both';
      NO_ASSERT_CHECK='TRUE';
      NO_DIR_CHECK='TRUE';
      ALLOW_CONNECT='TRUE';
    'VDDIO_BJ65':
      PIN_NUMBER='(0,0,0,0,0,0,0,0,0,0,0,0,0,0,0,0,0,0,0,0,0,0,0,0,0,0,BJ65,0,0,0,0,0,0,0,0,0,0,0,0,0)';
      PINUSE='POWER';
      NO_LOAD_CHECK='Both';
      NO_IO_CHECK='Both';
      NO_ASSERT_CHECK='TRUE';
      NO_DIR_CHECK='TRUE';
      ALLOW_CONNECT='TRUE';
    'VDDIO_BJ72':
      PIN_NUMBER='(0,0,0,0,0,0,0,0,0,0,0,0,0,0,0,0,0,0,0,0,0,0,0,0,0,0,BJ72,0,0,0,0,0,0,0,0,0,0,0,0,0)';
      PINUSE='POWER';
      NO_LOAD_CHECK='Both';
      NO_IO_CHECK='Both';
      NO_ASSERT_CHECK='TRUE';
      NO_DIR_CHECK='TRUE';
      ALLOW_CONNECT='TRUE';
    'VDDIO_BK51':
      PIN_NUMBER='(0,0,0,0,0,0,0,0,0,0,0,0,0,0,0,0,0,0,0,0,0,0,0,0,0,0,BK51,0,0,0,0,0,0,0,0,0,0,0,0,0)';
      PINUSE='POWER';
      NO_LOAD_CHECK='Both';
      NO_IO_CHECK='Both';
      NO_ASSERT_CHECK='TRUE';
      NO_DIR_CHECK='TRUE';
      ALLOW_CONNECT='TRUE';
    'VDDIO_BK53':
      PIN_NUMBER='(0,0,0,0,0,0,0,0,0,0,0,0,0,0,0,0,0,0,0,0,0,0,0,0,0,0,BK53,0,0,0,0,0,0,0,0,0,0,0,0,0)';
      PINUSE='POWER';
      NO_LOAD_CHECK='Both';
      NO_IO_CHECK='Both';
      NO_ASSERT_CHECK='TRUE';
      NO_DIR_CHECK='TRUE';
      ALLOW_CONNECT='TRUE';
    'VDDIO_BL50':
      PIN_NUMBER='(0,0,0,0,0,0,0,0,0,0,0,0,0,0,0,0,0,0,0,0,0,0,0,0,0,0,BL50,0,0,0,0,0,0,0,0,0,0,0,0,0)';
      PINUSE='POWER';
      NO_LOAD_CHECK='Both';
      NO_IO_CHECK='Both';
      NO_ASSERT_CHECK='TRUE';
      NO_DIR_CHECK='TRUE';
      ALLOW_CONNECT='TRUE';
    'VDDIO_BL52':
      PIN_NUMBER='(0,0,0,0,0,0,0,0,0,0,0,0,0,0,0,0,0,0,0,0,0,0,0,0,0,0,BL52,0,0,0,0,0,0,0,0,0,0,0,0,0)';
      PINUSE='POWER';
      NO_LOAD_CHECK='Both';
      NO_IO_CHECK='Both';
      NO_ASSERT_CHECK='TRUE';
      NO_DIR_CHECK='TRUE';
      ALLOW_CONNECT='TRUE';
    'VDDIO_BL54':
      PIN_NUMBER='(0,0,0,0,0,0,0,0,0,0,0,0,0,0,0,0,0,0,0,0,0,0,0,0,0,0,BL54,0,0,0,0,0,0,0,0,0,0,0,0,0)';
      PINUSE='POWER';
      NO_LOAD_CHECK='Both';
      NO_IO_CHECK='Both';
      NO_ASSERT_CHECK='TRUE';
      NO_DIR_CHECK='TRUE';
      ALLOW_CONNECT='TRUE';
    'VDDIO_BM51':
      PIN_NUMBER='(0,0,0,0,0,0,0,0,0,0,0,0,0,0,0,0,0,0,0,0,0,0,0,0,0,0,BM51,0,0,0,0,0,0,0,0,0,0,0,0,0)';
      PINUSE='POWER';
      NO_LOAD_CHECK='Both';
      NO_IO_CHECK='Both';
      NO_ASSERT_CHECK='TRUE';
      NO_DIR_CHECK='TRUE';
      ALLOW_CONNECT='TRUE';
    'VDDIO_BM53':
      PIN_NUMBER='(0,0,0,0,0,0,0,0,0,0,0,0,0,0,0,0,0,0,0,0,0,0,0,0,0,0,BM53,0,0,0,0,0,0,0,0,0,0,0,0,0)';
      PINUSE='POWER';
      NO_LOAD_CHECK='Both';
      NO_IO_CHECK='Both';
      NO_ASSERT_CHECK='TRUE';
      NO_DIR_CHECK='TRUE';
      ALLOW_CONNECT='TRUE';
    'VDDIO_BM57':
      PIN_NUMBER='(0,0,0,0,0,0,0,0,0,0,0,0,0,0,0,0,0,0,0,0,0,0,0,0,0,0,BM57,0,0,0,0,0,0,0,0,0,0,0,0,0)';
      PINUSE='POWER';
      NO_LOAD_CHECK='Both';
      NO_IO_CHECK='Both';
      NO_ASSERT_CHECK='TRUE';
      NO_DIR_CHECK='TRUE';
      ALLOW_CONNECT='TRUE';
    'VDDIO_BM64':
      PIN_NUMBER='(0,0,0,0,0,0,0,0,0,0,0,0,0,0,0,0,0,0,0,0,0,0,0,0,0,0,BM64,0,0,0,0,0,0,0,0,0,0,0,0,0)';
      PINUSE='POWER';
      NO_LOAD_CHECK='Both';
      NO_IO_CHECK='Both';
      NO_ASSERT_CHECK='TRUE';
      NO_DIR_CHECK='TRUE';
      ALLOW_CONNECT='TRUE';
    'VDDIO_BM71':
      PIN_NUMBER='(0,0,0,0,0,0,0,0,0,0,0,0,0,0,0,0,0,0,0,0,0,0,0,0,0,0,BM71,0,0,0,0,0,0,0,0,0,0,0,0,0)';
      PINUSE='POWER';
      NO_LOAD_CHECK='Both';
      NO_IO_CHECK='Both';
      NO_ASSERT_CHECK='TRUE';
      NO_DIR_CHECK='TRUE';
      ALLOW_CONNECT='TRUE';
    'VDDIO_BN54':
      PIN_NUMBER='(0,0,0,0,0,0,0,0,0,0,0,0,0,0,0,0,0,0,0,0,0,0,0,0,0,0,BN54,0,0,0,0,0,0,0,0,0,0,0,0,0)';
      PINUSE='POWER';
      NO_LOAD_CHECK='Both';
      NO_IO_CHECK='Both';
      NO_ASSERT_CHECK='TRUE';
      NO_DIR_CHECK='TRUE';
      ALLOW_CONNECT='TRUE';
    'VDDIO_BR58':
      PIN_NUMBER='(0,0,0,0,0,0,0,0,0,0,0,0,0,0,0,0,0,0,0,0,0,0,0,0,0,0,BR58,0,0,0,0,0,0,0,0,0,0,0,0,0)';
      PINUSE='POWER';
      NO_LOAD_CHECK='Both';
      NO_IO_CHECK='Both';
      NO_ASSERT_CHECK='TRUE';
      NO_DIR_CHECK='TRUE';
      ALLOW_CONNECT='TRUE';
    'VDDIO_BR65':
      PIN_NUMBER='(0,0,0,0,0,0,0,0,0,0,0,0,0,0,0,0,0,0,0,0,0,0,0,0,0,0,BR65,0,0,0,0,0,0,0,0,0,0,0,0,0)';
      PINUSE='POWER';
      NO_LOAD_CHECK='Both';
      NO_IO_CHECK='Both';
      NO_ASSERT_CHECK='TRUE';
      NO_DIR_CHECK='TRUE';
      ALLOW_CONNECT='TRUE';
    'VDDIO_BR72':
      PIN_NUMBER='(0,0,0,0,0,0,0,0,0,0,0,0,0,0,0,0,0,0,0,0,0,0,0,0,0,0,BR72,0,0,0,0,0,0,0,0,0,0,0,0,0)';
      PINUSE='POWER';
      NO_LOAD_CHECK='Both';
      NO_IO_CHECK='Both';
      NO_ASSERT_CHECK='TRUE';
      NO_DIR_CHECK='TRUE';
      ALLOW_CONNECT='TRUE';
    'VDDIO_BV54':
      PIN_NUMBER='(0,0,0,0,0,0,0,0,0,0,0,0,0,0,0,0,0,0,0,0,0,0,0,0,0,0,BV54,0,0,0,0,0,0,0,0,0,0,0,0,0)';
      PINUSE='POWER';
      NO_LOAD_CHECK='Both';
      NO_IO_CHECK='Both';
      NO_ASSERT_CHECK='TRUE';
      NO_DIR_CHECK='TRUE';
      ALLOW_CONNECT='TRUE';
    'VDDIO_BV57':
      PIN_NUMBER='(0,0,0,0,0,0,0,0,0,0,0,0,0,0,0,0,0,0,0,0,0,0,0,0,0,0,BV57,0,0,0,0,0,0,0,0,0,0,0,0,0)';
      PINUSE='POWER';
      NO_LOAD_CHECK='Both';
      NO_IO_CHECK='Both';
      NO_ASSERT_CHECK='TRUE';
      NO_DIR_CHECK='TRUE';
      ALLOW_CONNECT='TRUE';
    'VDDIO_BV64':
      PIN_NUMBER='(0,0,0,0,0,0,0,0,0,0,0,0,0,0,0,0,0,0,0,0,0,0,0,0,0,0,BV64,0,0,0,0,0,0,0,0,0,0,0,0,0)';
      PINUSE='POWER';
      NO_LOAD_CHECK='Both';
      NO_IO_CHECK='Both';
      NO_ASSERT_CHECK='TRUE';
      NO_DIR_CHECK='TRUE';
      ALLOW_CONNECT='TRUE';
    'VDDIO_BV71':
      PIN_NUMBER='(0,0,0,0,0,0,0,0,0,0,0,0,0,0,0,0,0,0,0,0,0,0,0,0,0,0,BV71,0,0,0,0,0,0,0,0,0,0,0,0,0)';
      PINUSE='POWER';
      NO_LOAD_CHECK='Both';
      NO_IO_CHECK='Both';
      NO_ASSERT_CHECK='TRUE';
      NO_DIR_CHECK='TRUE';
      ALLOW_CONNECT='TRUE';
    'VDDIO_CA58':
      PIN_NUMBER='(0,0,0,0,0,0,0,0,0,0,0,0,0,0,0,0,0,0,0,0,0,0,0,0,0,0,CA58,0,0,0,0,0,0,0,0,0,0,0,0,0)';
      PINUSE='POWER';
      NO_LOAD_CHECK='Both';
      NO_IO_CHECK='Both';
      NO_ASSERT_CHECK='TRUE';
      NO_DIR_CHECK='TRUE';
      ALLOW_CONNECT='TRUE';
    'VDDIO_CA65':
      PIN_NUMBER='(0,0,0,0,0,0,0,0,0,0,0,0,0,0,0,0,0,0,0,0,0,0,0,0,0,0,CA65,0,0,0,0,0,0,0,0,0,0,0,0,0)';
      PINUSE='POWER';
      NO_LOAD_CHECK='Both';
      NO_IO_CHECK='Both';
      NO_ASSERT_CHECK='TRUE';
      NO_DIR_CHECK='TRUE';
      ALLOW_CONNECT='TRUE';
    'VDDIO_CA72':
      PIN_NUMBER='(0,0,0,0,0,0,0,0,0,0,0,0,0,0,0,0,0,0,0,0,0,0,0,0,0,0,CA72,0,0,0,0,0,0,0,0,0,0,0,0,0)';
      PINUSE='POWER';
      NO_LOAD_CHECK='Both';
      NO_IO_CHECK='Both';
      NO_ASSERT_CHECK='TRUE';
      NO_DIR_CHECK='TRUE';
      ALLOW_CONNECT='TRUE';
    'VDDIO_CB54':
      PIN_NUMBER='(0,0,0,0,0,0,0,0,0,0,0,0,0,0,0,0,0,0,0,0,0,0,0,0,0,0,CB54,0,0,0,0,0,0,0,0,0,0,0,0,0)';
      PINUSE='POWER';
      NO_LOAD_CHECK='Both';
      NO_IO_CHECK='Both';
      NO_ASSERT_CHECK='TRUE';
      NO_DIR_CHECK='TRUE';
      ALLOW_CONNECT='TRUE';
    'VDDIO_CD57':
      PIN_NUMBER='(0,0,0,0,0,0,0,0,0,0,0,0,0,0,0,0,0,0,0,0,0,0,0,0,0,0,CD57,0,0,0,0,0,0,0,0,0,0,0,0,0)';
      PINUSE='POWER';
      NO_LOAD_CHECK='Both';
      NO_IO_CHECK='Both';
      NO_ASSERT_CHECK='TRUE';
      NO_DIR_CHECK='TRUE';
      ALLOW_CONNECT='TRUE';
    'VDDIO_CD64':
      PIN_NUMBER='(0,0,0,0,0,0,0,0,0,0,0,0,0,0,0,0,0,0,0,0,0,0,0,0,0,0,CD64,0,0,0,0,0,0,0,0,0,0,0,0,0)';
      PINUSE='POWER';
      NO_LOAD_CHECK='Both';
      NO_IO_CHECK='Both';
      NO_ASSERT_CHECK='TRUE';
      NO_DIR_CHECK='TRUE';
      ALLOW_CONNECT='TRUE';
    'VDDIO_CD71':
      PIN_NUMBER='(0,0,0,0,0,0,0,0,0,0,0,0,0,0,0,0,0,0,0,0,0,0,0,0,0,0,CD71,0,0,0,0,0,0,0,0,0,0,0,0,0)';
      PINUSE='POWER';
      NO_LOAD_CHECK='Both';
      NO_IO_CHECK='Both';
      NO_ASSERT_CHECK='TRUE';
      NO_DIR_CHECK='TRUE';
      ALLOW_CONNECT='TRUE';
    'VDDIO_CF54':
      PIN_NUMBER='(0,0,0,0,0,0,0,0,0,0,0,0,0,0,0,0,0,0,0,0,0,0,0,0,0,0,CF54,0,0,0,0,0,0,0,0,0,0,0,0,0)';
      PINUSE='POWER';
      NO_LOAD_CHECK='Both';
      NO_IO_CHECK='Both';
      NO_ASSERT_CHECK='TRUE';
      NO_DIR_CHECK='TRUE';
      ALLOW_CONNECT='TRUE';
    'VDDIO_CG58':
      PIN_NUMBER='(0,0,0,0,0,0,0,0,0,0,0,0,0,0,0,0,0,0,0,0,0,0,0,0,0,0,CG58,0,0,0,0,0,0,0,0,0,0,0,0,0)';
      PINUSE='POWER';
      NO_LOAD_CHECK='Both';
      NO_IO_CHECK='Both';
      NO_ASSERT_CHECK='TRUE';
      NO_DIR_CHECK='TRUE';
      ALLOW_CONNECT='TRUE';
    'VDDIO_CG65':
      PIN_NUMBER='(0,0,0,0,0,0,0,0,0,0,0,0,0,0,0,0,0,0,0,0,0,0,0,0,0,0,CG65,0,0,0,0,0,0,0,0,0,0,0,0,0)';
      PINUSE='POWER';
      NO_LOAD_CHECK='Both';
      NO_IO_CHECK='Both';
      NO_ASSERT_CHECK='TRUE';
      NO_DIR_CHECK='TRUE';
      ALLOW_CONNECT='TRUE';
    'VDDIO_CG72':
      PIN_NUMBER='(0,0,0,0,0,0,0,0,0,0,0,0,0,0,0,0,0,0,0,0,0,0,0,0,0,0,CG72,0,0,0,0,0,0,0,0,0,0,0,0,0)';
      PINUSE='POWER';
      NO_LOAD_CHECK='Both';
      NO_IO_CHECK='Both';
      NO_ASSERT_CHECK='TRUE';
      NO_DIR_CHECK='TRUE';
      ALLOW_CONNECT='TRUE';
    'VDDIO_CJ54':
      PIN_NUMBER='(0,0,0,0,0,0,0,0,0,0,0,0,0,0,0,0,0,0,0,0,0,0,0,0,0,0,CJ54,0,0,0,0,0,0,0,0,0,0,0,0,0)';
      PINUSE='POWER';
      NO_LOAD_CHECK='Both';
      NO_IO_CHECK='Both';
      NO_ASSERT_CHECK='TRUE';
      NO_DIR_CHECK='TRUE';
      ALLOW_CONNECT='TRUE';
    'VDDIO_CK57':
      PIN_NUMBER='(0,0,0,0,0,0,0,0,0,0,0,0,0,0,0,0,0,0,0,0,0,0,0,0,0,0,CK57,0,0,0,0,0,0,0,0,0,0,0,0,0)';
      PINUSE='POWER';
      NO_LOAD_CHECK='Both';
      NO_IO_CHECK='Both';
      NO_ASSERT_CHECK='TRUE';
      NO_DIR_CHECK='TRUE';
      ALLOW_CONNECT='TRUE';
    'VDDIO_CK64':
      PIN_NUMBER='(0,0,0,0,0,0,0,0,0,0,0,0,0,0,0,0,0,0,0,0,0,0,0,0,0,0,CK64,0,0,0,0,0,0,0,0,0,0,0,0,0)';
      PINUSE='POWER';
      NO_LOAD_CHECK='Both';
      NO_IO_CHECK='Both';
      NO_ASSERT_CHECK='TRUE';
      NO_DIR_CHECK='TRUE';
      ALLOW_CONNECT='TRUE';
    'VDDIO_CK71':
      PIN_NUMBER='(0,0,0,0,0,0,0,0,0,0,0,0,0,0,0,0,0,0,0,0,0,0,0,0,0,0,CK71,0,0,0,0,0,0,0,0,0,0,0,0,0)';
      PINUSE='POWER';
      NO_LOAD_CHECK='Both';
      NO_IO_CHECK='Both';
      NO_ASSERT_CHECK='TRUE';
      NO_DIR_CHECK='TRUE';
      ALLOW_CONNECT='TRUE';
    'VDDIO_CM54':
      PIN_NUMBER='(0,0,0,0,0,0,0,0,0,0,0,0,0,0,0,0,0,0,0,0,0,0,0,0,0,0,CM54,0,0,0,0,0,0,0,0,0,0,0,0,0)';
      PINUSE='POWER';
      NO_LOAD_CHECK='Both';
      NO_IO_CHECK='Both';
      NO_ASSERT_CHECK='TRUE';
      NO_DIR_CHECK='TRUE';
      ALLOW_CONNECT='TRUE';
    'VDDIO_CN58':
      PIN_NUMBER='(0,0,0,0,0,0,0,0,0,0,0,0,0,0,0,0,0,0,0,0,0,0,0,0,0,0,CN58,0,0,0,0,0,0,0,0,0,0,0,0,0)';
      PINUSE='POWER';
      NO_LOAD_CHECK='Both';
      NO_IO_CHECK='Both';
      NO_ASSERT_CHECK='TRUE';
      NO_DIR_CHECK='TRUE';
      ALLOW_CONNECT='TRUE';
    'VDDIO_CN65':
      PIN_NUMBER='(0,0,0,0,0,0,0,0,0,0,0,0,0,0,0,0,0,0,0,0,0,0,0,0,0,0,CN65,0,0,0,0,0,0,0,0,0,0,0,0,0)';
      PINUSE='POWER';
      NO_LOAD_CHECK='Both';
      NO_IO_CHECK='Both';
      NO_ASSERT_CHECK='TRUE';
      NO_DIR_CHECK='TRUE';
      ALLOW_CONNECT='TRUE';
    'VDDIO_CN72':
      PIN_NUMBER='(0,0,0,0,0,0,0,0,0,0,0,0,0,0,0,0,0,0,0,0,0,0,0,0,0,0,CN72,0,0,0,0,0,0,0,0,0,0,0,0,0)';
      PINUSE='POWER';
      NO_LOAD_CHECK='Both';
      NO_IO_CHECK='Both';
      NO_ASSERT_CHECK='TRUE';
      NO_DIR_CHECK='TRUE';
      ALLOW_CONNECT='TRUE';
    'VDDIO_CT54':
      PIN_NUMBER='(0,0,0,0,0,0,0,0,0,0,0,0,0,0,0,0,0,0,0,0,0,0,0,0,0,0,CT54,0,0,0,0,0,0,0,0,0,0,0,0,0)';
      PINUSE='POWER';
      NO_LOAD_CHECK='Both';
      NO_IO_CHECK='Both';
      NO_ASSERT_CHECK='TRUE';
      NO_DIR_CHECK='TRUE';
      ALLOW_CONNECT='TRUE';
    'VDDIO_CT57':
      PIN_NUMBER='(0,0,0,0,0,0,0,0,0,0,0,0,0,0,0,0,0,0,0,0,0,0,0,0,0,0,CT57,0,0,0,0,0,0,0,0,0,0,0,0,0)';
      PINUSE='POWER';
      NO_LOAD_CHECK='Both';
      NO_IO_CHECK='Both';
      NO_ASSERT_CHECK='TRUE';
      NO_DIR_CHECK='TRUE';
      ALLOW_CONNECT='TRUE';
    'VDD_11_S3_BJ18':
      PIN_NUMBER='(0,0,0,0,0,0,0,0,0,0,0,0,0,0,0,0,0,0,0,0,0,0,0,0,0,0,BJ18,0,0,0,0,0,0,0,0,0,0,0,0,0)';
      PINUSE='POWER';
      NO_LOAD_CHECK='Both';
      NO_IO_CHECK='Both';
      NO_ASSERT_CHECK='TRUE';
      NO_DIR_CHECK='TRUE';
      ALLOW_CONNECT='TRUE';
    'VDD_11_S3_BJ23':
      PIN_NUMBER='(0,0,0,0,0,0,0,0,0,0,0,0,0,0,0,0,0,0,0,0,0,0,0,0,0,0,BJ23,0,0,0,0,0,0,0,0,0,0,0,0,0)';
      PINUSE='POWER';
      NO_LOAD_CHECK='Both';
      NO_IO_CHECK='Both';
      NO_ASSERT_CHECK='TRUE';
      NO_DIR_CHECK='TRUE';
      ALLOW_CONNECT='TRUE';
    'VDD_11_S3_BJ25':
      PIN_NUMBER='(0,0,0,0,0,0,0,0,0,0,0,0,0,0,0,0,0,0,0,0,0,0,0,0,0,0,BJ25,0,0,0,0,0,0,0,0,0,0,0,0,0)';
      PINUSE='POWER';
      NO_LOAD_CHECK='Both';
      NO_IO_CHECK='Both';
      NO_ASSERT_CHECK='TRUE';
      NO_DIR_CHECK='TRUE';
      ALLOW_CONNECT='TRUE';
    'VDD_11_S3_BJ27':
      PIN_NUMBER='(0,0,0,0,0,0,0,0,0,0,0,0,0,0,0,0,0,0,0,0,0,0,0,0,0,0,BJ27,0,0,0,0,0,0,0,0,0,0,0,0,0)';
      PINUSE='POWER';
      NO_LOAD_CHECK='Both';
      NO_IO_CHECK='Both';
      NO_ASSERT_CHECK='TRUE';
      NO_DIR_CHECK='TRUE';
      ALLOW_CONNECT='TRUE';
    'VDD_11_S3_BK22':
      PIN_NUMBER='(0,0,0,0,0,0,0,0,0,0,0,0,0,0,0,0,0,0,0,0,0,0,0,0,0,0,BK22,0,0,0,0,0,0,0,0,0,0,0,0,0)';
      PINUSE='POWER';
      NO_LOAD_CHECK='Both';
      NO_IO_CHECK='Both';
      NO_ASSERT_CHECK='TRUE';
      NO_DIR_CHECK='TRUE';
      ALLOW_CONNECT='TRUE';
    'VDD_11_S3_BK24':
      PIN_NUMBER='(0,0,0,0,0,0,0,0,0,0,0,0,0,0,0,0,0,0,0,0,0,0,0,0,0,0,BK24,0,0,0,0,0,0,0,0,0,0,0,0,0)';
      PINUSE='POWER';
      NO_LOAD_CHECK='Both';
      NO_IO_CHECK='Both';
      NO_ASSERT_CHECK='TRUE';
      NO_DIR_CHECK='TRUE';
      ALLOW_CONNECT='TRUE';
    'VDD_11_S3_BK26':
      PIN_NUMBER='(0,0,0,0,0,0,0,0,0,0,0,0,0,0,0,0,0,0,0,0,0,0,0,0,0,0,BK26,0,0,0,0,0,0,0,0,0,0,0,0,0)';
      PINUSE='POWER';
      NO_LOAD_CHECK='Both';
      NO_IO_CHECK='Both';
      NO_ASSERT_CHECK='TRUE';
      NO_DIR_CHECK='TRUE';
      ALLOW_CONNECT='TRUE';
    'VDD_11_S3_BK28':
      PIN_NUMBER='(0,0,0,0,0,0,0,0,0,0,0,0,0,0,0,0,0,0,0,0,0,0,0,0,0,0,BK28,0,0,0,0,0,0,0,0,0,0,0,0,0)';
      PINUSE='POWER';
      NO_LOAD_CHECK='Both';
      NO_IO_CHECK='Both';
      NO_ASSERT_CHECK='TRUE';
      NO_DIR_CHECK='TRUE';
      ALLOW_CONNECT='TRUE';
    'VDD_11_S3_BK49':
      PIN_NUMBER='(0,0,0,0,0,0,0,0,0,0,0,0,0,0,0,0,0,0,0,0,0,0,0,0,0,0,BK49,0,0,0,0,0,0,0,0,0,0,0,0,0)';
      PINUSE='POWER';
      NO_LOAD_CHECK='Both';
      NO_IO_CHECK='Both';
      NO_ASSERT_CHECK='TRUE';
      NO_DIR_CHECK='TRUE';
      ALLOW_CONNECT='TRUE';
    'VDD_11_S3_BL23':
      PIN_NUMBER='(0,0,0,0,0,0,0,0,0,0,0,0,0,0,0,0,0,0,0,0,0,0,0,0,0,0,BL23,0,0,0,0,0,0,0,0,0,0,0,0,0)';
      PINUSE='POWER';
      NO_LOAD_CHECK='Both';
      NO_IO_CHECK='Both';
      NO_ASSERT_CHECK='TRUE';
      NO_DIR_CHECK='TRUE';
      ALLOW_CONNECT='TRUE';
    'VDD_11_S3_BL25':
      PIN_NUMBER='(0,0,0,0,0,0,0,0,0,0,0,0,0,0,0,0,0,0,0,0,0,0,0,0,0,0,BL25,0,0,0,0,0,0,0,0,0,0,0,0,0)';
      PINUSE='POWER';
      NO_LOAD_CHECK='Both';
      NO_IO_CHECK='Both';
      NO_ASSERT_CHECK='TRUE';
      NO_DIR_CHECK='TRUE';
      ALLOW_CONNECT='TRUE';
    'VDD_11_S3_BL27':
      PIN_NUMBER='(0,0,0,0,0,0,0,0,0,0,0,0,0,0,0,0,0,0,0,0,0,0,0,0,0,0,BL27,0,0,0,0,0,0,0,0,0,0,0,0,0)';
      PINUSE='POWER';
      NO_LOAD_CHECK='Both';
      NO_IO_CHECK='Both';
      NO_ASSERT_CHECK='TRUE';
      NO_DIR_CHECK='TRUE';
      ALLOW_CONNECT='TRUE';
    'VDD_11_S3_BL48':
      PIN_NUMBER='(0,0,0,0,0,0,0,0,0,0,0,0,0,0,0,0,0,0,0,0,0,0,0,0,0,0,BL48,0,0,0,0,0,0,0,0,0,0,0,0,0)';
      PINUSE='POWER';
      NO_LOAD_CHECK='Both';
      NO_IO_CHECK='Both';
      NO_ASSERT_CHECK='TRUE';
      NO_DIR_CHECK='TRUE';
      ALLOW_CONNECT='TRUE';
    'VDD_11_S3_BM12':
      PIN_NUMBER='(0,0,0,0,0,0,0,0,0,0,0,0,0,0,0,0,0,0,0,0,0,0,0,0,0,0,BM12,0,0,0,0,0,0,0,0,0,0,0,0,0)';
      PINUSE='POWER';
      NO_LOAD_CHECK='Both';
      NO_IO_CHECK='Both';
      NO_ASSERT_CHECK='TRUE';
      NO_DIR_CHECK='TRUE';
      ALLOW_CONNECT='TRUE';
    'VDD_11_S3_BM19':
      PIN_NUMBER='(0,0,0,0,0,0,0,0,0,0,0,0,0,0,0,0,0,0,0,0,0,0,0,0,0,0,BM19,0,0,0,0,0,0,0,0,0,0,0,0,0)';
      PINUSE='POWER';
      NO_LOAD_CHECK='Both';
      NO_IO_CHECK='Both';
      NO_ASSERT_CHECK='TRUE';
      NO_DIR_CHECK='TRUE';
      ALLOW_CONNECT='TRUE';
    'VDD_11_S3_BM22':
      PIN_NUMBER='(0,0,0,0,0,0,0,0,0,0,0,0,0,0,0,0,0,0,0,0,0,0,0,0,0,0,BM22,0,0,0,0,0,0,0,0,0,0,0,0,0)';
      PINUSE='POWER';
      NO_LOAD_CHECK='Both';
      NO_IO_CHECK='Both';
      NO_ASSERT_CHECK='TRUE';
      NO_DIR_CHECK='TRUE';
      ALLOW_CONNECT='TRUE';
    'VDD_11_S3_BM24':
      PIN_NUMBER='(0,0,0,0,0,0,0,0,0,0,0,0,0,0,0,0,0,0,0,0,0,0,0,0,0,0,BM24,0,0,0,0,0,0,0,0,0,0,0,0,0)';
      PINUSE='POWER';
      NO_LOAD_CHECK='Both';
      NO_IO_CHECK='Both';
      NO_ASSERT_CHECK='TRUE';
      NO_DIR_CHECK='TRUE';
      ALLOW_CONNECT='TRUE';
    'VDD_11_S3_BM26':
      PIN_NUMBER='(0,0,0,0,0,0,0,0,0,0,0,0,0,0,0,0,0,0,0,0,0,0,0,0,0,0,BM26,0,0,0,0,0,0,0,0,0,0,0,0,0)';
      PINUSE='POWER';
      NO_LOAD_CHECK='Both';
      NO_IO_CHECK='Both';
      NO_ASSERT_CHECK='TRUE';
      NO_DIR_CHECK='TRUE';
      ALLOW_CONNECT='TRUE';
    'VDD_11_S3_BM28':
      PIN_NUMBER='(0,0,0,0,0,0,0,0,0,0,0,0,0,0,0,0,0,0,0,0,0,0,0,0,0,0,BM28,0,0,0,0,0,0,0,0,0,0,0,0,0)';
      PINUSE='POWER';
      NO_LOAD_CHECK='Both';
      NO_IO_CHECK='Both';
      NO_ASSERT_CHECK='TRUE';
      NO_DIR_CHECK='TRUE';
      ALLOW_CONNECT='TRUE';
    'VDD_11_S3_BM30':
      PIN_NUMBER='(0,0,0,0,0,0,0,0,0,0,0,0,0,0,0,0,0,0,0,0,0,0,0,0,0,0,BM30,0,0,0,0,0,0,0,0,0,0,0,0,0)';
      PINUSE='POWER';
      NO_LOAD_CHECK='Both';
      NO_IO_CHECK='Both';
      NO_ASSERT_CHECK='TRUE';
      NO_DIR_CHECK='TRUE';
      ALLOW_CONNECT='TRUE';
    'VDD_11_S3_BM32':
      PIN_NUMBER='(0,0,0,0,0,0,0,0,0,0,0,0,0,0,0,0,0,0,0,0,0,0,0,0,0,0,BM32,0,0,0,0,0,0,0,0,0,0,0,0,0)';
      PINUSE='POWER';
      NO_LOAD_CHECK='Both';
      NO_IO_CHECK='Both';
      NO_ASSERT_CHECK='TRUE';
      NO_DIR_CHECK='TRUE';
      ALLOW_CONNECT='TRUE';
    'VDD_11_S3_BM34':
      PIN_NUMBER='(0,0,0,0,0,0,0,0,0,0,0,0,0,0,0,0,0,0,0,0,0,0,0,0,0,0,BM34,0,0,0,0,0,0,0,0,0,0,0,0,0)';
      PINUSE='POWER';
      NO_LOAD_CHECK='Both';
      NO_IO_CHECK='Both';
      NO_ASSERT_CHECK='TRUE';
      NO_DIR_CHECK='TRUE';
      ALLOW_CONNECT='TRUE';
    'VDD_11_S3_BM36':
      PIN_NUMBER='(0,0,0,0,0,0,0,0,0,0,0,0,0,0,0,0,0,0,0,0,0,0,0,0,0,0,BM36,0,0,0,0,0,0,0,0,0,0,0,0,0)';
      PINUSE='POWER';
      NO_LOAD_CHECK='Both';
      NO_IO_CHECK='Both';
      NO_ASSERT_CHECK='TRUE';
      NO_DIR_CHECK='TRUE';
      ALLOW_CONNECT='TRUE';
    'VDD_11_S3_BM39':
      PIN_NUMBER='(0,0,0,0,0,0,0,0,0,0,0,0,0,0,0,0,0,0,0,0,0,0,0,0,0,0,BM39,0,0,0,0,0,0,0,0,0,0,0,0,0)';
      PINUSE='POWER';
      NO_LOAD_CHECK='Both';
      NO_IO_CHECK='Both';
      NO_ASSERT_CHECK='TRUE';
      NO_DIR_CHECK='TRUE';
      ALLOW_CONNECT='TRUE';
    'VDD_11_S3_BM41':
      PIN_NUMBER='(0,0,0,0,0,0,0,0,0,0,0,0,0,0,0,0,0,0,0,0,0,0,0,0,0,0,BM41,0,0,0,0,0,0,0,0,0,0,0,0,0)';
      PINUSE='POWER';
      NO_LOAD_CHECK='Both';
      NO_IO_CHECK='Both';
      NO_ASSERT_CHECK='TRUE';
      NO_DIR_CHECK='TRUE';
      ALLOW_CONNECT='TRUE';
    'VDD_11_S3_BM43':
      PIN_NUMBER='(0,0,0,0,0,0,0,0,0,0,0,0,0,0,0,0,0,0,0,0,0,0,0,0,0,0,BM43,0,0,0,0,0,0,0,0,0,0,0,0,0)';
      PINUSE='POWER';
      NO_LOAD_CHECK='Both';
      NO_IO_CHECK='Both';
      NO_ASSERT_CHECK='TRUE';
      NO_DIR_CHECK='TRUE';
      ALLOW_CONNECT='TRUE';
    'VDD_11_S3_BM45':
      PIN_NUMBER='(0,0,0,0,0,0,0,0,0,0,0,0,0,0,0,0,0,0,0,0,0,0,0,0,0,0,BM45,0,0,0,0,0,0,0,0,0,0,0,0,0)';
      PINUSE='POWER';
      NO_LOAD_CHECK='Both';
      NO_IO_CHECK='Both';
      NO_ASSERT_CHECK='TRUE';
      NO_DIR_CHECK='TRUE';
      ALLOW_CONNECT='TRUE';
    'VDD_11_S3_BM47':
      PIN_NUMBER='(0,0,0,0,0,0,0,0,0,0,0,0,0,0,0,0,0,0,0,0,0,0,0,0,0,0,BM47,0,0,0,0,0,0,0,0,0,0,0,0,0)';
      PINUSE='POWER';
      NO_LOAD_CHECK='Both';
      NO_IO_CHECK='Both';
      NO_ASSERT_CHECK='TRUE';
      NO_DIR_CHECK='TRUE';
      ALLOW_CONNECT='TRUE';
    'VDD_11_S3_BM49':
      PIN_NUMBER='(0,0,0,0,0,0,0,0,0,0,0,0,0,0,0,0,0,0,0,0,0,0,0,0,0,0,BM49,0,0,0,0,0,0,0,0,0,0,0,0,0)';
      PINUSE='POWER';
      NO_LOAD_CHECK='Both';
      NO_IO_CHECK='Both';
      NO_ASSERT_CHECK='TRUE';
      NO_DIR_CHECK='TRUE';
      ALLOW_CONNECT='TRUE';
    'VDD_11_S3_BN25':
      PIN_NUMBER='(0,0,0,0,0,0,0,0,0,0,0,0,0,0,0,0,0,0,0,0,0,0,0,0,0,0,BN25,0,0,0,0,0,0,0,0,0,0,0,0,0)';
      PINUSE='POWER';
      NO_LOAD_CHECK='Both';
      NO_IO_CHECK='Both';
      NO_ASSERT_CHECK='TRUE';
      NO_DIR_CHECK='TRUE';
      ALLOW_CONNECT='TRUE';
    'VDD_11_S3_BN29':
      PIN_NUMBER='(0,0,0,0,0,0,0,0,0,0,0,0,0,0,0,0,0,0,0,0,0,0,0,0,0,0,BN29,0,0,0,0,0,0,0,0,0,0,0,0,0)';
      PINUSE='POWER';
      NO_LOAD_CHECK='Both';
      NO_IO_CHECK='Both';
      NO_ASSERT_CHECK='TRUE';
      NO_DIR_CHECK='TRUE';
      ALLOW_CONNECT='TRUE';
    'VDD_11_S3_BN33':
      PIN_NUMBER='(0,0,0,0,0,0,0,0,0,0,0,0,0,0,0,0,0,0,0,0,0,0,0,0,0,0,BN33,0,0,0,0,0,0,0,0,0,0,0,0,0)';
      PINUSE='POWER';
      NO_LOAD_CHECK='Both';
      NO_IO_CHECK='Both';
      NO_ASSERT_CHECK='TRUE';
      NO_DIR_CHECK='TRUE';
      ALLOW_CONNECT='TRUE';
    'VDD_11_S3_BN40':
      PIN_NUMBER='(0,0,0,0,0,0,0,0,0,0,0,0,0,0,0,0,0,0,0,0,0,0,0,0,0,0,BN40,0,0,0,0,0,0,0,0,0,0,0,0,0)';
      PINUSE='POWER';
      NO_LOAD_CHECK='Both';
      NO_IO_CHECK='Both';
      NO_ASSERT_CHECK='TRUE';
      NO_DIR_CHECK='TRUE';
      ALLOW_CONNECT='TRUE';
    'VDD_11_S3_BN44':
      PIN_NUMBER='(0,0,0,0,0,0,0,0,0,0,0,0,0,0,0,0,0,0,0,0,0,0,0,0,0,0,BN44,0,0,0,0,0,0,0,0,0,0,0,0,0)';
      PINUSE='POWER';
      NO_LOAD_CHECK='Both';
      NO_IO_CHECK='Both';
      NO_ASSERT_CHECK='TRUE';
      NO_DIR_CHECK='TRUE';
      ALLOW_CONNECT='TRUE';
    'VDD_11_S3_BN48':
      PIN_NUMBER='(0,0,0,0,0,0,0,0,0,0,0,0,0,0,0,0,0,0,0,0,0,0,0,0,0,0,BN48,0,0,0,0,0,0,0,0,0,0,0,0,0)';
      PINUSE='POWER';
      NO_LOAD_CHECK='Both';
      NO_IO_CHECK='Both';
      NO_ASSERT_CHECK='TRUE';
      NO_DIR_CHECK='TRUE';
      ALLOW_CONNECT='TRUE';
    'VDD_11_S3_BP22':
      PIN_NUMBER='(0,0,0,0,0,0,0,0,0,0,0,0,0,0,0,0,0,0,0,0,0,0,0,0,0,0,BP22,0,0,0,0,0,0,0,0,0,0,0,0,0)';
      PINUSE='POWER';
      NO_LOAD_CHECK='Both';
      NO_IO_CHECK='Both';
      NO_ASSERT_CHECK='TRUE';
      NO_DIR_CHECK='TRUE';
      ALLOW_CONNECT='TRUE';
    'VDD_11_S3_BR4':
      PIN_NUMBER='(0,0,0,0,0,0,0,0,0,0,0,0,0,0,0,0,0,0,0,0,0,0,0,0,0,0,BR4,0,0,0,0,0,0,0,0,0,0,0,0,0)';
      PINUSE='POWER';
      NO_LOAD_CHECK='Both';
      NO_IO_CHECK='Both';
      NO_ASSERT_CHECK='TRUE';
      NO_DIR_CHECK='TRUE';
      ALLOW_CONNECT='TRUE';
    'VDD_11_S3_BR11':
      PIN_NUMBER='(0,0,0,0,0,0,0,0,0,0,0,0,0,0,0,0,0,0,0,0,0,0,0,0,0,0,BR11,0,0,0,0,0,0,0,0,0,0,0,0,0)';
      PINUSE='POWER';
      NO_LOAD_CHECK='Both';
      NO_IO_CHECK='Both';
      NO_ASSERT_CHECK='TRUE';
      NO_DIR_CHECK='TRUE';
      ALLOW_CONNECT='TRUE';
    'VDD_11_S3_BR18':
      PIN_NUMBER='(0,0,0,0,0,0,0,0,0,0,0,0,0,0,0,0,0,0,0,0,0,0,0,0,0,0,BR18,0,0,0,0,0,0,0,0,0,0,0,0,0)';
      PINUSE='POWER';
      NO_LOAD_CHECK='Both';
      NO_IO_CHECK='Both';
      NO_ASSERT_CHECK='TRUE';
      NO_DIR_CHECK='TRUE';
      ALLOW_CONNECT='TRUE';
    'VDD_11_S3_BV5':
      PIN_NUMBER='(0,0,0,0,0,0,0,0,0,0,0,0,0,0,0,0,0,0,0,0,0,0,0,0,0,0,BV5,0,0,0,0,0,0,0,0,0,0,0,0,0)';
      PINUSE='POWER';
      NO_LOAD_CHECK='Both';
      NO_IO_CHECK='Both';
      NO_ASSERT_CHECK='TRUE';
      NO_DIR_CHECK='TRUE';
      ALLOW_CONNECT='TRUE';
    'VDD_11_S3_BV12':
      PIN_NUMBER='(0,0,0,0,0,0,0,0,0,0,0,0,0,0,0,0,0,0,0,0,0,0,0,0,0,0,BV12,0,0,0,0,0,0,0,0,0,0,0,0,0)';
      PINUSE='POWER';
      NO_LOAD_CHECK='Both';
      NO_IO_CHECK='Both';
      NO_ASSERT_CHECK='TRUE';
      NO_DIR_CHECK='TRUE';
      ALLOW_CONNECT='TRUE';
    'VDD_11_S3_BV19':
      PIN_NUMBER='(0,0,0,0,0,0,0,0,0,0,0,0,0,0,0,0,0,0,0,0,0,0,0,0,0,0,BV19,0,0,0,0,0,0,0,0,0,0,0,0,0)';
      PINUSE='POWER';
      NO_LOAD_CHECK='Both';
      NO_IO_CHECK='Both';
      NO_ASSERT_CHECK='TRUE';
      NO_DIR_CHECK='TRUE';
      ALLOW_CONNECT='TRUE';
    'VDD_11_S3_BV22':
      PIN_NUMBER='(0,0,0,0,0,0,0,0,0,0,0,0,0,0,0,0,0,0,0,0,0,0,0,0,0,0,BV22,0,0,0,0,0,0,0,0,0,0,0,0,0)';
      PINUSE='POWER';
      NO_LOAD_CHECK='Both';
      NO_IO_CHECK='Both';
      NO_ASSERT_CHECK='TRUE';
      NO_DIR_CHECK='TRUE';
      ALLOW_CONNECT='TRUE';
    'VDD_11_S3_CA4':
      PIN_NUMBER='(0,0,0,0,0,0,0,0,0,0,0,0,0,0,0,0,0,0,0,0,0,0,0,0,0,0,CA4,0,0,0,0,0,0,0,0,0,0,0,0,0)';
      PINUSE='POWER';
      NO_LOAD_CHECK='Both';
      NO_IO_CHECK='Both';
      NO_ASSERT_CHECK='TRUE';
      NO_DIR_CHECK='TRUE';
      ALLOW_CONNECT='TRUE';
    'VDD_11_S3_CA11':
      PIN_NUMBER='(0,0,0,0,0,0,0,0,0,0,0,0,0,0,0,0,0,0,0,0,0,0,0,0,0,0,CA11,0,0,0,0,0,0,0,0,0,0,0,0,0)';
      PINUSE='POWER';
      NO_LOAD_CHECK='Both';
      NO_IO_CHECK='Both';
      NO_ASSERT_CHECK='TRUE';
      NO_DIR_CHECK='TRUE';
      ALLOW_CONNECT='TRUE';
    'VDD_11_S3_CA18':
      PIN_NUMBER='(0,0,0,0,0,0,0,0,0,0,0,0,0,0,0,0,0,0,0,0,0,0,0,0,0,0,CA18,0,0,0,0,0,0,0,0,0,0,0,0,0)';
      PINUSE='POWER';
      NO_LOAD_CHECK='Both';
      NO_IO_CHECK='Both';
      NO_ASSERT_CHECK='TRUE';
      NO_DIR_CHECK='TRUE';
      ALLOW_CONNECT='TRUE';
    'VDD_11_S3_CB22':
      PIN_NUMBER='(0,0,0,0,0,0,0,0,0,0,0,0,0,0,0,0,0,0,0,0,0,0,0,0,0,0,CB22,0,0,0,0,0,0,0,0,0,0,0,0,0)';
      PINUSE='POWER';
      NO_LOAD_CHECK='Both';
      NO_IO_CHECK='Both';
      NO_ASSERT_CHECK='TRUE';
      NO_DIR_CHECK='TRUE';
      ALLOW_CONNECT='TRUE';
    'VDD_11_S3_CD5':
      PIN_NUMBER='(0,0,0,0,0,0,0,0,0,0,0,0,0,0,0,0,0,0,0,0,0,0,0,0,0,0,CD5,0,0,0,0,0,0,0,0,0,0,0,0,0)';
      PINUSE='POWER';
      NO_LOAD_CHECK='Both';
      NO_IO_CHECK='Both';
      NO_ASSERT_CHECK='TRUE';
      NO_DIR_CHECK='TRUE';
      ALLOW_CONNECT='TRUE';
    'VDD_11_S3_CD12':
      PIN_NUMBER='(0,0,0,0,0,0,0,0,0,0,0,0,0,0,0,0,0,0,0,0,0,0,0,0,0,0,CD12,0,0,0,0,0,0,0,0,0,0,0,0,0)';
      PINUSE='POWER';
      NO_LOAD_CHECK='Both';
      NO_IO_CHECK='Both';
      NO_ASSERT_CHECK='TRUE';
      NO_DIR_CHECK='TRUE';
      ALLOW_CONNECT='TRUE';
    'VDD_11_S3_CD19':
      PIN_NUMBER='(0,0,0,0,0,0,0,0,0,0,0,0,0,0,0,0,0,0,0,0,0,0,0,0,0,0,CD19,0,0,0,0,0,0,0,0,0,0,0,0,0)';
      PINUSE='POWER';
      NO_LOAD_CHECK='Both';
      NO_IO_CHECK='Both';
      NO_ASSERT_CHECK='TRUE';
      NO_DIR_CHECK='TRUE';
      ALLOW_CONNECT='TRUE';
    'VDD_11_S3_CF22':
      PIN_NUMBER='(0,0,0,0,0,0,0,0,0,0,0,0,0,0,0,0,0,0,0,0,0,0,0,0,0,0,CF22,0,0,0,0,0,0,0,0,0,0,0,0,0)';
      PINUSE='POWER';
      NO_LOAD_CHECK='Both';
      NO_IO_CHECK='Both';
      NO_ASSERT_CHECK='TRUE';
      NO_DIR_CHECK='TRUE';
      ALLOW_CONNECT='TRUE';
    'VDD_11_S3_CG4':
      PIN_NUMBER='(0,0,0,0,0,0,0,0,0,0,0,0,0,0,0,0,0,0,0,0,0,0,0,0,0,0,CG4,0,0,0,0,0,0,0,0,0,0,0,0,0)';
      PINUSE='POWER';
      NO_LOAD_CHECK='Both';
      NO_IO_CHECK='Both';
      NO_ASSERT_CHECK='TRUE';
      NO_DIR_CHECK='TRUE';
      ALLOW_CONNECT='TRUE';
    'VDD_11_S3_CG11':
      PIN_NUMBER='(0,0,0,0,0,0,0,0,0,0,0,0,0,0,0,0,0,0,0,0,0,0,0,0,0,0,CG11,0,0,0,0,0,0,0,0,0,0,0,0,0)';
      PINUSE='POWER';
      NO_LOAD_CHECK='Both';
      NO_IO_CHECK='Both';
      NO_ASSERT_CHECK='TRUE';
      NO_DIR_CHECK='TRUE';
      ALLOW_CONNECT='TRUE';
    'VDD_11_S3_CG18':
      PIN_NUMBER='(0,0,0,0,0,0,0,0,0,0,0,0,0,0,0,0,0,0,0,0,0,0,0,0,0,0,CG18,0,0,0,0,0,0,0,0,0,0,0,0,0)';
      PINUSE='POWER';
      NO_LOAD_CHECK='Both';
      NO_IO_CHECK='Both';
      NO_ASSERT_CHECK='TRUE';
      NO_DIR_CHECK='TRUE';
      ALLOW_CONNECT='TRUE';
    'VDD_11_S3_CJ22':
      PIN_NUMBER='(0,0,0,0,0,0,0,0,0,0,0,0,0,0,0,0,0,0,0,0,0,0,0,0,0,0,CJ22,0,0,0,0,0,0,0,0,0,0,0,0,0)';
      PINUSE='POWER';
      NO_LOAD_CHECK='Both';
      NO_IO_CHECK='Both';
      NO_ASSERT_CHECK='TRUE';
      NO_DIR_CHECK='TRUE';
      ALLOW_CONNECT='TRUE';
    'VDD_11_S3_CK5':
      PIN_NUMBER='(0,0,0,0,0,0,0,0,0,0,0,0,0,0,0,0,0,0,0,0,0,0,0,0,0,0,CK5,0,0,0,0,0,0,0,0,0,0,0,0,0)';
      PINUSE='POWER';
      NO_LOAD_CHECK='Both';
      NO_IO_CHECK='Both';
      NO_ASSERT_CHECK='TRUE';
      NO_DIR_CHECK='TRUE';
      ALLOW_CONNECT='TRUE';
    'VDD_11_S3_CK12':
      PIN_NUMBER='(0,0,0,0,0,0,0,0,0,0,0,0,0,0,0,0,0,0,0,0,0,0,0,0,0,0,CK12,0,0,0,0,0,0,0,0,0,0,0,0,0)';
      PINUSE='POWER';
      NO_LOAD_CHECK='Both';
      NO_IO_CHECK='Both';
      NO_ASSERT_CHECK='TRUE';
      NO_DIR_CHECK='TRUE';
      ALLOW_CONNECT='TRUE';
    'VDD_11_S3_CK19':
      PIN_NUMBER='(0,0,0,0,0,0,0,0,0,0,0,0,0,0,0,0,0,0,0,0,0,0,0,0,0,0,CK19,0,0,0,0,0,0,0,0,0,0,0,0,0)';
      PINUSE='POWER';
      NO_LOAD_CHECK='Both';
      NO_IO_CHECK='Both';
      NO_ASSERT_CHECK='TRUE';
      NO_DIR_CHECK='TRUE';
      ALLOW_CONNECT='TRUE';
    'VDD_11_S3_CM22':
      PIN_NUMBER='(0,0,0,0,0,0,0,0,0,0,0,0,0,0,0,0,0,0,0,0,0,0,0,0,0,0,CM22,0,0,0,0,0,0,0,0,0,0,0,0,0)';
      PINUSE='POWER';
      NO_LOAD_CHECK='Both';
      NO_IO_CHECK='Both';
      NO_ASSERT_CHECK='TRUE';
      NO_DIR_CHECK='TRUE';
      ALLOW_CONNECT='TRUE';
    'VDD_11_S3_CN4':
      PIN_NUMBER='(0,0,0,0,0,0,0,0,0,0,0,0,0,0,0,0,0,0,0,0,0,0,0,0,0,0,CN4,0,0,0,0,0,0,0,0,0,0,0,0,0)';
      PINUSE='POWER';
      NO_LOAD_CHECK='Both';
      NO_IO_CHECK='Both';
      NO_ASSERT_CHECK='TRUE';
      NO_DIR_CHECK='TRUE';
      ALLOW_CONNECT='TRUE';
    'VDD_11_S3_CN11':
      PIN_NUMBER='(0,0,0,0,0,0,0,0,0,0,0,0,0,0,0,0,0,0,0,0,0,0,0,0,0,0,CN11,0,0,0,0,0,0,0,0,0,0,0,0,0)';
      PINUSE='POWER';
      NO_LOAD_CHECK='Both';
      NO_IO_CHECK='Both';
      NO_ASSERT_CHECK='TRUE';
      NO_DIR_CHECK='TRUE';
      ALLOW_CONNECT='TRUE';
    'VDD_11_S3_CN18':
      PIN_NUMBER='(0,0,0,0,0,0,0,0,0,0,0,0,0,0,0,0,0,0,0,0,0,0,0,0,0,0,CN18,0,0,0,0,0,0,0,0,0,0,0,0,0)';
      PINUSE='POWER';
      NO_LOAD_CHECK='Both';
      NO_IO_CHECK='Both';
      NO_ASSERT_CHECK='TRUE';
      NO_DIR_CHECK='TRUE';
      ALLOW_CONNECT='TRUE';
    'VDD_11_S3_CT5':
      PIN_NUMBER='(0,0,0,0,0,0,0,0,0,0,0,0,0,0,0,0,0,0,0,0,0,0,0,0,0,0,CT5,0,0,0,0,0,0,0,0,0,0,0,0,0)';
      PINUSE='POWER';
      NO_LOAD_CHECK='Both';
      NO_IO_CHECK='Both';
      NO_ASSERT_CHECK='TRUE';
      NO_DIR_CHECK='TRUE';
      ALLOW_CONNECT='TRUE';
    'VDD_18_S5_AU54':
      PIN_NUMBER='(0,0,0,0,0,0,0,0,0,0,0,0,0,0,0,0,0,0,0,0,0,0,0,0,0,0,AU54,0,0,0,0,0,0,0,0,0,0,0,0,0)';
      PINUSE='POWER';
      NO_LOAD_CHECK='Both';
      NO_IO_CHECK='Both';
      NO_ASSERT_CHECK='TRUE';
      NO_DIR_CHECK='TRUE';
      ALLOW_CONNECT='TRUE';
    'VDD_18_S5_AR52':
      PIN_NUMBER='(0,0,0,0,0,0,0,0,0,0,0,0,0,0,0,0,0,0,0,0,0,0,0,0,0,0,AR52,0,0,0,0,0,0,0,0,0,0,0,0,0)';
      PINUSE='POWER';
      NO_LOAD_CHECK='Both';
      NO_IO_CHECK='Both';
      NO_ASSERT_CHECK='TRUE';
      NO_DIR_CHECK='TRUE';
      ALLOW_CONNECT='TRUE';
    'VDD_18_S5_AR54':
      PIN_NUMBER='(0,0,0,0,0,0,0,0,0,0,0,0,0,0,0,0,0,0,0,0,0,0,0,0,0,0,AR54,0,0,0,0,0,0,0,0,0,0,0,0,0)';
      PINUSE='POWER';
      NO_LOAD_CHECK='Both';
      NO_IO_CHECK='Both';
      NO_ASSERT_CHECK='TRUE';
      NO_DIR_CHECK='TRUE';
      ALLOW_CONNECT='TRUE';
    'VDD_18_S5_AT51':
      PIN_NUMBER='(0,0,0,0,0,0,0,0,0,0,0,0,0,0,0,0,0,0,0,0,0,0,0,0,0,0,AT51,0,0,0,0,0,0,0,0,0,0,0,0,0)';
      PINUSE='POWER';
      NO_LOAD_CHECK='Both';
      NO_IO_CHECK='Both';
      NO_ASSERT_CHECK='TRUE';
      NO_DIR_CHECK='TRUE';
      ALLOW_CONNECT='TRUE';
    'VDD_18_S5_AT53':
      PIN_NUMBER='(0,0,0,0,0,0,0,0,0,0,0,0,0,0,0,0,0,0,0,0,0,0,0,0,0,0,AT53,0,0,0,0,0,0,0,0,0,0,0,0,0)';
      PINUSE='POWER';
      NO_LOAD_CHECK='Both';
      NO_IO_CHECK='Both';
      NO_ASSERT_CHECK='TRUE';
      NO_DIR_CHECK='TRUE';
      ALLOW_CONNECT='TRUE';
    'VDD_18_S5_AU50':
      PIN_NUMBER='(0,0,0,0,0,0,0,0,0,0,0,0,0,0,0,0,0,0,0,0,0,0,0,0,0,0,AU50,0,0,0,0,0,0,0,0,0,0,0,0,0)';
      PINUSE='POWER';
      NO_LOAD_CHECK='Both';
      NO_IO_CHECK='Both';
      NO_ASSERT_CHECK='TRUE';
      NO_DIR_CHECK='TRUE';
      ALLOW_CONNECT='TRUE';
    'VDD_18_S5_AU52':
      PIN_NUMBER='(0,0,0,0,0,0,0,0,0,0,0,0,0,0,0,0,0,0,0,0,0,0,0,0,0,0,AU52,0,0,0,0,0,0,0,0,0,0,0,0,0)';
      PINUSE='POWER';
      NO_LOAD_CHECK='Both';
      NO_IO_CHECK='Both';
      NO_ASSERT_CHECK='TRUE';
      NO_DIR_CHECK='TRUE';
      ALLOW_CONNECT='TRUE';
    'VDD_18_S5_AV49':
      PIN_NUMBER='(0,0,0,0,0,0,0,0,0,0,0,0,0,0,0,0,0,0,0,0,0,0,0,0,0,0,AV49,0,0,0,0,0,0,0,0,0,0,0,0,0)';
      PINUSE='POWER';
      NO_LOAD_CHECK='Both';
      NO_IO_CHECK='Both';
      NO_ASSERT_CHECK='TRUE';
      NO_DIR_CHECK='TRUE';
      ALLOW_CONNECT='TRUE';
    'VDD_18_S5_AV51':
      PIN_NUMBER='(0,0,0,0,0,0,0,0,0,0,0,0,0,0,0,0,0,0,0,0,0,0,0,0,0,0,AV51,0,0,0,0,0,0,0,0,0,0,0,0,0)';
      PINUSE='POWER';
      NO_LOAD_CHECK='Both';
      NO_IO_CHECK='Both';
      NO_ASSERT_CHECK='TRUE';
      NO_DIR_CHECK='TRUE';
      ALLOW_CONNECT='TRUE';
    'VDD_18_S5_AV53':
      PIN_NUMBER='(0,0,0,0,0,0,0,0,0,0,0,0,0,0,0,0,0,0,0,0,0,0,0,0,0,0,AV53,0,0,0,0,0,0,0,0,0,0,0,0,0)';
      PINUSE='POWER';
      NO_LOAD_CHECK='Both';
      NO_IO_CHECK='Both';
      NO_ASSERT_CHECK='TRUE';
      NO_DIR_CHECK='TRUE';
      ALLOW_CONNECT='TRUE';
    'VDD_18_S5_AW50':
      PIN_NUMBER='(0,0,0,0,0,0,0,0,0,0,0,0,0,0,0,0,0,0,0,0,0,0,0,0,0,0,AW50,0,0,0,0,0,0,0,0,0,0,0,0,0)';
      PINUSE='POWER';
      NO_LOAD_CHECK='Both';
      NO_IO_CHECK='Both';
      NO_ASSERT_CHECK='TRUE';
      NO_DIR_CHECK='TRUE';
      ALLOW_CONNECT='TRUE';
    'VDD_18_S5_BC52':
      PIN_NUMBER='(0,0,0,0,0,0,0,0,0,0,0,0,0,0,0,0,0,0,0,0,0,0,0,0,0,0,BC52,0,0,0,0,0,0,0,0,0,0,0,0,0)';
      PINUSE='POWER';
      NO_LOAD_CHECK='Both';
      NO_IO_CHECK='Both';
      NO_ASSERT_CHECK='TRUE';
      NO_DIR_CHECK='TRUE';
      ALLOW_CONNECT='TRUE';
    'VDD_18_S5_BC54':
      PIN_NUMBER='(0,0,0,0,0,0,0,0,0,0,0,0,0,0,0,0,0,0,0,0,0,0,0,0,0,0,BC54,0,0,0,0,0,0,0,0,0,0,0,0,0)';
      PINUSE='POWER';
      NO_LOAD_CHECK='Both';
      NO_IO_CHECK='Both';
      NO_ASSERT_CHECK='TRUE';
      NO_DIR_CHECK='TRUE';
      ALLOW_CONNECT='TRUE';
    'VDD_18_S5_AW52':
      PIN_NUMBER='(0,0,0,0,0,0,0,0,0,0,0,0,0,0,0,0,0,0,0,0,0,0,0,0,0,0,AW52,0,0,0,0,0,0,0,0,0,0,0,0,0)';
      PINUSE='POWER';
      NO_LOAD_CHECK='Both';
      NO_IO_CHECK='Both';
      NO_ASSERT_CHECK='TRUE';
      NO_DIR_CHECK='TRUE';
      ALLOW_CONNECT='TRUE';
    'VDD_18_S5_AW54':
      PIN_NUMBER='(0,0,0,0,0,0,0,0,0,0,0,0,0,0,0,0,0,0,0,0,0,0,0,0,0,0,AW54,0,0,0,0,0,0,0,0,0,0,0,0,0)';
      PINUSE='POWER';
      NO_LOAD_CHECK='Both';
      NO_IO_CHECK='Both';
      NO_ASSERT_CHECK='TRUE';
      NO_DIR_CHECK='TRUE';
      ALLOW_CONNECT='TRUE';
    'VDD_18_S5_AY51':
      PIN_NUMBER='(0,0,0,0,0,0,0,0,0,0,0,0,0,0,0,0,0,0,0,0,0,0,0,0,0,0,AY51,0,0,0,0,0,0,0,0,0,0,0,0,0)';
      PINUSE='POWER';
      NO_LOAD_CHECK='Both';
      NO_IO_CHECK='Both';
      NO_ASSERT_CHECK='TRUE';
      NO_DIR_CHECK='TRUE';
      ALLOW_CONNECT='TRUE';
    'VDD_18_S5_AY53':
      PIN_NUMBER='(0,0,0,0,0,0,0,0,0,0,0,0,0,0,0,0,0,0,0,0,0,0,0,0,0,0,AY53,0,0,0,0,0,0,0,0,0,0,0,0,0)';
      PINUSE='POWER';
      NO_LOAD_CHECK='Both';
      NO_IO_CHECK='Both';
      NO_ASSERT_CHECK='TRUE';
      NO_DIR_CHECK='TRUE';
      ALLOW_CONNECT='TRUE';
    'VDD_18_S5_BA50':
      PIN_NUMBER='(0,0,0,0,0,0,0,0,0,0,0,0,0,0,0,0,0,0,0,0,0,0,0,0,0,0,BA50,0,0,0,0,0,0,0,0,0,0,0,0,0)';
      PINUSE='POWER';
      NO_LOAD_CHECK='Both';
      NO_IO_CHECK='Both';
      NO_ASSERT_CHECK='TRUE';
      NO_DIR_CHECK='TRUE';
      ALLOW_CONNECT='TRUE';
    'VDD_18_S5_BA52':
      PIN_NUMBER='(0,0,0,0,0,0,0,0,0,0,0,0,0,0,0,0,0,0,0,0,0,0,0,0,0,0,BA52,0,0,0,0,0,0,0,0,0,0,0,0,0)';
      PINUSE='POWER';
      NO_LOAD_CHECK='Both';
      NO_IO_CHECK='Both';
      NO_ASSERT_CHECK='TRUE';
      NO_DIR_CHECK='TRUE';
      ALLOW_CONNECT='TRUE';
    'VDD_18_S5_BA54':
      PIN_NUMBER='(0,0,0,0,0,0,0,0,0,0,0,0,0,0,0,0,0,0,0,0,0,0,0,0,0,0,BA54,0,0,0,0,0,0,0,0,0,0,0,0,0)';
      PINUSE='POWER';
      NO_LOAD_CHECK='Both';
      NO_IO_CHECK='Both';
      NO_ASSERT_CHECK='TRUE';
      NO_DIR_CHECK='TRUE';
      ALLOW_CONNECT='TRUE';
    'VDD_18_S5_BB51':
      PIN_NUMBER='(0,0,0,0,0,0,0,0,0,0,0,0,0,0,0,0,0,0,0,0,0,0,0,0,0,0,BB51,0,0,0,0,0,0,0,0,0,0,0,0,0)';
      PINUSE='POWER';
      NO_LOAD_CHECK='Both';
      NO_IO_CHECK='Both';
      NO_ASSERT_CHECK='TRUE';
      NO_DIR_CHECK='TRUE';
      ALLOW_CONNECT='TRUE';
    'VDD_18_S5_BB53':
      PIN_NUMBER='(0,0,0,0,0,0,0,0,0,0,0,0,0,0,0,0,0,0,0,0,0,0,0,0,0,0,BB53,0,0,0,0,0,0,0,0,0,0,0,0,0)';
      PINUSE='POWER';
      NO_LOAD_CHECK='Both';
      NO_IO_CHECK='Both';
      NO_ASSERT_CHECK='TRUE';
      NO_DIR_CHECK='TRUE';
      ALLOW_CONNECT='TRUE';
    'VDD_11_S3_CT12':
      PIN_NUMBER='(0,0,0,0,0,0,0,0,0,0,0,0,0,0,0,0,0,0,0,0,0,0,0,0,0,0,CT12,0,0,0,0,0,0,0,0,0,0,0,0,0)';
      PINUSE='POWER';
      NO_LOAD_CHECK='Both';
      NO_IO_CHECK='Both';
      NO_ASSERT_CHECK='TRUE';
      NO_DIR_CHECK='TRUE';
      ALLOW_CONNECT='TRUE';
    'VDD_33_S5_BN52':
      PIN_NUMBER='(0,0,0,0,0,0,0,0,0,0,0,0,0,0,0,0,0,0,0,0,0,0,0,0,0,0,BN52,0,0,0,0,0,0,0,0,0,0,0,0,0)';
      PINUSE='POWER';
      NO_LOAD_CHECK='Both';
      NO_IO_CHECK='Both';
      NO_ASSERT_CHECK='TRUE';
      NO_DIR_CHECK='TRUE';
      ALLOW_CONNECT='TRUE';
    'VDD_33_S5_BP51':
      PIN_NUMBER='(0,0,0,0,0,0,0,0,0,0,0,0,0,0,0,0,0,0,0,0,0,0,0,0,0,0,BP51,0,0,0,0,0,0,0,0,0,0,0,0,0)';
      PINUSE='POWER';
      NO_LOAD_CHECK='Both';
      NO_IO_CHECK='Both';
      NO_ASSERT_CHECK='TRUE';
      NO_DIR_CHECK='TRUE';
      ALLOW_CONNECT='TRUE';
    'VDDIO_AUDIO':
      PIN_NUMBER='(0,0,0,0,0,0,0,0,0,0,0,0,0,0,0,0,0,0,0,0,0,0,0,0,0,0,BH27,0,0,0,0,0,0,0,0,0,0,0,0,0)';
      PINUSE='POWER';
      NO_LOAD_CHECK='Both';
      NO_IO_CHECK='Both';
      NO_ASSERT_CHECK='TRUE';
      NO_DIR_CHECK='TRUE';
      ALLOW_CONNECT='TRUE';
    'VDDBT_RTC_G':
      PIN_NUMBER='(0,0,0,0,0,0,0,0,0,0,0,0,0,0,0,0,0,0,0,0,0,0,0,0,0,0,BN23,0,0,0,0,0,0,0,0,0,0,0,0,0)';
      PINUSE='POWER';
      NO_LOAD_CHECK='Both';
      NO_IO_CHECK='Both';
      NO_ASSERT_CHECK='TRUE';
      NO_DIR_CHECK='TRUE';
      ALLOW_CONNECT='TRUE';
    'VDDIO_DG71':
      PIN_NUMBER='(0,0,0,0,0,0,0,0,0,0,0,0,0,0,0,0,0,0,0,0,0,0,0,0,0,0,DG71,0,0,0,0,0,0,0,0,0,0,0,0,0)';
      PINUSE='POWER';
      NO_LOAD_CHECK='Both';
      NO_IO_CHECK='Both';
      NO_ASSERT_CHECK='TRUE';
      NO_DIR_CHECK='TRUE';
      ALLOW_CONNECT='TRUE';
    'VDDIO_DG64':
      PIN_NUMBER='(0,0,0,0,0,0,0,0,0,0,0,0,0,0,0,0,0,0,0,0,0,0,0,0,0,0,DG64,0,0,0,0,0,0,0,0,0,0,0,0,0)';
      PINUSE='POWER';
      NO_LOAD_CHECK='Both';
      NO_IO_CHECK='Both';
      NO_ASSERT_CHECK='TRUE';
      NO_DIR_CHECK='TRUE';
      ALLOW_CONNECT='TRUE';
    'VDDIO_DE72':
      PIN_NUMBER='(0,0,0,0,0,0,0,0,0,0,0,0,0,0,0,0,0,0,0,0,0,0,0,0,0,0,DE72,0,0,0,0,0,0,0,0,0,0,0,0,0)';
      PINUSE='POWER';
      NO_LOAD_CHECK='Both';
      NO_IO_CHECK='Both';
      NO_ASSERT_CHECK='TRUE';
      NO_DIR_CHECK='TRUE';
      ALLOW_CONNECT='TRUE';
    'VDDIO_DE65':
      PIN_NUMBER='(0,0,0,0,0,0,0,0,0,0,0,0,0,0,0,0,0,0,0,0,0,0,0,0,0,0,DE65,0,0,0,0,0,0,0,0,0,0,0,0,0)';
      PINUSE='POWER';
      NO_LOAD_CHECK='Both';
      NO_IO_CHECK='Both';
      NO_ASSERT_CHECK='TRUE';
      NO_DIR_CHECK='TRUE';
      ALLOW_CONNECT='TRUE';
    'VDDIO_DE58':
      PIN_NUMBER='(0,0,0,0,0,0,0,0,0,0,0,0,0,0,0,0,0,0,0,0,0,0,0,0,0,0,DE58,0,0,0,0,0,0,0,0,0,0,0,0,0)';
      PINUSE='POWER';
      NO_LOAD_CHECK='Both';
      NO_IO_CHECK='Both';
      NO_ASSERT_CHECK='TRUE';
      NO_DIR_CHECK='TRUE';
      ALLOW_CONNECT='TRUE';
    'VDDIO_DB71':
      PIN_NUMBER='(0,0,0,0,0,0,0,0,0,0,0,0,0,0,0,0,0,0,0,0,0,0,0,0,0,0,DB71,0,0,0,0,0,0,0,0,0,0,0,0,0)';
      PINUSE='POWER';
      NO_LOAD_CHECK='Both';
      NO_IO_CHECK='Both';
      NO_ASSERT_CHECK='TRUE';
      NO_DIR_CHECK='TRUE';
      ALLOW_CONNECT='TRUE';
    'VDDIO_DB64':
      PIN_NUMBER='(0,0,0,0,0,0,0,0,0,0,0,0,0,0,0,0,0,0,0,0,0,0,0,0,0,0,DB64,0,0,0,0,0,0,0,0,0,0,0,0,0)';
      PINUSE='POWER';
      NO_LOAD_CHECK='Both';
      NO_IO_CHECK='Both';
      NO_ASSERT_CHECK='TRUE';
      NO_DIR_CHECK='TRUE';
      ALLOW_CONNECT='TRUE';
    'VDDIO_DB57':
      PIN_NUMBER='(0,0,0,0,0,0,0,0,0,0,0,0,0,0,0,0,0,0,0,0,0,0,0,0,0,0,DB57,0,0,0,0,0,0,0,0,0,0,0,0,0)';
      PINUSE='POWER';
      NO_LOAD_CHECK='Both';
      NO_IO_CHECK='Both';
      NO_ASSERT_CHECK='TRUE';
      NO_DIR_CHECK='TRUE';
      ALLOW_CONNECT='TRUE';
    'VDDIO_CY54':
      PIN_NUMBER='(0,0,0,0,0,0,0,0,0,0,0,0,0,0,0,0,0,0,0,0,0,0,0,0,0,0,CY54,0,0,0,0,0,0,0,0,0,0,0,0,0)';
      PINUSE='POWER';
      NO_LOAD_CHECK='Both';
      NO_IO_CHECK='Both';
      NO_ASSERT_CHECK='TRUE';
      NO_DIR_CHECK='TRUE';
      ALLOW_CONNECT='TRUE';
    'VDDIO_CW72':
      PIN_NUMBER='(0,0,0,0,0,0,0,0,0,0,0,0,0,0,0,0,0,0,0,0,0,0,0,0,0,0,CW72,0,0,0,0,0,0,0,0,0,0,0,0,0)';
      PINUSE='POWER';
      NO_LOAD_CHECK='Both';
      NO_IO_CHECK='Both';
      NO_ASSERT_CHECK='TRUE';
      NO_DIR_CHECK='TRUE';
      ALLOW_CONNECT='TRUE';
    'VDDIO_CW65':
      PIN_NUMBER='(0,0,0,0,0,0,0,0,0,0,0,0,0,0,0,0,0,0,0,0,0,0,0,0,0,0,CW65,0,0,0,0,0,0,0,0,0,0,0,0,0)';
      PINUSE='POWER';
      NO_LOAD_CHECK='Both';
      NO_IO_CHECK='Both';
      NO_ASSERT_CHECK='TRUE';
      NO_DIR_CHECK='TRUE';
      ALLOW_CONNECT='TRUE';
    'VDDIO_CW58':
      PIN_NUMBER='(0,0,0,0,0,0,0,0,0,0,0,0,0,0,0,0,0,0,0,0,0,0,0,0,0,0,CW58,0,0,0,0,0,0,0,0,0,0,0,0,0)';
      PINUSE='POWER';
      NO_LOAD_CHECK='Both';
      NO_IO_CHECK='Both';
      NO_ASSERT_CHECK='TRUE';
      NO_DIR_CHECK='TRUE';
      ALLOW_CONNECT='TRUE';
    'VDDIO_CT71':
      PIN_NUMBER='(0,0,0,0,0,0,0,0,0,0,0,0,0,0,0,0,0,0,0,0,0,0,0,0,0,0,CT71,0,0,0,0,0,0,0,0,0,0,0,0,0)';
      PINUSE='POWER';
      NO_LOAD_CHECK='Both';
      NO_IO_CHECK='Both';
      NO_ASSERT_CHECK='TRUE';
      NO_DIR_CHECK='TRUE';
      ALLOW_CONNECT='TRUE';
    'VDDIO_CT64':
      PIN_NUMBER='(0,0,0,0,0,0,0,0,0,0,0,0,0,0,0,0,0,0,0,0,0,0,0,0,0,0,CT64,0,0,0,0,0,0,0,0,0,0,0,0,0)';
      PINUSE='POWER';
      NO_LOAD_CHECK='Both';
      NO_IO_CHECK='Both';
      NO_ASSERT_CHECK='TRUE';
      NO_DIR_CHECK='TRUE';
      ALLOW_CONNECT='TRUE';
    'VDD_11_S3_DG5':
      PIN_NUMBER='(0,0,0,0,0,0,0,0,0,0,0,0,0,0,0,0,0,0,0,0,0,0,0,0,0,0,DG5,0,0,0,0,0,0,0,0,0,0,0,0,0)';
      PINUSE='POWER';
      NO_LOAD_CHECK='Both';
      NO_IO_CHECK='Both';
      NO_ASSERT_CHECK='TRUE';
      NO_DIR_CHECK='TRUE';
      ALLOW_CONNECT='TRUE';
    'VDD_11_S3_DE18':
      PIN_NUMBER='(0,0,0,0,0,0,0,0,0,0,0,0,0,0,0,0,0,0,0,0,0,0,0,0,0,0,DE18,0,0,0,0,0,0,0,0,0,0,0,0,0)';
      PINUSE='POWER';
      NO_LOAD_CHECK='Both';
      NO_IO_CHECK='Both';
      NO_ASSERT_CHECK='TRUE';
      NO_DIR_CHECK='TRUE';
      ALLOW_CONNECT='TRUE';
    'VDD_11_S3_DE11':
      PIN_NUMBER='(0,0,0,0,0,0,0,0,0,0,0,0,0,0,0,0,0,0,0,0,0,0,0,0,0,0,DE11,0,0,0,0,0,0,0,0,0,0,0,0,0)';
      PINUSE='POWER';
      NO_LOAD_CHECK='Both';
      NO_IO_CHECK='Both';
      NO_ASSERT_CHECK='TRUE';
      NO_DIR_CHECK='TRUE';
      ALLOW_CONNECT='TRUE';
    'VDD_11_S3_DE4':
      PIN_NUMBER='(0,0,0,0,0,0,0,0,0,0,0,0,0,0,0,0,0,0,0,0,0,0,0,0,0,0,DE4,0,0,0,0,0,0,0,0,0,0,0,0,0)';
      PINUSE='POWER';
      NO_LOAD_CHECK='Both';
      NO_IO_CHECK='Both';
      NO_ASSERT_CHECK='TRUE';
      NO_DIR_CHECK='TRUE';
      ALLOW_CONNECT='TRUE';
    'VDD_11_S3_DB19':
      PIN_NUMBER='(0,0,0,0,0,0,0,0,0,0,0,0,0,0,0,0,0,0,0,0,0,0,0,0,0,0,DB19,0,0,0,0,0,0,0,0,0,0,0,0,0)';
      PINUSE='POWER';
      NO_LOAD_CHECK='Both';
      NO_IO_CHECK='Both';
      NO_ASSERT_CHECK='TRUE';
      NO_DIR_CHECK='TRUE';
      ALLOW_CONNECT='TRUE';
    'VDD_11_S3_DB12':
      PIN_NUMBER='(0,0,0,0,0,0,0,0,0,0,0,0,0,0,0,0,0,0,0,0,0,0,0,0,0,0,DB12,0,0,0,0,0,0,0,0,0,0,0,0,0)';
      PINUSE='POWER';
      NO_LOAD_CHECK='Both';
      NO_IO_CHECK='Both';
      NO_ASSERT_CHECK='TRUE';
      NO_DIR_CHECK='TRUE';
      ALLOW_CONNECT='TRUE';
    'VDD_11_S3_DB5':
      PIN_NUMBER='(0,0,0,0,0,0,0,0,0,0,0,0,0,0,0,0,0,0,0,0,0,0,0,0,0,0,DB5,0,0,0,0,0,0,0,0,0,0,0,0,0)';
      PINUSE='POWER';
      NO_LOAD_CHECK='Both';
      NO_IO_CHECK='Both';
      NO_ASSERT_CHECK='TRUE';
      NO_DIR_CHECK='TRUE';
      ALLOW_CONNECT='TRUE';
    'VDD_11_S3_CY22':
      PIN_NUMBER='(0,0,0,0,0,0,0,0,0,0,0,0,0,0,0,0,0,0,0,0,0,0,0,0,0,0,CY22,0,0,0,0,0,0,0,0,0,0,0,0,0)';
      PINUSE='POWER';
      NO_LOAD_CHECK='Both';
      NO_IO_CHECK='Both';
      NO_ASSERT_CHECK='TRUE';
      NO_DIR_CHECK='TRUE';
      ALLOW_CONNECT='TRUE';
    'VDD_11_S3_CW18':
      PIN_NUMBER='(0,0,0,0,0,0,0,0,0,0,0,0,0,0,0,0,0,0,0,0,0,0,0,0,0,0,CW18,0,0,0,0,0,0,0,0,0,0,0,0,0)';
      PINUSE='POWER';
      NO_LOAD_CHECK='Both';
      NO_IO_CHECK='Both';
      NO_ASSERT_CHECK='TRUE';
      NO_DIR_CHECK='TRUE';
      ALLOW_CONNECT='TRUE';
    'VDD_11_S3_CW11':
      PIN_NUMBER='(0,0,0,0,0,0,0,0,0,0,0,0,0,0,0,0,0,0,0,0,0,0,0,0,0,0,CW11,0,0,0,0,0,0,0,0,0,0,0,0,0)';
      PINUSE='POWER';
      NO_LOAD_CHECK='Both';
      NO_IO_CHECK='Both';
      NO_ASSERT_CHECK='TRUE';
      NO_DIR_CHECK='TRUE';
      ALLOW_CONNECT='TRUE';
    'VDD_11_S3_CW4':
      PIN_NUMBER='(0,0,0,0,0,0,0,0,0,0,0,0,0,0,0,0,0,0,0,0,0,0,0,0,0,0,CW4,0,0,0,0,0,0,0,0,0,0,0,0,0)';
      PINUSE='POWER';
      NO_LOAD_CHECK='Both';
      NO_IO_CHECK='Both';
      NO_ASSERT_CHECK='TRUE';
      NO_DIR_CHECK='TRUE';
      ALLOW_CONNECT='TRUE';
    'VDD_11_S3_CT22':
      PIN_NUMBER='(0,0,0,0,0,0,0,0,0,0,0,0,0,0,0,0,0,0,0,0,0,0,0,0,0,0,CT22,0,0,0,0,0,0,0,0,0,0,0,0,0)';
      PINUSE='POWER';
      NO_LOAD_CHECK='Both';
      NO_IO_CHECK='Both';
      NO_ASSERT_CHECK='TRUE';
      NO_DIR_CHECK='TRUE';
      ALLOW_CONNECT='TRUE';
    'VDD_11_S3_CT19':
      PIN_NUMBER='(0,0,0,0,0,0,0,0,0,0,0,0,0,0,0,0,0,0,0,0,0,0,0,0,0,0,CT19,0,0,0,0,0,0,0,0,0,0,0,0,0)';
      PINUSE='POWER';
      NO_LOAD_CHECK='Both';
      NO_IO_CHECK='Both';
      NO_ASSERT_CHECK='TRUE';
      NO_DIR_CHECK='TRUE';
      ALLOW_CONNECT='TRUE';
    'VSS_H37':
      PIN_NUMBER='(0,0,0,0,0,0,0,0,0,0,0,0,0,0,0,0,0,0,0,0,0,0,0,0,0,0,0,H37,0,0,0,0,0,0,0,0,0,0,0,0)';
      PINUSE='POWER';
      NO_LOAD_CHECK='Both';
      NO_IO_CHECK='Both';
      NO_ASSERT_CHECK='TRUE';
      NO_DIR_CHECK='TRUE';
      ALLOW_CONNECT='TRUE';
    'VSS_H39':
      PIN_NUMBER='(0,0,0,0,0,0,0,0,0,0,0,0,0,0,0,0,0,0,0,0,0,0,0,0,0,0,0,H39,0,0,0,0,0,0,0,0,0,0,0,0)';
      PINUSE='POWER';
      NO_LOAD_CHECK='Both';
      NO_IO_CHECK='Both';
      NO_ASSERT_CHECK='TRUE';
      NO_DIR_CHECK='TRUE';
      ALLOW_CONNECT='TRUE';
    'VSS_H42':
      PIN_NUMBER='(0,0,0,0,0,0,0,0,0,0,0,0,0,0,0,0,0,0,0,0,0,0,0,0,0,0,0,H42,0,0,0,0,0,0,0,0,0,0,0,0)';
      PINUSE='POWER';
      NO_LOAD_CHECK='Both';
      NO_IO_CHECK='Both';
      NO_ASSERT_CHECK='TRUE';
      NO_DIR_CHECK='TRUE';
      ALLOW_CONNECT='TRUE';
    'VSS_H45':
      PIN_NUMBER='(0,0,0,0,0,0,0,0,0,0,0,0,0,0,0,0,0,0,0,0,0,0,0,0,0,0,0,H45,0,0,0,0,0,0,0,0,0,0,0,0)';
      PINUSE='POWER';
      NO_LOAD_CHECK='Both';
      NO_IO_CHECK='Both';
      NO_ASSERT_CHECK='TRUE';
      NO_DIR_CHECK='TRUE';
      ALLOW_CONNECT='TRUE';
    'VSS_H48':
      PIN_NUMBER='(0,0,0,0,0,0,0,0,0,0,0,0,0,0,0,0,0,0,0,0,0,0,0,0,0,0,0,H48,0,0,0,0,0,0,0,0,0,0,0,0)';
      PINUSE='POWER';
      NO_LOAD_CHECK='Both';
      NO_IO_CHECK='Both';
      NO_ASSERT_CHECK='TRUE';
      NO_DIR_CHECK='TRUE';
      ALLOW_CONNECT='TRUE';
    'VSS_H51':
      PIN_NUMBER='(0,0,0,0,0,0,0,0,0,0,0,0,0,0,0,0,0,0,0,0,0,0,0,0,0,0,0,H51,0,0,0,0,0,0,0,0,0,0,0,0)';
      PINUSE='POWER';
      NO_LOAD_CHECK='Both';
      NO_IO_CHECK='Both';
      NO_ASSERT_CHECK='TRUE';
      NO_DIR_CHECK='TRUE';
      ALLOW_CONNECT='TRUE';
    'VSS_H54':
      PIN_NUMBER='(0,0,0,0,0,0,0,0,0,0,0,0,0,0,0,0,0,0,0,0,0,0,0,0,0,0,0,H54,0,0,0,0,0,0,0,0,0,0,0,0)';
      PINUSE='POWER';
      NO_LOAD_CHECK='Both';
      NO_IO_CHECK='Both';
      NO_ASSERT_CHECK='TRUE';
      NO_DIR_CHECK='TRUE';
      ALLOW_CONNECT='TRUE';
    'VSS_H59':
      PIN_NUMBER='(0,0,0,0,0,0,0,0,0,0,0,0,0,0,0,0,0,0,0,0,0,0,0,0,0,0,0,H59,0,0,0,0,0,0,0,0,0,0,0,0)';
      PINUSE='POWER';
      NO_LOAD_CHECK='Both';
      NO_IO_CHECK='Both';
      NO_ASSERT_CHECK='TRUE';
      NO_DIR_CHECK='TRUE';
      ALLOW_CONNECT='TRUE';
    'VSS_H61':
      PIN_NUMBER='(0,0,0,0,0,0,0,0,0,0,0,0,0,0,0,0,0,0,0,0,0,0,0,0,0,0,0,H61,0,0,0,0,0,0,0,0,0,0,0,0)';
      PINUSE='POWER';
      NO_LOAD_CHECK='Both';
      NO_IO_CHECK='Both';
      NO_ASSERT_CHECK='TRUE';
      NO_DIR_CHECK='TRUE';
      ALLOW_CONNECT='TRUE';
    'VSS_H66':
      PIN_NUMBER='(0,0,0,0,0,0,0,0,0,0,0,0,0,0,0,0,0,0,0,0,0,0,0,0,0,0,0,H66,0,0,0,0,0,0,0,0,0,0,0,0)';
      PINUSE='POWER';
      NO_LOAD_CHECK='Both';
      NO_IO_CHECK='Both';
      NO_ASSERT_CHECK='TRUE';
      NO_DIR_CHECK='TRUE';
      ALLOW_CONNECT='TRUE';
    'VSS_H68':
      PIN_NUMBER='(0,0,0,0,0,0,0,0,0,0,0,0,0,0,0,0,0,0,0,0,0,0,0,0,0,0,0,H68,0,0,0,0,0,0,0,0,0,0,0,0)';
      PINUSE='POWER';
      NO_LOAD_CHECK='Both';
      NO_IO_CHECK='Both';
      NO_ASSERT_CHECK='TRUE';
      NO_DIR_CHECK='TRUE';
      ALLOW_CONNECT='TRUE';
    'VSS_H73':
      PIN_NUMBER='(0,0,0,0,0,0,0,0,0,0,0,0,0,0,0,0,0,0,0,0,0,0,0,0,0,0,0,H73,0,0,0,0,0,0,0,0,0,0,0,0)';
      PINUSE='POWER';
      NO_LOAD_CHECK='Both';
      NO_IO_CHECK='Both';
      NO_ASSERT_CHECK='TRUE';
      NO_DIR_CHECK='TRUE';
      ALLOW_CONNECT='TRUE';
    'VSS_J1':
      PIN_NUMBER='(0,0,0,0,0,0,0,0,0,0,0,0,0,0,0,0,0,0,0,0,0,0,0,0,0,0,0,J1,0,0,0,0,0,0,0,0,0,0,0,0)';
      PINUSE='POWER';
      NO_LOAD_CHECK='Both';
      NO_IO_CHECK='Both';
      NO_ASSERT_CHECK='TRUE';
      NO_DIR_CHECK='TRUE';
      ALLOW_CONNECT='TRUE';
    'VSS_J4':
      PIN_NUMBER='(0,0,0,0,0,0,0,0,0,0,0,0,0,0,0,0,0,0,0,0,0,0,0,0,0,0,0,J4,0,0,0,0,0,0,0,0,0,0,0,0)';
      PINUSE='POWER';
      NO_LOAD_CHECK='Both';
      NO_IO_CHECK='Both';
      NO_ASSERT_CHECK='TRUE';
      NO_DIR_CHECK='TRUE';
      ALLOW_CONNECT='TRUE';
    'VSS_J6':
      PIN_NUMBER='(0,0,0,0,0,0,0,0,0,0,0,0,0,0,0,0,0,0,0,0,0,0,0,0,0,0,0,J6,0,0,0,0,0,0,0,0,0,0,0,0)';
      PINUSE='POWER';
      NO_LOAD_CHECK='Both';
      NO_IO_CHECK='Both';
      NO_ASSERT_CHECK='TRUE';
      NO_DIR_CHECK='TRUE';
      ALLOW_CONNECT='TRUE';
    'VSS_J8':
      PIN_NUMBER='(0,0,0,0,0,0,0,0,0,0,0,0,0,0,0,0,0,0,0,0,0,0,0,0,0,0,0,J8,0,0,0,0,0,0,0,0,0,0,0,0)';
      PINUSE='POWER';
      NO_LOAD_CHECK='Both';
      NO_IO_CHECK='Both';
      NO_ASSERT_CHECK='TRUE';
      NO_DIR_CHECK='TRUE';
      ALLOW_CONNECT='TRUE';
    'VSS_J11':
      PIN_NUMBER='(0,0,0,0,0,0,0,0,0,0,0,0,0,0,0,0,0,0,0,0,0,0,0,0,0,0,0,J11,0,0,0,0,0,0,0,0,0,0,0,0)';
      PINUSE='POWER';
      NO_LOAD_CHECK='Both';
      NO_IO_CHECK='Both';
      NO_ASSERT_CHECK='TRUE';
      NO_DIR_CHECK='TRUE';
      ALLOW_CONNECT='TRUE';
    'VSS_J13':
      PIN_NUMBER='(0,0,0,0,0,0,0,0,0,0,0,0,0,0,0,0,0,0,0,0,0,0,0,0,0,0,0,J13,0,0,0,0,0,0,0,0,0,0,0,0)';
      PINUSE='POWER';
      NO_LOAD_CHECK='Both';
      NO_IO_CHECK='Both';
      NO_ASSERT_CHECK='TRUE';
      NO_DIR_CHECK='TRUE';
      ALLOW_CONNECT='TRUE';
    'VSS_A3':
      PIN_NUMBER='(0,0,0,0,0,0,0,0,0,0,0,0,0,0,0,0,0,0,0,0,0,0,0,0,0,0,0,A3,0,0,0,0,0,0,0,0,0,0,0,0)';
      PINUSE='POWER';
      NO_LOAD_CHECK='Both';
      NO_IO_CHECK='Both';
      NO_ASSERT_CHECK='TRUE';
      NO_DIR_CHECK='TRUE';
      ALLOW_CONNECT='TRUE';
    'VSS_A9':
      PIN_NUMBER='(0,0,0,0,0,0,0,0,0,0,0,0,0,0,0,0,0,0,0,0,0,0,0,0,0,0,0,A9,0,0,0,0,0,0,0,0,0,0,0,0)';
      PINUSE='POWER';
      NO_LOAD_CHECK='Both';
      NO_IO_CHECK='Both';
      NO_ASSERT_CHECK='TRUE';
      NO_DIR_CHECK='TRUE';
      ALLOW_CONNECT='TRUE';
    'VSS_A15':
      PIN_NUMBER='(0,0,0,0,0,0,0,0,0,0,0,0,0,0,0,0,0,0,0,0,0,0,0,0,0,0,0,A15,0,0,0,0,0,0,0,0,0,0,0,0)';
      PINUSE='POWER';
      NO_LOAD_CHECK='Both';
      NO_IO_CHECK='Both';
      NO_ASSERT_CHECK='TRUE';
      NO_DIR_CHECK='TRUE';
      ALLOW_CONNECT='TRUE';
    'VSS_A21':
      PIN_NUMBER='(0,0,0,0,0,0,0,0,0,0,0,0,0,0,0,0,0,0,0,0,0,0,0,0,0,0,0,A21,0,0,0,0,0,0,0,0,0,0,0,0)';
      PINUSE='POWER';
      NO_LOAD_CHECK='Both';
      NO_IO_CHECK='Both';
      NO_ASSERT_CHECK='TRUE';
      NO_DIR_CHECK='TRUE';
      ALLOW_CONNECT='TRUE';
    'VSS_A27':
      PIN_NUMBER='(0,0,0,0,0,0,0,0,0,0,0,0,0,0,0,0,0,0,0,0,0,0,0,0,0,0,0,A27,0,0,0,0,0,0,0,0,0,0,0,0)';
      PINUSE='POWER';
      NO_LOAD_CHECK='Both';
      NO_IO_CHECK='Both';
      NO_ASSERT_CHECK='TRUE';
      NO_DIR_CHECK='TRUE';
      ALLOW_CONNECT='TRUE';
    'VSS_A43':
      PIN_NUMBER='(0,0,0,0,0,0,0,0,0,0,0,0,0,0,0,0,0,0,0,0,0,0,0,0,0,0,0,A43,0,0,0,0,0,0,0,0,0,0,0,0)';
      PINUSE='POWER';
      NO_LOAD_CHECK='Both';
      NO_IO_CHECK='Both';
      NO_ASSERT_CHECK='TRUE';
      NO_DIR_CHECK='TRUE';
      ALLOW_CONNECT='TRUE';
    'VSS_A44':
      PIN_NUMBER='(0,0,0,0,0,0,0,0,0,0,0,0,0,0,0,0,0,0,0,0,0,0,0,0,0,0,0,A44,0,0,0,0,0,0,0,0,0,0,0,0)';
      PINUSE='POWER';
      NO_LOAD_CHECK='Both';
      NO_IO_CHECK='Both';
      NO_ASSERT_CHECK='TRUE';
      NO_DIR_CHECK='TRUE';
      ALLOW_CONNECT='TRUE';
    'VSS_A47':
      PIN_NUMBER='(0,0,0,0,0,0,0,0,0,0,0,0,0,0,0,0,0,0,0,0,0,0,0,0,0,0,0,A47,0,0,0,0,0,0,0,0,0,0,0,0)';
      PINUSE='POWER';
      NO_LOAD_CHECK='Both';
      NO_IO_CHECK='Both';
      NO_ASSERT_CHECK='TRUE';
      NO_DIR_CHECK='TRUE';
      ALLOW_CONNECT='TRUE';
    'VSS_A49':
      PIN_NUMBER='(0,0,0,0,0,0,0,0,0,0,0,0,0,0,0,0,0,0,0,0,0,0,0,0,0,0,0,A49,0,0,0,0,0,0,0,0,0,0,0,0)';
      PINUSE='POWER';
      NO_LOAD_CHECK='Both';
      NO_IO_CHECK='Both';
      NO_ASSERT_CHECK='TRUE';
      NO_DIR_CHECK='TRUE';
      ALLOW_CONNECT='TRUE';
    'VSS_A53':
      PIN_NUMBER='(0,0,0,0,0,0,0,0,0,0,0,0,0,0,0,0,0,0,0,0,0,0,0,0,0,0,0,A53,0,0,0,0,0,0,0,0,0,0,0,0)';
      PINUSE='POWER';
      NO_LOAD_CHECK='Both';
      NO_IO_CHECK='Both';
      NO_ASSERT_CHECK='TRUE';
      NO_DIR_CHECK='TRUE';
      ALLOW_CONNECT='TRUE';
    'VSS_A61':
      PIN_NUMBER='(0,0,0,0,0,0,0,0,0,0,0,0,0,0,0,0,0,0,0,0,0,0,0,0,0,0,0,A61,0,0,0,0,0,0,0,0,0,0,0,0)';
      PINUSE='POWER';
      NO_LOAD_CHECK='Both';
      NO_IO_CHECK='Both';
      NO_ASSERT_CHECK='TRUE';
      NO_DIR_CHECK='TRUE';
      ALLOW_CONNECT='TRUE';
    'VSS_A67':
      PIN_NUMBER='(0,0,0,0,0,0,0,0,0,0,0,0,0,0,0,0,0,0,0,0,0,0,0,0,0,0,0,A67,0,0,0,0,0,0,0,0,0,0,0,0)';
      PINUSE='POWER';
      NO_LOAD_CHECK='Both';
      NO_IO_CHECK='Both';
      NO_ASSERT_CHECK='TRUE';
      NO_DIR_CHECK='TRUE';
      ALLOW_CONNECT='TRUE';
    'VSS_A72':
      PIN_NUMBER='(0,0,0,0,0,0,0,0,0,0,0,0,0,0,0,0,0,0,0,0,0,0,0,0,0,0,0,A72,0,0,0,0,0,0,0,0,0,0,0,0)';
      PINUSE='POWER';
      NO_LOAD_CHECK='Both';
      NO_IO_CHECK='Both';
      NO_ASSERT_CHECK='TRUE';
      NO_DIR_CHECK='TRUE';
      ALLOW_CONNECT='TRUE';
    'VSS_A73':
      PIN_NUMBER='(0,0,0,0,0,0,0,0,0,0,0,0,0,0,0,0,0,0,0,0,0,0,0,0,0,0,0,A73,0,0,0,0,0,0,0,0,0,0,0,0)';
      PINUSE='POWER';
      NO_LOAD_CHECK='Both';
      NO_IO_CHECK='Both';
      NO_ASSERT_CHECK='TRUE';
      NO_DIR_CHECK='TRUE';
      ALLOW_CONNECT='TRUE';
    'VSS_B7':
      PIN_NUMBER='(0,0,0,0,0,0,0,0,0,0,0,0,0,0,0,0,0,0,0,0,0,0,0,0,0,0,0,B7,0,0,0,0,0,0,0,0,0,0,0,0)';
      PINUSE='POWER';
      NO_LOAD_CHECK='Both';
      NO_IO_CHECK='Both';
      NO_ASSERT_CHECK='TRUE';
      NO_DIR_CHECK='TRUE';
      ALLOW_CONNECT='TRUE';
    'VSS_B8':
      PIN_NUMBER='(0,0,0,0,0,0,0,0,0,0,0,0,0,0,0,0,0,0,0,0,0,0,0,0,0,0,0,B8,0,0,0,0,0,0,0,0,0,0,0,0)';
      PINUSE='POWER';
      NO_LOAD_CHECK='Both';
      NO_IO_CHECK='Both';
      NO_ASSERT_CHECK='TRUE';
      NO_DIR_CHECK='TRUE';
      ALLOW_CONNECT='TRUE';
    'VSS_B10':
      PIN_NUMBER='(0,0,0,0,0,0,0,0,0,0,0,0,0,0,0,0,0,0,0,0,0,0,0,0,0,0,0,B10,0,0,0,0,0,0,0,0,0,0,0,0)';
      PINUSE='POWER';
      NO_LOAD_CHECK='Both';
      NO_IO_CHECK='Both';
      NO_ASSERT_CHECK='TRUE';
      NO_DIR_CHECK='TRUE';
      ALLOW_CONNECT='TRUE';
    'VSS_B11':
      PIN_NUMBER='(0,0,0,0,0,0,0,0,0,0,0,0,0,0,0,0,0,0,0,0,0,0,0,0,0,0,0,B11,0,0,0,0,0,0,0,0,0,0,0,0)';
      PINUSE='POWER';
      NO_LOAD_CHECK='Both';
      NO_IO_CHECK='Both';
      NO_ASSERT_CHECK='TRUE';
      NO_DIR_CHECK='TRUE';
      ALLOW_CONNECT='TRUE';
    'VSS_B13':
      PIN_NUMBER='(0,0,0,0,0,0,0,0,0,0,0,0,0,0,0,0,0,0,0,0,0,0,0,0,0,0,0,B13,0,0,0,0,0,0,0,0,0,0,0,0)';
      PINUSE='POWER';
      NO_LOAD_CHECK='Both';
      NO_IO_CHECK='Both';
      NO_ASSERT_CHECK='TRUE';
      NO_DIR_CHECK='TRUE';
      ALLOW_CONNECT='TRUE';
    'VSS_B18':
      PIN_NUMBER='(0,0,0,0,0,0,0,0,0,0,0,0,0,0,0,0,0,0,0,0,0,0,0,0,0,0,0,B18,0,0,0,0,0,0,0,0,0,0,0,0)';
      PINUSE='POWER';
      NO_LOAD_CHECK='Both';
      NO_IO_CHECK='Both';
      NO_ASSERT_CHECK='TRUE';
      NO_DIR_CHECK='TRUE';
      ALLOW_CONNECT='TRUE';
    'VSS_B24':
      PIN_NUMBER='(0,0,0,0,0,0,0,0,0,0,0,0,0,0,0,0,0,0,0,0,0,0,0,0,0,0,0,B24,0,0,0,0,0,0,0,0,0,0,0,0)';
      PINUSE='POWER';
      NO_LOAD_CHECK='Both';
      NO_IO_CHECK='Both';
      NO_ASSERT_CHECK='TRUE';
      NO_DIR_CHECK='TRUE';
      ALLOW_CONNECT='TRUE';
    'VSS_B27':
      PIN_NUMBER='(0,0,0,0,0,0,0,0,0,0,0,0,0,0,0,0,0,0,0,0,0,0,0,0,0,0,0,B27,0,0,0,0,0,0,0,0,0,0,0,0)';
      PINUSE='POWER';
      NO_LOAD_CHECK='Both';
      NO_IO_CHECK='Both';
      NO_ASSERT_CHECK='TRUE';
      NO_DIR_CHECK='TRUE';
      ALLOW_CONNECT='TRUE';
    'VSS_B30':
      PIN_NUMBER='(0,0,0,0,0,0,0,0,0,0,0,0,0,0,0,0,0,0,0,0,0,0,0,0,0,0,0,B30,0,0,0,0,0,0,0,0,0,0,0,0)';
      PINUSE='POWER';
      NO_LOAD_CHECK='Both';
      NO_IO_CHECK='Both';
      NO_ASSERT_CHECK='TRUE';
      NO_DIR_CHECK='TRUE';
      ALLOW_CONNECT='TRUE';
    'VSS_B33':
      PIN_NUMBER='(0,0,0,0,0,0,0,0,0,0,0,0,0,0,0,0,0,0,0,0,0,0,0,0,0,0,0,B33,0,0,0,0,0,0,0,0,0,0,0,0)';
      PINUSE='POWER';
      NO_LOAD_CHECK='Both';
      NO_IO_CHECK='Both';
      NO_ASSERT_CHECK='TRUE';
      NO_DIR_CHECK='TRUE';
      ALLOW_CONNECT='TRUE';
    'VSS_B37':
      PIN_NUMBER='(0,0,0,0,0,0,0,0,0,0,0,0,0,0,0,0,0,0,0,0,0,0,0,0,0,0,0,B37,0,0,0,0,0,0,0,0,0,0,0,0)';
      PINUSE='POWER';
      NO_LOAD_CHECK='Both';
      NO_IO_CHECK='Both';
      NO_ASSERT_CHECK='TRUE';
      NO_DIR_CHECK='TRUE';
      ALLOW_CONNECT='TRUE';
    'VSS_B39':
      PIN_NUMBER='(0,0,0,0,0,0,0,0,0,0,0,0,0,0,0,0,0,0,0,0,0,0,0,0,0,0,0,B39,0,0,0,0,0,0,0,0,0,0,0,0)';
      PINUSE='POWER';
      NO_LOAD_CHECK='Both';
      NO_IO_CHECK='Both';
      NO_ASSERT_CHECK='TRUE';
      NO_DIR_CHECK='TRUE';
      ALLOW_CONNECT='TRUE';
    'VSS_B43':
      PIN_NUMBER='(0,0,0,0,0,0,0,0,0,0,0,0,0,0,0,0,0,0,0,0,0,0,0,0,0,0,0,B43,0,0,0,0,0,0,0,0,0,0,0,0)';
      PINUSE='POWER';
      NO_LOAD_CHECK='Both';
      NO_IO_CHECK='Both';
      NO_ASSERT_CHECK='TRUE';
      NO_DIR_CHECK='TRUE';
      ALLOW_CONNECT='TRUE';
    'VSS_B46':
      PIN_NUMBER='(0,0,0,0,0,0,0,0,0,0,0,0,0,0,0,0,0,0,0,0,0,0,0,0,0,0,0,B46,0,0,0,0,0,0,0,0,0,0,0,0)';
      PINUSE='POWER';
      NO_LOAD_CHECK='Both';
      NO_IO_CHECK='Both';
      NO_ASSERT_CHECK='TRUE';
      NO_DIR_CHECK='TRUE';
      ALLOW_CONNECT='TRUE';
    'VSS_B49':
      PIN_NUMBER='(0,0,0,0,0,0,0,0,0,0,0,0,0,0,0,0,0,0,0,0,0,0,0,0,0,0,0,B49,0,0,0,0,0,0,0,0,0,0,0,0)';
      PINUSE='POWER';
      NO_LOAD_CHECK='Both';
      NO_IO_CHECK='Both';
      NO_ASSERT_CHECK='TRUE';
      NO_DIR_CHECK='TRUE';
      ALLOW_CONNECT='TRUE';
    'VSS_B52':
      PIN_NUMBER='(0,0,0,0,0,0,0,0,0,0,0,0,0,0,0,0,0,0,0,0,0,0,0,0,0,0,0,B52,0,0,0,0,0,0,0,0,0,0,0,0)';
      PINUSE='POWER';
      NO_LOAD_CHECK='Both';
      NO_IO_CHECK='Both';
      NO_ASSERT_CHECK='TRUE';
      NO_DIR_CHECK='TRUE';
      ALLOW_CONNECT='TRUE';
    'VSS_B55':
      PIN_NUMBER='(0,0,0,0,0,0,0,0,0,0,0,0,0,0,0,0,0,0,0,0,0,0,0,0,0,0,0,B55,0,0,0,0,0,0,0,0,0,0,0,0)';
      PINUSE='POWER';
      NO_LOAD_CHECK='Both';
      NO_IO_CHECK='Both';
      NO_ASSERT_CHECK='TRUE';
      NO_DIR_CHECK='TRUE';
      ALLOW_CONNECT='TRUE';
    'VSS_B59':
      PIN_NUMBER='(0,0,0,0,0,0,0,0,0,0,0,0,0,0,0,0,0,0,0,0,0,0,0,0,0,0,0,B59,0,0,0,0,0,0,0,0,0,0,0,0)';
      PINUSE='POWER';
      NO_LOAD_CHECK='Both';
      NO_IO_CHECK='Both';
      NO_ASSERT_CHECK='TRUE';
      NO_DIR_CHECK='TRUE';
      ALLOW_CONNECT='TRUE';
    'VSS_B62':
      PIN_NUMBER='(0,0,0,0,0,0,0,0,0,0,0,0,0,0,0,0,0,0,0,0,0,0,0,0,0,0,0,B62,0,0,0,0,0,0,0,0,0,0,0,0)';
      PINUSE='POWER';
      NO_LOAD_CHECK='Both';
      NO_IO_CHECK='Both';
      NO_ASSERT_CHECK='TRUE';
      NO_DIR_CHECK='TRUE';
      ALLOW_CONNECT='TRUE';
    'VSS_B65':
      PIN_NUMBER='(0,0,0,0,0,0,0,0,0,0,0,0,0,0,0,0,0,0,0,0,0,0,0,0,0,0,0,B65,0,0,0,0,0,0,0,0,0,0,0,0)';
      PINUSE='POWER';
      NO_LOAD_CHECK='Both';
      NO_IO_CHECK='Both';
      NO_ASSERT_CHECK='TRUE';
      NO_DIR_CHECK='TRUE';
      ALLOW_CONNECT='TRUE';
    'VSS_B68':
      PIN_NUMBER='(0,0,0,0,0,0,0,0,0,0,0,0,0,0,0,0,0,0,0,0,0,0,0,0,0,0,0,B68,0,0,0,0,0,0,0,0,0,0,0,0)';
      PINUSE='POWER';
      NO_LOAD_CHECK='Both';
      NO_IO_CHECK='Both';
      NO_ASSERT_CHECK='TRUE';
      NO_DIR_CHECK='TRUE';
      ALLOW_CONNECT='TRUE';
    'VSS_B70':
      PIN_NUMBER='(0,0,0,0,0,0,0,0,0,0,0,0,0,0,0,0,0,0,0,0,0,0,0,0,0,0,0,B70,0,0,0,0,0,0,0,0,0,0,0,0)';
      PINUSE='POWER';
      NO_LOAD_CHECK='Both';
      NO_IO_CHECK='Both';
      NO_ASSERT_CHECK='TRUE';
      NO_DIR_CHECK='TRUE';
      ALLOW_CONNECT='TRUE';
    'VSS_C1':
      PIN_NUMBER='(0,0,0,0,0,0,0,0,0,0,0,0,0,0,0,0,0,0,0,0,0,0,0,0,0,0,0,C1,0,0,0,0,0,0,0,0,0,0,0,0)';
      PINUSE='POWER';
      NO_LOAD_CHECK='Both';
      NO_IO_CHECK='Both';
      NO_ASSERT_CHECK='TRUE';
      NO_DIR_CHECK='TRUE';
      ALLOW_CONNECT='TRUE';
    'VSS_C5':
      PIN_NUMBER='(0,0,0,0,0,0,0,0,0,0,0,0,0,0,0,0,0,0,0,0,0,0,0,0,0,0,0,C5,0,0,0,0,0,0,0,0,0,0,0,0)';
      PINUSE='POWER';
      NO_LOAD_CHECK='Both';
      NO_IO_CHECK='Both';
      NO_ASSERT_CHECK='TRUE';
      NO_DIR_CHECK='TRUE';
      ALLOW_CONNECT='TRUE';
    'VSS_C8':
      PIN_NUMBER='(0,0,0,0,0,0,0,0,0,0,0,0,0,0,0,0,0,0,0,0,0,0,0,0,0,0,0,C8,0,0,0,0,0,0,0,0,0,0,0,0)';
      PINUSE='POWER';
      NO_LOAD_CHECK='Both';
      NO_IO_CHECK='Both';
      NO_ASSERT_CHECK='TRUE';
      NO_DIR_CHECK='TRUE';
      ALLOW_CONNECT='TRUE';
    'VSS_C10':
      PIN_NUMBER='(0,0,0,0,0,0,0,0,0,0,0,0,0,0,0,0,0,0,0,0,0,0,0,0,0,0,0,C10,0,0,0,0,0,0,0,0,0,0,0,0)';
      PINUSE='POWER';
      NO_LOAD_CHECK='Both';
      NO_IO_CHECK='Both';
      NO_ASSERT_CHECK='TRUE';
      NO_DIR_CHECK='TRUE';
      ALLOW_CONNECT='TRUE';
    'VSS_C11':
      PIN_NUMBER='(0,0,0,0,0,0,0,0,0,0,0,0,0,0,0,0,0,0,0,0,0,0,0,0,0,0,0,C11,0,0,0,0,0,0,0,0,0,0,0,0)';
      PINUSE='POWER';
      NO_LOAD_CHECK='Both';
      NO_IO_CHECK='Both';
      NO_ASSERT_CHECK='TRUE';
      NO_DIR_CHECK='TRUE';
      ALLOW_CONNECT='TRUE';
    'VSS_C13':
      PIN_NUMBER='(0,0,0,0,0,0,0,0,0,0,0,0,0,0,0,0,0,0,0,0,0,0,0,0,0,0,0,C13,0,0,0,0,0,0,0,0,0,0,0,0)';
      PINUSE='POWER';
      NO_LOAD_CHECK='Both';
      NO_IO_CHECK='Both';
      NO_ASSERT_CHECK='TRUE';
      NO_DIR_CHECK='TRUE';
      ALLOW_CONNECT='TRUE';
    'VSS_C15':
      PIN_NUMBER='(0,0,0,0,0,0,0,0,0,0,0,0,0,0,0,0,0,0,0,0,0,0,0,0,0,0,0,C15,0,0,0,0,0,0,0,0,0,0,0,0)';
      PINUSE='POWER';
      NO_LOAD_CHECK='Both';
      NO_IO_CHECK='Both';
      NO_ASSERT_CHECK='TRUE';
      NO_DIR_CHECK='TRUE';
      ALLOW_CONNECT='TRUE';
    'VSS_C21':
      PIN_NUMBER='(0,0,0,0,0,0,0,0,0,0,0,0,0,0,0,0,0,0,0,0,0,0,0,0,0,0,0,C21,0,0,0,0,0,0,0,0,0,0,0,0)';
      PINUSE='POWER';
      NO_LOAD_CHECK='Both';
      NO_IO_CHECK='Both';
      NO_ASSERT_CHECK='TRUE';
      NO_DIR_CHECK='TRUE';
      ALLOW_CONNECT='TRUE';
    'VSS_C24':
      PIN_NUMBER='(0,0,0,0,0,0,0,0,0,0,0,0,0,0,0,0,0,0,0,0,0,0,0,0,0,0,0,C24,0,0,0,0,0,0,0,0,0,0,0,0)';
      PINUSE='POWER';
      NO_LOAD_CHECK='Both';
      NO_IO_CHECK='Both';
      NO_ASSERT_CHECK='TRUE';
      NO_DIR_CHECK='TRUE';
      ALLOW_CONNECT='TRUE';
    'VSS_C27':
      PIN_NUMBER='(0,0,0,0,0,0,0,0,0,0,0,0,0,0,0,0,0,0,0,0,0,0,0,0,0,0,0,C27,0,0,0,0,0,0,0,0,0,0,0,0)';
      PINUSE='POWER';
      NO_LOAD_CHECK='Both';
      NO_IO_CHECK='Both';
      NO_ASSERT_CHECK='TRUE';
      NO_DIR_CHECK='TRUE';
      ALLOW_CONNECT='TRUE';
    'VSS_C30':
      PIN_NUMBER='(0,0,0,0,0,0,0,0,0,0,0,0,0,0,0,0,0,0,0,0,0,0,0,0,0,0,0,C30,0,0,0,0,0,0,0,0,0,0,0,0)';
      PINUSE='POWER';
      NO_LOAD_CHECK='Both';
      NO_IO_CHECK='Both';
      NO_ASSERT_CHECK='TRUE';
      NO_DIR_CHECK='TRUE';
      ALLOW_CONNECT='TRUE';
    'VSS_C36':
      PIN_NUMBER='(0,0,0,0,0,0,0,0,0,0,0,0,0,0,0,0,0,0,0,0,0,0,0,0,0,0,0,C36,0,0,0,0,0,0,0,0,0,0,0,0)';
      PINUSE='POWER';
      NO_LOAD_CHECK='Both';
      NO_IO_CHECK='Both';
      NO_ASSERT_CHECK='TRUE';
      NO_DIR_CHECK='TRUE';
      ALLOW_CONNECT='TRUE';
    'VSS_C40':
      PIN_NUMBER='(0,0,0,0,0,0,0,0,0,0,0,0,0,0,0,0,0,0,0,0,0,0,0,0,0,0,0,C40,0,0,0,0,0,0,0,0,0,0,0,0)';
      PINUSE='POWER';
      NO_LOAD_CHECK='Both';
      NO_IO_CHECK='Both';
      NO_ASSERT_CHECK='TRUE';
      NO_DIR_CHECK='TRUE';
      ALLOW_CONNECT='TRUE';
    'VSS_C43':
      PIN_NUMBER='(0,0,0,0,0,0,0,0,0,0,0,0,0,0,0,0,0,0,0,0,0,0,0,0,0,0,0,C43,0,0,0,0,0,0,0,0,0,0,0,0)';
      PINUSE='POWER';
      NO_LOAD_CHECK='Both';
      NO_IO_CHECK='Both';
      NO_ASSERT_CHECK='TRUE';
      NO_DIR_CHECK='TRUE';
      ALLOW_CONNECT='TRUE';
    'VSS_C46':
      PIN_NUMBER='(0,0,0,0,0,0,0,0,0,0,0,0,0,0,0,0,0,0,0,0,0,0,0,0,0,0,0,C46,0,0,0,0,0,0,0,0,0,0,0,0)';
      PINUSE='POWER';
      NO_LOAD_CHECK='Both';
      NO_IO_CHECK='Both';
      NO_ASSERT_CHECK='TRUE';
      NO_DIR_CHECK='TRUE';
      ALLOW_CONNECT='TRUE';
    'VSS_C49':
      PIN_NUMBER='(0,0,0,0,0,0,0,0,0,0,0,0,0,0,0,0,0,0,0,0,0,0,0,0,0,0,0,C49,0,0,0,0,0,0,0,0,0,0,0,0)';
      PINUSE='POWER';
      NO_LOAD_CHECK='Both';
      NO_IO_CHECK='Both';
      NO_ASSERT_CHECK='TRUE';
      NO_DIR_CHECK='TRUE';
      ALLOW_CONNECT='TRUE';
    'VSS_C52':
      PIN_NUMBER='(0,0,0,0,0,0,0,0,0,0,0,0,0,0,0,0,0,0,0,0,0,0,0,0,0,0,0,C52,0,0,0,0,0,0,0,0,0,0,0,0)';
      PINUSE='POWER';
      NO_LOAD_CHECK='Both';
      NO_IO_CHECK='Both';
      NO_ASSERT_CHECK='TRUE';
      NO_DIR_CHECK='TRUE';
      ALLOW_CONNECT='TRUE';
    'VSS_C55':
      PIN_NUMBER='(0,0,0,0,0,0,0,0,0,0,0,0,0,0,0,0,0,0,0,0,0,0,0,0,0,0,0,C55,0,0,0,0,0,0,0,0,0,0,0,0)';
      PINUSE='POWER';
      NO_LOAD_CHECK='Both';
      NO_IO_CHECK='Both';
      NO_ASSERT_CHECK='TRUE';
      NO_DIR_CHECK='TRUE';
      ALLOW_CONNECT='TRUE';
    'VSS_C56':
      PIN_NUMBER='(0,0,0,0,0,0,0,0,0,0,0,0,0,0,0,0,0,0,0,0,0,0,0,0,0,0,0,C56,0,0,0,0,0,0,0,0,0,0,0,0)';
      PINUSE='POWER';
      NO_LOAD_CHECK='Both';
      NO_IO_CHECK='Both';
      NO_ASSERT_CHECK='TRUE';
      NO_DIR_CHECK='TRUE';
      ALLOW_CONNECT='TRUE';
    'VSS_C57':
      PIN_NUMBER='(0,0,0,0,0,0,0,0,0,0,0,0,0,0,0,0,0,0,0,0,0,0,0,0,0,0,0,C57,0,0,0,0,0,0,0,0,0,0,0,0)';
      PINUSE='POWER';
      NO_LOAD_CHECK='Both';
      NO_IO_CHECK='Both';
      NO_ASSERT_CHECK='TRUE';
      NO_DIR_CHECK='TRUE';
      ALLOW_CONNECT='TRUE';
    'VSS_C61':
      PIN_NUMBER='(0,0,0,0,0,0,0,0,0,0,0,0,0,0,0,0,0,0,0,0,0,0,0,0,0,0,0,C61,0,0,0,0,0,0,0,0,0,0,0,0)';
      PINUSE='POWER';
      NO_LOAD_CHECK='Both';
      NO_IO_CHECK='Both';
      NO_ASSERT_CHECK='TRUE';
      NO_DIR_CHECK='TRUE';
      ALLOW_CONNECT='TRUE';
    'VSS_C64':
      PIN_NUMBER='(0,0,0,0,0,0,0,0,0,0,0,0,0,0,0,0,0,0,0,0,0,0,0,0,0,0,0,C64,0,0,0,0,0,0,0,0,0,0,0,0)';
      PINUSE='POWER';
      NO_LOAD_CHECK='Both';
      NO_IO_CHECK='Both';
      NO_ASSERT_CHECK='TRUE';
      NO_DIR_CHECK='TRUE';
      ALLOW_CONNECT='TRUE';
    'VSS_C67':
      PIN_NUMBER='(0,0,0,0,0,0,0,0,0,0,0,0,0,0,0,0,0,0,0,0,0,0,0,0,0,0,0,C67,0,0,0,0,0,0,0,0,0,0,0,0)';
      PINUSE='POWER';
      NO_LOAD_CHECK='Both';
      NO_IO_CHECK='Both';
      NO_ASSERT_CHECK='TRUE';
      NO_DIR_CHECK='TRUE';
      ALLOW_CONNECT='TRUE';
    'VSS_C69':
      PIN_NUMBER='(0,0,0,0,0,0,0,0,0,0,0,0,0,0,0,0,0,0,0,0,0,0,0,0,0,0,0,C69,0,0,0,0,0,0,0,0,0,0,0,0)';
      PINUSE='POWER';
      NO_LOAD_CHECK='Both';
      NO_IO_CHECK='Both';
      NO_ASSERT_CHECK='TRUE';
      NO_DIR_CHECK='TRUE';
      ALLOW_CONNECT='TRUE';
    'VSS_C71':
      PIN_NUMBER='(0,0,0,0,0,0,0,0,0,0,0,0,0,0,0,0,0,0,0,0,0,0,0,0,0,0,0,C71,0,0,0,0,0,0,0,0,0,0,0,0)';
      PINUSE='POWER';
      NO_LOAD_CHECK='Both';
      NO_IO_CHECK='Both';
      NO_ASSERT_CHECK='TRUE';
      NO_DIR_CHECK='TRUE';
      ALLOW_CONNECT='TRUE';
    'VSS_C73':
      PIN_NUMBER='(0,0,0,0,0,0,0,0,0,0,0,0,0,0,0,0,0,0,0,0,0,0,0,0,0,0,0,C73,0,0,0,0,0,0,0,0,0,0,0,0)';
      PINUSE='POWER';
      NO_LOAD_CHECK='Both';
      NO_IO_CHECK='Both';
      NO_ASSERT_CHECK='TRUE';
      NO_DIR_CHECK='TRUE';
      ALLOW_CONNECT='TRUE';
    'VSS_C75':
      PIN_NUMBER='(0,0,0,0,0,0,0,0,0,0,0,0,0,0,0,0,0,0,0,0,0,0,0,0,0,0,0,C75,0,0,0,0,0,0,0,0,0,0,0,0)';
      PINUSE='POWER';
      NO_LOAD_CHECK='Both';
      NO_IO_CHECK='Both';
      NO_ASSERT_CHECK='TRUE';
      NO_DIR_CHECK='TRUE';
      ALLOW_CONNECT='TRUE';
    'VSS_D2':
      PIN_NUMBER='(0,0,0,0,0,0,0,0,0,0,0,0,0,0,0,0,0,0,0,0,0,0,0,0,0,0,0,D2,0,0,0,0,0,0,0,0,0,0,0,0)';
      PINUSE='POWER';
      NO_LOAD_CHECK='Both';
      NO_IO_CHECK='Both';
      NO_ASSERT_CHECK='TRUE';
      NO_DIR_CHECK='TRUE';
      ALLOW_CONNECT='TRUE';
    'VSS_D3':
      PIN_NUMBER='(0,0,0,0,0,0,0,0,0,0,0,0,0,0,0,0,0,0,0,0,0,0,0,0,0,0,0,D3,0,0,0,0,0,0,0,0,0,0,0,0)';
      PINUSE='POWER';
      NO_LOAD_CHECK='Both';
      NO_IO_CHECK='Both';
      NO_ASSERT_CHECK='TRUE';
      NO_DIR_CHECK='TRUE';
      ALLOW_CONNECT='TRUE';
    'VSS_D5':
      PIN_NUMBER='(0,0,0,0,0,0,0,0,0,0,0,0,0,0,0,0,0,0,0,0,0,0,0,0,0,0,0,D5,0,0,0,0,0,0,0,0,0,0,0,0)';
      PINUSE='POWER';
      NO_LOAD_CHECK='Both';
      NO_IO_CHECK='Both';
      NO_ASSERT_CHECK='TRUE';
      NO_DIR_CHECK='TRUE';
      ALLOW_CONNECT='TRUE';
    'VSS_D6':
      PIN_NUMBER='(0,0,0,0,0,0,0,0,0,0,0,0,0,0,0,0,0,0,0,0,0,0,0,0,0,0,0,D6,0,0,0,0,0,0,0,0,0,0,0,0)';
      PINUSE='POWER';
      NO_LOAD_CHECK='Both';
      NO_IO_CHECK='Both';
      NO_ASSERT_CHECK='TRUE';
      NO_DIR_CHECK='TRUE';
      ALLOW_CONNECT='TRUE';
    'VSS_D9':
      PIN_NUMBER='(0,0,0,0,0,0,0,0,0,0,0,0,0,0,0,0,0,0,0,0,0,0,0,0,0,0,0,D9,0,0,0,0,0,0,0,0,0,0,0,0)';
      PINUSE='POWER';
      NO_LOAD_CHECK='Both';
      NO_IO_CHECK='Both';
      NO_ASSERT_CHECK='TRUE';
      NO_DIR_CHECK='TRUE';
      ALLOW_CONNECT='TRUE';
    'VSS_D10':
      PIN_NUMBER='(0,0,0,0,0,0,0,0,0,0,0,0,0,0,0,0,0,0,0,0,0,0,0,0,0,0,0,D10,0,0,0,0,0,0,0,0,0,0,0,0)';
      PINUSE='POWER';
      NO_LOAD_CHECK='Both';
      NO_IO_CHECK='Both';
      NO_ASSERT_CHECK='TRUE';
      NO_DIR_CHECK='TRUE';
      ALLOW_CONNECT='TRUE';
    'VSS_D12':
      PIN_NUMBER='(0,0,0,0,0,0,0,0,0,0,0,0,0,0,0,0,0,0,0,0,0,0,0,0,0,0,0,D12,0,0,0,0,0,0,0,0,0,0,0,0)';
      PINUSE='POWER';
      NO_LOAD_CHECK='Both';
      NO_IO_CHECK='Both';
      NO_ASSERT_CHECK='TRUE';
      NO_DIR_CHECK='TRUE';
      ALLOW_CONNECT='TRUE';
    'VSS_D13':
      PIN_NUMBER='(0,0,0,0,0,0,0,0,0,0,0,0,0,0,0,0,0,0,0,0,0,0,0,0,0,0,0,D13,0,0,0,0,0,0,0,0,0,0,0,0)';
      PINUSE='POWER';
      NO_LOAD_CHECK='Both';
      NO_IO_CHECK='Both';
      NO_ASSERT_CHECK='TRUE';
      NO_DIR_CHECK='TRUE';
      ALLOW_CONNECT='TRUE';
    'VSS_D16':
      PIN_NUMBER='(0,0,0,0,0,0,0,0,0,0,0,0,0,0,0,0,0,0,0,0,0,0,0,0,0,0,0,D16,0,0,0,0,0,0,0,0,0,0,0,0)';
      PINUSE='POWER';
      NO_LOAD_CHECK='Both';
      NO_IO_CHECK='Both';
      NO_ASSERT_CHECK='TRUE';
      NO_DIR_CHECK='TRUE';
      ALLOW_CONNECT='TRUE';
    'VSS_D17':
      PIN_NUMBER='(0,0,0,0,0,0,0,0,0,0,0,0,0,0,0,0,0,0,0,0,0,0,0,0,0,0,0,D17,0,0,0,0,0,0,0,0,0,0,0,0)';
      PINUSE='POWER';
      NO_LOAD_CHECK='Both';
      NO_IO_CHECK='Both';
      NO_ASSERT_CHECK='TRUE';
      NO_DIR_CHECK='TRUE';
      ALLOW_CONNECT='TRUE';
    'VSS_D19':
      PIN_NUMBER='(0,0,0,0,0,0,0,0,0,0,0,0,0,0,0,0,0,0,0,0,0,0,0,0,0,0,0,D19,0,0,0,0,0,0,0,0,0,0,0,0)';
      PINUSE='POWER';
      NO_LOAD_CHECK='Both';
      NO_IO_CHECK='Both';
      NO_ASSERT_CHECK='TRUE';
      NO_DIR_CHECK='TRUE';
      ALLOW_CONNECT='TRUE';
    'VSS_D20':
      PIN_NUMBER='(0,0,0,0,0,0,0,0,0,0,0,0,0,0,0,0,0,0,0,0,0,0,0,0,0,0,0,D20,0,0,0,0,0,0,0,0,0,0,0,0)';
      PINUSE='POWER';
      NO_LOAD_CHECK='Both';
      NO_IO_CHECK='Both';
      NO_ASSERT_CHECK='TRUE';
      NO_DIR_CHECK='TRUE';
      ALLOW_CONNECT='TRUE';
    'VSS_D21':
      PIN_NUMBER='(0,0,0,0,0,0,0,0,0,0,0,0,0,0,0,0,0,0,0,0,0,0,0,0,0,0,0,D21,0,0,0,0,0,0,0,0,0,0,0,0)';
      PINUSE='POWER';
      NO_LOAD_CHECK='Both';
      NO_IO_CHECK='Both';
      NO_ASSERT_CHECK='TRUE';
      NO_DIR_CHECK='TRUE';
      ALLOW_CONNECT='TRUE';
    'VSS_D24':
      PIN_NUMBER='(0,0,0,0,0,0,0,0,0,0,0,0,0,0,0,0,0,0,0,0,0,0,0,0,0,0,0,D24,0,0,0,0,0,0,0,0,0,0,0,0)';
      PINUSE='POWER';
      NO_LOAD_CHECK='Both';
      NO_IO_CHECK='Both';
      NO_ASSERT_CHECK='TRUE';
      NO_DIR_CHECK='TRUE';
      ALLOW_CONNECT='TRUE';
    'VSS_D25':
      PIN_NUMBER='(0,0,0,0,0,0,0,0,0,0,0,0,0,0,0,0,0,0,0,0,0,0,0,0,0,0,0,D25,0,0,0,0,0,0,0,0,0,0,0,0)';
      PINUSE='POWER';
      NO_LOAD_CHECK='Both';
      NO_IO_CHECK='Both';
      NO_ASSERT_CHECK='TRUE';
      NO_DIR_CHECK='TRUE';
      ALLOW_CONNECT='TRUE';
    'VSS_D26':
      PIN_NUMBER='(0,0,0,0,0,0,0,0,0,0,0,0,0,0,0,0,0,0,0,0,0,0,0,0,0,0,0,D26,0,0,0,0,0,0,0,0,0,0,0,0)';
      PINUSE='POWER';
      NO_LOAD_CHECK='Both';
      NO_IO_CHECK='Both';
      NO_ASSERT_CHECK='TRUE';
      NO_DIR_CHECK='TRUE';
      ALLOW_CONNECT='TRUE';
    'VSS_D27':
      PIN_NUMBER='(0,0,0,0,0,0,0,0,0,0,0,0,0,0,0,0,0,0,0,0,0,0,0,0,0,0,0,D27,0,0,0,0,0,0,0,0,0,0,0,0)';
      PINUSE='POWER';
      NO_LOAD_CHECK='Both';
      NO_IO_CHECK='Both';
      NO_ASSERT_CHECK='TRUE';
      NO_DIR_CHECK='TRUE';
      ALLOW_CONNECT='TRUE';
    'VSS_D28':
      PIN_NUMBER='(0,0,0,0,0,0,0,0,0,0,0,0,0,0,0,0,0,0,0,0,0,0,0,0,0,0,0,D28,0,0,0,0,0,0,0,0,0,0,0,0)';
      PINUSE='POWER';
      NO_LOAD_CHECK='Both';
      NO_IO_CHECK='Both';
      NO_ASSERT_CHECK='TRUE';
      NO_DIR_CHECK='TRUE';
      ALLOW_CONNECT='TRUE';
    'VSS_D29':
      PIN_NUMBER='(0,0,0,0,0,0,0,0,0,0,0,0,0,0,0,0,0,0,0,0,0,0,0,0,0,0,0,D29,0,0,0,0,0,0,0,0,0,0,0,0)';
      PINUSE='POWER';
      NO_LOAD_CHECK='Both';
      NO_IO_CHECK='Both';
      NO_ASSERT_CHECK='TRUE';
      NO_DIR_CHECK='TRUE';
      ALLOW_CONNECT='TRUE';
    'VSS_D30':
      PIN_NUMBER='(0,0,0,0,0,0,0,0,0,0,0,0,0,0,0,0,0,0,0,0,0,0,0,0,0,0,0,D30,0,0,0,0,0,0,0,0,0,0,0,0)';
      PINUSE='POWER';
      NO_LOAD_CHECK='Both';
      NO_IO_CHECK='Both';
      NO_ASSERT_CHECK='TRUE';
      NO_DIR_CHECK='TRUE';
      ALLOW_CONNECT='TRUE';
    'VSS_D31':
      PIN_NUMBER='(0,0,0,0,0,0,0,0,0,0,0,0,0,0,0,0,0,0,0,0,0,0,0,0,0,0,0,D31,0,0,0,0,0,0,0,0,0,0,0,0)';
      PINUSE='POWER';
      NO_LOAD_CHECK='Both';
      NO_IO_CHECK='Both';
      NO_ASSERT_CHECK='TRUE';
      NO_DIR_CHECK='TRUE';
      ALLOW_CONNECT='TRUE';
    'VSS_D35':
      PIN_NUMBER='(0,0,0,0,0,0,0,0,0,0,0,0,0,0,0,0,0,0,0,0,0,0,0,0,0,0,0,D35,0,0,0,0,0,0,0,0,0,0,0,0)';
      PINUSE='POWER';
      NO_LOAD_CHECK='Both';
      NO_IO_CHECK='Both';
      NO_ASSERT_CHECK='TRUE';
      NO_DIR_CHECK='TRUE';
      ALLOW_CONNECT='TRUE';
    'VSS_D37':
      PIN_NUMBER='(0,0,0,0,0,0,0,0,0,0,0,0,0,0,0,0,0,0,0,0,0,0,0,0,0,0,0,D37,0,0,0,0,0,0,0,0,0,0,0,0)';
      PINUSE='POWER';
      NO_LOAD_CHECK='Both';
      NO_IO_CHECK='Both';
      NO_ASSERT_CHECK='TRUE';
      NO_DIR_CHECK='TRUE';
      ALLOW_CONNECT='TRUE';
    'VSS_D39':
      PIN_NUMBER='(0,0,0,0,0,0,0,0,0,0,0,0,0,0,0,0,0,0,0,0,0,0,0,0,0,0,0,D39,0,0,0,0,0,0,0,0,0,0,0,0)';
      PINUSE='POWER';
      NO_LOAD_CHECK='Both';
      NO_IO_CHECK='Both';
      NO_ASSERT_CHECK='TRUE';
      NO_DIR_CHECK='TRUE';
      ALLOW_CONNECT='TRUE';
    'VSS_D40':
      PIN_NUMBER='(0,0,0,0,0,0,0,0,0,0,0,0,0,0,0,0,0,0,0,0,0,0,0,0,0,0,0,D40,0,0,0,0,0,0,0,0,0,0,0,0)';
      PINUSE='POWER';
      NO_LOAD_CHECK='Both';
      NO_IO_CHECK='Both';
      NO_ASSERT_CHECK='TRUE';
      NO_DIR_CHECK='TRUE';
      ALLOW_CONNECT='TRUE';
    'VSS_D41':
      PIN_NUMBER='(0,0,0,0,0,0,0,0,0,0,0,0,0,0,0,0,0,0,0,0,0,0,0,0,0,0,0,D41,0,0,0,0,0,0,0,0,0,0,0,0)';
      PINUSE='POWER';
      NO_LOAD_CHECK='Both';
      NO_IO_CHECK='Both';
      NO_ASSERT_CHECK='TRUE';
      NO_DIR_CHECK='TRUE';
      ALLOW_CONNECT='TRUE';
    'VSS_D42':
      PIN_NUMBER='(0,0,0,0,0,0,0,0,0,0,0,0,0,0,0,0,0,0,0,0,0,0,0,0,0,0,0,D42,0,0,0,0,0,0,0,0,0,0,0,0)';
      PINUSE='POWER';
      NO_LOAD_CHECK='Both';
      NO_IO_CHECK='Both';
      NO_ASSERT_CHECK='TRUE';
      NO_DIR_CHECK='TRUE';
      ALLOW_CONNECT='TRUE';
    'VSS_D43':
      PIN_NUMBER='(0,0,0,0,0,0,0,0,0,0,0,0,0,0,0,0,0,0,0,0,0,0,0,0,0,0,0,D43,0,0,0,0,0,0,0,0,0,0,0,0)';
      PINUSE='POWER';
      NO_LOAD_CHECK='Both';
      NO_IO_CHECK='Both';
      NO_ASSERT_CHECK='TRUE';
      NO_DIR_CHECK='TRUE';
      ALLOW_CONNECT='TRUE';
    'VSS_D44':
      PIN_NUMBER='(0,0,0,0,0,0,0,0,0,0,0,0,0,0,0,0,0,0,0,0,0,0,0,0,0,0,0,D44,0,0,0,0,0,0,0,0,0,0,0,0)';
      PINUSE='POWER';
      NO_LOAD_CHECK='Both';
      NO_IO_CHECK='Both';
      NO_ASSERT_CHECK='TRUE';
      NO_DIR_CHECK='TRUE';
      ALLOW_CONNECT='TRUE';
    'VSS_D45':
      PIN_NUMBER='(0,0,0,0,0,0,0,0,0,0,0,0,0,0,0,0,0,0,0,0,0,0,0,0,0,0,0,D45,0,0,0,0,0,0,0,0,0,0,0,0)';
      PINUSE='POWER';
      NO_LOAD_CHECK='Both';
      NO_IO_CHECK='Both';
      NO_ASSERT_CHECK='TRUE';
      NO_DIR_CHECK='TRUE';
      ALLOW_CONNECT='TRUE';
    'VSS_D46':
      PIN_NUMBER='(0,0,0,0,0,0,0,0,0,0,0,0,0,0,0,0,0,0,0,0,0,0,0,0,0,0,0,D46,0,0,0,0,0,0,0,0,0,0,0,0)';
      PINUSE='POWER';
      NO_LOAD_CHECK='Both';
      NO_IO_CHECK='Both';
      NO_ASSERT_CHECK='TRUE';
      NO_DIR_CHECK='TRUE';
      ALLOW_CONNECT='TRUE';
    'VSS_D47':
      PIN_NUMBER='(0,0,0,0,0,0,0,0,0,0,0,0,0,0,0,0,0,0,0,0,0,0,0,0,0,0,0,D47,0,0,0,0,0,0,0,0,0,0,0,0)';
      PINUSE='POWER';
      NO_LOAD_CHECK='Both';
      NO_IO_CHECK='Both';
      NO_ASSERT_CHECK='TRUE';
      NO_DIR_CHECK='TRUE';
      ALLOW_CONNECT='TRUE';
    'VSS_D48':
      PIN_NUMBER='(0,0,0,0,0,0,0,0,0,0,0,0,0,0,0,0,0,0,0,0,0,0,0,0,0,0,0,D48,0,0,0,0,0,0,0,0,0,0,0,0)';
      PINUSE='POWER';
      NO_LOAD_CHECK='Both';
      NO_IO_CHECK='Both';
      NO_ASSERT_CHECK='TRUE';
      NO_DIR_CHECK='TRUE';
      ALLOW_CONNECT='TRUE';
    'VSS_D49':
      PIN_NUMBER='(0,0,0,0,0,0,0,0,0,0,0,0,0,0,0,0,0,0,0,0,0,0,0,0,0,0,0,D49,0,0,0,0,0,0,0,0,0,0,0,0)';
      PINUSE='POWER';
      NO_LOAD_CHECK='Both';
      NO_IO_CHECK='Both';
      NO_ASSERT_CHECK='TRUE';
      NO_DIR_CHECK='TRUE';
      ALLOW_CONNECT='TRUE';
    'VSS_D50':
      PIN_NUMBER='(0,0,0,0,0,0,0,0,0,0,0,0,0,0,0,0,0,0,0,0,0,0,0,0,0,0,0,D50,0,0,0,0,0,0,0,0,0,0,0,0)';
      PINUSE='POWER';
      NO_LOAD_CHECK='Both';
      NO_IO_CHECK='Both';
      NO_ASSERT_CHECK='TRUE';
      NO_DIR_CHECK='TRUE';
      ALLOW_CONNECT='TRUE';
    'VSS_D51':
      PIN_NUMBER='(0,0,0,0,0,0,0,0,0,0,0,0,0,0,0,0,0,0,0,0,0,0,0,0,0,0,0,D51,0,0,0,0,0,0,0,0,0,0,0,0)';
      PINUSE='POWER';
      NO_LOAD_CHECK='Both';
      NO_IO_CHECK='Both';
      NO_ASSERT_CHECK='TRUE';
      NO_DIR_CHECK='TRUE';
      ALLOW_CONNECT='TRUE';
    'VSS_D52':
      PIN_NUMBER='(0,0,0,0,0,0,0,0,0,0,0,0,0,0,0,0,0,0,0,0,0,0,0,0,0,0,0,D52,0,0,0,0,0,0,0,0,0,0,0,0)';
      PINUSE='POWER';
      NO_LOAD_CHECK='Both';
      NO_IO_CHECK='Both';
      NO_ASSERT_CHECK='TRUE';
      NO_DIR_CHECK='TRUE';
      ALLOW_CONNECT='TRUE';
    'VSS_D53':
      PIN_NUMBER='(0,0,0,0,0,0,0,0,0,0,0,0,0,0,0,0,0,0,0,0,0,0,0,0,0,0,0,D53,0,0,0,0,0,0,0,0,0,0,0,0)';
      PINUSE='POWER';
      NO_LOAD_CHECK='Both';
      NO_IO_CHECK='Both';
      NO_ASSERT_CHECK='TRUE';
      NO_DIR_CHECK='TRUE';
      ALLOW_CONNECT='TRUE';
    'VSS_D54':
      PIN_NUMBER='(0,0,0,0,0,0,0,0,0,0,0,0,0,0,0,0,0,0,0,0,0,0,0,0,0,0,0,D54,0,0,0,0,0,0,0,0,0,0,0,0)';
      PINUSE='POWER';
      NO_LOAD_CHECK='Both';
      NO_IO_CHECK='Both';
      NO_ASSERT_CHECK='TRUE';
      NO_DIR_CHECK='TRUE';
      ALLOW_CONNECT='TRUE';
    'VSS_D57':
      PIN_NUMBER='(0,0,0,0,0,0,0,0,0,0,0,0,0,0,0,0,0,0,0,0,0,0,0,0,0,0,0,D57,0,0,0,0,0,0,0,0,0,0,0,0)';
      PINUSE='POWER';
      NO_LOAD_CHECK='Both';
      NO_IO_CHECK='Both';
      NO_ASSERT_CHECK='TRUE';
      NO_DIR_CHECK='TRUE';
      ALLOW_CONNECT='TRUE';
    'VSS_D59':
      PIN_NUMBER='(0,0,0,0,0,0,0,0,0,0,0,0,0,0,0,0,0,0,0,0,0,0,0,0,0,0,0,D59,0,0,0,0,0,0,0,0,0,0,0,0)';
      PINUSE='POWER';
      NO_LOAD_CHECK='Both';
      NO_IO_CHECK='Both';
      NO_ASSERT_CHECK='TRUE';
      NO_DIR_CHECK='TRUE';
      ALLOW_CONNECT='TRUE';
    'VSS_D60':
      PIN_NUMBER='(0,0,0,0,0,0,0,0,0,0,0,0,0,0,0,0,0,0,0,0,0,0,0,0,0,0,0,D60,0,0,0,0,0,0,0,0,0,0,0,0)';
      PINUSE='POWER';
      NO_LOAD_CHECK='Both';
      NO_IO_CHECK='Both';
      NO_ASSERT_CHECK='TRUE';
      NO_DIR_CHECK='TRUE';
      ALLOW_CONNECT='TRUE';
    'VSS_D61':
      PIN_NUMBER='(0,0,0,0,0,0,0,0,0,0,0,0,0,0,0,0,0,0,0,0,0,0,0,0,0,0,0,D61,0,0,0,0,0,0,0,0,0,0,0,0)';
      PINUSE='POWER';
      NO_LOAD_CHECK='Both';
      NO_IO_CHECK='Both';
      NO_ASSERT_CHECK='TRUE';
      NO_DIR_CHECK='TRUE';
      ALLOW_CONNECT='TRUE';
    'VSS_D63':
      PIN_NUMBER='(0,0,0,0,0,0,0,0,0,0,0,0,0,0,0,0,0,0,0,0,0,0,0,0,0,0,0,D63,0,0,0,0,0,0,0,0,0,0,0,0)';
      PINUSE='POWER';
      NO_LOAD_CHECK='Both';
      NO_IO_CHECK='Both';
      NO_ASSERT_CHECK='TRUE';
      NO_DIR_CHECK='TRUE';
      ALLOW_CONNECT='TRUE';
    'VSS_D64':
      PIN_NUMBER='(0,0,0,0,0,0,0,0,0,0,0,0,0,0,0,0,0,0,0,0,0,0,0,0,0,0,0,D64,0,0,0,0,0,0,0,0,0,0,0,0)';
      PINUSE='POWER';
      NO_LOAD_CHECK='Both';
      NO_IO_CHECK='Both';
      NO_ASSERT_CHECK='TRUE';
      NO_DIR_CHECK='TRUE';
      ALLOW_CONNECT='TRUE';
    'VSS_D66':
      PIN_NUMBER='(0,0,0,0,0,0,0,0,0,0,0,0,0,0,0,0,0,0,0,0,0,0,0,0,0,0,0,D66,0,0,0,0,0,0,0,0,0,0,0,0)';
      PINUSE='POWER';
      NO_LOAD_CHECK='Both';
      NO_IO_CHECK='Both';
      NO_ASSERT_CHECK='TRUE';
      NO_DIR_CHECK='TRUE';
      ALLOW_CONNECT='TRUE';
    'VSS_D67':
      PIN_NUMBER='(0,0,0,0,0,0,0,0,0,0,0,0,0,0,0,0,0,0,0,0,0,0,0,0,0,0,0,D67,0,0,0,0,0,0,0,0,0,0,0,0)';
      PINUSE='POWER';
      NO_LOAD_CHECK='Both';
      NO_IO_CHECK='Both';
      NO_ASSERT_CHECK='TRUE';
      NO_DIR_CHECK='TRUE';
      ALLOW_CONNECT='TRUE';
    'VSS_D70':
      PIN_NUMBER='(0,0,0,0,0,0,0,0,0,0,0,0,0,0,0,0,0,0,0,0,0,0,0,0,0,0,0,D70,0,0,0,0,0,0,0,0,0,0,0,0)';
      PINUSE='POWER';
      NO_LOAD_CHECK='Both';
      NO_IO_CHECK='Both';
      NO_ASSERT_CHECK='TRUE';
      NO_DIR_CHECK='TRUE';
      ALLOW_CONNECT='TRUE';
    'VSS_D71':
      PIN_NUMBER='(0,0,0,0,0,0,0,0,0,0,0,0,0,0,0,0,0,0,0,0,0,0,0,0,0,0,0,D71,0,0,0,0,0,0,0,0,0,0,0,0)';
      PINUSE='POWER';
      NO_LOAD_CHECK='Both';
      NO_IO_CHECK='Both';
      NO_ASSERT_CHECK='TRUE';
      NO_DIR_CHECK='TRUE';
      ALLOW_CONNECT='TRUE';
    'VSS_D73':
      PIN_NUMBER='(0,0,0,0,0,0,0,0,0,0,0,0,0,0,0,0,0,0,0,0,0,0,0,0,0,0,0,D73,0,0,0,0,0,0,0,0,0,0,0,0)';
      PINUSE='POWER';
      NO_LOAD_CHECK='Both';
      NO_IO_CHECK='Both';
      NO_ASSERT_CHECK='TRUE';
      NO_DIR_CHECK='TRUE';
      ALLOW_CONNECT='TRUE';
    'VSS_D74':
      PIN_NUMBER='(0,0,0,0,0,0,0,0,0,0,0,0,0,0,0,0,0,0,0,0,0,0,0,0,0,0,0,D74,0,0,0,0,0,0,0,0,0,0,0,0)';
      PINUSE='POWER';
      NO_LOAD_CHECK='Both';
      NO_IO_CHECK='Both';
      NO_ASSERT_CHECK='TRUE';
      NO_DIR_CHECK='TRUE';
      ALLOW_CONNECT='TRUE';
    'VSS_E1':
      PIN_NUMBER='(0,0,0,0,0,0,0,0,0,0,0,0,0,0,0,0,0,0,0,0,0,0,0,0,0,0,0,E1,0,0,0,0,0,0,0,0,0,0,0,0)';
      PINUSE='POWER';
      NO_LOAD_CHECK='Both';
      NO_IO_CHECK='Both';
      NO_ASSERT_CHECK='TRUE';
      NO_DIR_CHECK='TRUE';
      ALLOW_CONNECT='TRUE';
    'VSS_E3':
      PIN_NUMBER='(0,0,0,0,0,0,0,0,0,0,0,0,0,0,0,0,0,0,0,0,0,0,0,0,0,0,0,E3,0,0,0,0,0,0,0,0,0,0,0,0)';
      PINUSE='POWER';
      NO_LOAD_CHECK='Both';
      NO_IO_CHECK='Both';
      NO_ASSERT_CHECK='TRUE';
      NO_DIR_CHECK='TRUE';
      ALLOW_CONNECT='TRUE';
    'VSS_E6':
      PIN_NUMBER='(0,0,0,0,0,0,0,0,0,0,0,0,0,0,0,0,0,0,0,0,0,0,0,0,0,0,0,E6,0,0,0,0,0,0,0,0,0,0,0,0)';
      PINUSE='POWER';
      NO_LOAD_CHECK='Both';
      NO_IO_CHECK='Both';
      NO_ASSERT_CHECK='TRUE';
      NO_DIR_CHECK='TRUE';
      ALLOW_CONNECT='TRUE';
    'VSS_E7':
      PIN_NUMBER='(0,0,0,0,0,0,0,0,0,0,0,0,0,0,0,0,0,0,0,0,0,0,0,0,0,0,0,E7,0,0,0,0,0,0,0,0,0,0,0,0)';
      PINUSE='POWER';
      NO_LOAD_CHECK='Both';
      NO_IO_CHECK='Both';
      NO_ASSERT_CHECK='TRUE';
      NO_DIR_CHECK='TRUE';
      ALLOW_CONNECT='TRUE';
    'VSS_E8':
      PIN_NUMBER='(0,0,0,0,0,0,0,0,0,0,0,0,0,0,0,0,0,0,0,0,0,0,0,0,0,0,0,E8,0,0,0,0,0,0,0,0,0,0,0,0)';
      PINUSE='POWER';
      NO_LOAD_CHECK='Both';
      NO_IO_CHECK='Both';
      NO_ASSERT_CHECK='TRUE';
      NO_DIR_CHECK='TRUE';
      ALLOW_CONNECT='TRUE';
    'VSS_E10':
      PIN_NUMBER='(0,0,0,0,0,0,0,0,0,0,0,0,0,0,0,0,0,0,0,0,0,0,0,0,0,0,0,E10,0,0,0,0,0,0,0,0,0,0,0,0)';
      PINUSE='POWER';
      NO_LOAD_CHECK='Both';
      NO_IO_CHECK='Both';
      NO_ASSERT_CHECK='TRUE';
      NO_DIR_CHECK='TRUE';
      ALLOW_CONNECT='TRUE';
    'VSS_E13':
      PIN_NUMBER='(0,0,0,0,0,0,0,0,0,0,0,0,0,0,0,0,0,0,0,0,0,0,0,0,0,0,0,E13,0,0,0,0,0,0,0,0,0,0,0,0)';
      PINUSE='POWER';
      NO_LOAD_CHECK='Both';
      NO_IO_CHECK='Both';
      NO_ASSERT_CHECK='TRUE';
      NO_DIR_CHECK='TRUE';
      ALLOW_CONNECT='TRUE';
    'VSS_E14':
      PIN_NUMBER='(0,0,0,0,0,0,0,0,0,0,0,0,0,0,0,0,0,0,0,0,0,0,0,0,0,0,0,E14,0,0,0,0,0,0,0,0,0,0,0,0)';
      PINUSE='POWER';
      NO_LOAD_CHECK='Both';
      NO_IO_CHECK='Both';
      NO_ASSERT_CHECK='TRUE';
      NO_DIR_CHECK='TRUE';
      ALLOW_CONNECT='TRUE';
    'VSS_E15':
      PIN_NUMBER='(0,0,0,0,0,0,0,0,0,0,0,0,0,0,0,0,0,0,0,0,0,0,0,0,0,0,0,E15,0,0,0,0,0,0,0,0,0,0,0,0)';
      PINUSE='POWER';
      NO_LOAD_CHECK='Both';
      NO_IO_CHECK='Both';
      NO_ASSERT_CHECK='TRUE';
      NO_DIR_CHECK='TRUE';
      ALLOW_CONNECT='TRUE';
    'VSS_E17':
      PIN_NUMBER='(0,0,0,0,0,0,0,0,0,0,0,0,0,0,0,0,0,0,0,0,0,0,0,0,0,0,0,E17,0,0,0,0,0,0,0,0,0,0,0,0)';
      PINUSE='POWER';
      NO_LOAD_CHECK='Both';
      NO_IO_CHECK='Both';
      NO_ASSERT_CHECK='TRUE';
      NO_DIR_CHECK='TRUE';
      ALLOW_CONNECT='TRUE';
    'VSS_E18':
      PIN_NUMBER='(0,0,0,0,0,0,0,0,0,0,0,0,0,0,0,0,0,0,0,0,0,0,0,0,0,0,0,E18,0,0,0,0,0,0,0,0,0,0,0,0)';
      PINUSE='POWER';
      NO_LOAD_CHECK='Both';
      NO_IO_CHECK='Both';
      NO_ASSERT_CHECK='TRUE';
      NO_DIR_CHECK='TRUE';
      ALLOW_CONNECT='TRUE';
    'VSS_E20':
      PIN_NUMBER='(0,0,0,0,0,0,0,0,0,0,0,0,0,0,0,0,0,0,0,0,0,0,0,0,0,0,0,E20,0,0,0,0,0,0,0,0,0,0,0,0)';
      PINUSE='POWER';
      NO_LOAD_CHECK='Both';
      NO_IO_CHECK='Both';
      NO_ASSERT_CHECK='TRUE';
      NO_DIR_CHECK='TRUE';
      ALLOW_CONNECT='TRUE';
    'VSS_E21':
      PIN_NUMBER='(0,0,0,0,0,0,0,0,0,0,0,0,0,0,0,0,0,0,0,0,0,0,0,0,0,0,0,E21,0,0,0,0,0,0,0,0,0,0,0,0)';
      PINUSE='POWER';
      NO_LOAD_CHECK='Both';
      NO_IO_CHECK='Both';
      NO_ASSERT_CHECK='TRUE';
      NO_DIR_CHECK='TRUE';
      ALLOW_CONNECT='TRUE';
    'VSS_E52':
      PIN_NUMBER='(0,0,0,0,0,0,0,0,0,0,0,0,0,0,0,0,0,0,0,0,0,0,0,0,0,0,0,E52,0,0,0,0,0,0,0,0,0,0,0,0)';
      PINUSE='POWER';
      NO_LOAD_CHECK='Both';
      NO_IO_CHECK='Both';
      NO_ASSERT_CHECK='TRUE';
      NO_DIR_CHECK='TRUE';
      ALLOW_CONNECT='TRUE';
    'VSS_E53':
      PIN_NUMBER='(0,0,0,0,0,0,0,0,0,0,0,0,0,0,0,0,0,0,0,0,0,0,0,0,0,0,0,E53,0,0,0,0,0,0,0,0,0,0,0,0)';
      PINUSE='POWER';
      NO_LOAD_CHECK='Both';
      NO_IO_CHECK='Both';
      NO_ASSERT_CHECK='TRUE';
      NO_DIR_CHECK='TRUE';
      ALLOW_CONNECT='TRUE';
    'VSS_E55':
      PIN_NUMBER='(0,0,0,0,0,0,0,0,0,0,0,0,0,0,0,0,0,0,0,0,0,0,0,0,0,0,0,E55,0,0,0,0,0,0,0,0,0,0,0,0)';
      PINUSE='POWER';
      NO_LOAD_CHECK='Both';
      NO_IO_CHECK='Both';
      NO_ASSERT_CHECK='TRUE';
      NO_DIR_CHECK='TRUE';
      ALLOW_CONNECT='TRUE';
    'VSS_E56':
      PIN_NUMBER='(0,0,0,0,0,0,0,0,0,0,0,0,0,0,0,0,0,0,0,0,0,0,0,0,0,0,0,E56,0,0,0,0,0,0,0,0,0,0,0,0)';
      PINUSE='POWER';
      NO_LOAD_CHECK='Both';
      NO_IO_CHECK='Both';
      NO_ASSERT_CHECK='TRUE';
      NO_DIR_CHECK='TRUE';
      ALLOW_CONNECT='TRUE';
    'VSS_E58':
      PIN_NUMBER='(0,0,0,0,0,0,0,0,0,0,0,0,0,0,0,0,0,0,0,0,0,0,0,0,0,0,0,E58,0,0,0,0,0,0,0,0,0,0,0,0)';
      PINUSE='POWER';
      NO_LOAD_CHECK='Both';
      NO_IO_CHECK='Both';
      NO_ASSERT_CHECK='TRUE';
      NO_DIR_CHECK='TRUE';
      ALLOW_CONNECT='TRUE';
    'VSS_E59':
      PIN_NUMBER='(0,0,0,0,0,0,0,0,0,0,0,0,0,0,0,0,0,0,0,0,0,0,0,0,0,0,0,E59,0,0,0,0,0,0,0,0,0,0,0,0)';
      PINUSE='POWER';
      NO_LOAD_CHECK='Both';
      NO_IO_CHECK='Both';
      NO_ASSERT_CHECK='TRUE';
      NO_DIR_CHECK='TRUE';
      ALLOW_CONNECT='TRUE';
    'VSS_E61':
      PIN_NUMBER='(0,0,0,0,0,0,0,0,0,0,0,0,0,0,0,0,0,0,0,0,0,0,0,0,0,0,0,E61,0,0,0,0,0,0,0,0,0,0,0,0)';
      PINUSE='POWER';
      NO_LOAD_CHECK='Both';
      NO_IO_CHECK='Both';
      NO_ASSERT_CHECK='TRUE';
      NO_DIR_CHECK='TRUE';
      ALLOW_CONNECT='TRUE';
    'VSS_E62':
      PIN_NUMBER='(0,0,0,0,0,0,0,0,0,0,0,0,0,0,0,0,0,0,0,0,0,0,0,0,0,0,0,E62,0,0,0,0,0,0,0,0,0,0,0,0)';
      PINUSE='POWER';
      NO_LOAD_CHECK='Both';
      NO_IO_CHECK='Both';
      NO_ASSERT_CHECK='TRUE';
      NO_DIR_CHECK='TRUE';
      ALLOW_CONNECT='TRUE';
    'VSS_E63':
      PIN_NUMBER='(0,0,0,0,0,0,0,0,0,0,0,0,0,0,0,0,0,0,0,0,0,0,0,0,0,0,0,E63,0,0,0,0,0,0,0,0,0,0,0,0)';
      PINUSE='POWER';
      NO_LOAD_CHECK='Both';
      NO_IO_CHECK='Both';
      NO_ASSERT_CHECK='TRUE';
      NO_DIR_CHECK='TRUE';
      ALLOW_CONNECT='TRUE';
    'VSS_E65':
      PIN_NUMBER='(0,0,0,0,0,0,0,0,0,0,0,0,0,0,0,0,0,0,0,0,0,0,0,0,0,0,0,E65,0,0,0,0,0,0,0,0,0,0,0,0)';
      PINUSE='POWER';
      NO_LOAD_CHECK='Both';
      NO_IO_CHECK='Both';
      NO_ASSERT_CHECK='TRUE';
      NO_DIR_CHECK='TRUE';
      ALLOW_CONNECT='TRUE';
    'VSS_E66':
      PIN_NUMBER='(0,0,0,0,0,0,0,0,0,0,0,0,0,0,0,0,0,0,0,0,0,0,0,0,0,0,0,E66,0,0,0,0,0,0,0,0,0,0,0,0)';
      PINUSE='POWER';
      NO_LOAD_CHECK='Both';
      NO_IO_CHECK='Both';
      NO_ASSERT_CHECK='TRUE';
      NO_DIR_CHECK='TRUE';
      ALLOW_CONNECT='TRUE';
    'VSS_E68':
      PIN_NUMBER='(0,0,0,0,0,0,0,0,0,0,0,0,0,0,0,0,0,0,0,0,0,0,0,0,0,0,0,E68,0,0,0,0,0,0,0,0,0,0,0,0)';
      PINUSE='POWER';
      NO_LOAD_CHECK='Both';
      NO_IO_CHECK='Both';
      NO_ASSERT_CHECK='TRUE';
      NO_DIR_CHECK='TRUE';
      ALLOW_CONNECT='TRUE';
    'VSS_E69':
      PIN_NUMBER='(0,0,0,0,0,0,0,0,0,0,0,0,0,0,0,0,0,0,0,0,0,0,0,0,0,0,0,E69,0,0,0,0,0,0,0,0,0,0,0,0)';
      PINUSE='POWER';
      NO_LOAD_CHECK='Both';
      NO_IO_CHECK='Both';
      NO_ASSERT_CHECK='TRUE';
      NO_DIR_CHECK='TRUE';
      ALLOW_CONNECT='TRUE';
    'VSS_E70':
      PIN_NUMBER='(0,0,0,0,0,0,0,0,0,0,0,0,0,0,0,0,0,0,0,0,0,0,0,0,0,0,0,E70,0,0,0,0,0,0,0,0,0,0,0,0)';
      PINUSE='POWER';
      NO_LOAD_CHECK='Both';
      NO_IO_CHECK='Both';
      NO_ASSERT_CHECK='TRUE';
      NO_DIR_CHECK='TRUE';
      ALLOW_CONNECT='TRUE';
    'VSS_E72':
      PIN_NUMBER='(0,0,0,0,0,0,0,0,0,0,0,0,0,0,0,0,0,0,0,0,0,0,0,0,0,0,0,E72,0,0,0,0,0,0,0,0,0,0,0,0)';
      PINUSE='POWER';
      NO_LOAD_CHECK='Both';
      NO_IO_CHECK='Both';
      NO_ASSERT_CHECK='TRUE';
      NO_DIR_CHECK='TRUE';
      ALLOW_CONNECT='TRUE';
    'VSS_E73':
      PIN_NUMBER='(0,0,0,0,0,0,0,0,0,0,0,0,0,0,0,0,0,0,0,0,0,0,0,0,0,0,0,E73,0,0,0,0,0,0,0,0,0,0,0,0)';
      PINUSE='POWER';
      NO_LOAD_CHECK='Both';
      NO_IO_CHECK='Both';
      NO_ASSERT_CHECK='TRUE';
      NO_DIR_CHECK='TRUE';
      ALLOW_CONNECT='TRUE';
    'VSS_E75':
      PIN_NUMBER='(0,0,0,0,0,0,0,0,0,0,0,0,0,0,0,0,0,0,0,0,0,0,0,0,0,0,0,E75,0,0,0,0,0,0,0,0,0,0,0,0)';
      PINUSE='POWER';
      NO_LOAD_CHECK='Both';
      NO_IO_CHECK='Both';
      NO_ASSERT_CHECK='TRUE';
      NO_DIR_CHECK='TRUE';
      ALLOW_CONNECT='TRUE';
    'VSS_F3':
      PIN_NUMBER='(0,0,0,0,0,0,0,0,0,0,0,0,0,0,0,0,0,0,0,0,0,0,0,0,0,0,0,F3,0,0,0,0,0,0,0,0,0,0,0,0)';
      PINUSE='POWER';
      NO_LOAD_CHECK='Both';
      NO_IO_CHECK='Both';
      NO_ASSERT_CHECK='TRUE';
      NO_DIR_CHECK='TRUE';
      ALLOW_CONNECT='TRUE';
    'VSS_F5':
      PIN_NUMBER='(0,0,0,0,0,0,0,0,0,0,0,0,0,0,0,0,0,0,0,0,0,0,0,0,0,0,0,F5,0,0,0,0,0,0,0,0,0,0,0,0)';
      PINUSE='POWER';
      NO_LOAD_CHECK='Both';
      NO_IO_CHECK='Both';
      NO_ASSERT_CHECK='TRUE';
      NO_DIR_CHECK='TRUE';
      ALLOW_CONNECT='TRUE';
    'VSS_F8':
      PIN_NUMBER='(0,0,0,0,0,0,0,0,0,0,0,0,0,0,0,0,0,0,0,0,0,0,0,0,0,0,0,F8,0,0,0,0,0,0,0,0,0,0,0,0)';
      PINUSE='POWER';
      NO_LOAD_CHECK='Both';
      NO_IO_CHECK='Both';
      NO_ASSERT_CHECK='TRUE';
      NO_DIR_CHECK='TRUE';
      ALLOW_CONNECT='TRUE';
    'VSS_F10':
      PIN_NUMBER='(0,0,0,0,0,0,0,0,0,0,0,0,0,0,0,0,0,0,0,0,0,0,0,0,0,0,0,F10,0,0,0,0,0,0,0,0,0,0,0,0)';
      PINUSE='POWER';
      NO_LOAD_CHECK='Both';
      NO_IO_CHECK='Both';
      NO_ASSERT_CHECK='TRUE';
      NO_DIR_CHECK='TRUE';
      ALLOW_CONNECT='TRUE';
    'VSS_F12':
      PIN_NUMBER='(0,0,0,0,0,0,0,0,0,0,0,0,0,0,0,0,0,0,0,0,0,0,0,0,0,0,0,F12,0,0,0,0,0,0,0,0,0,0,0,0)';
      PINUSE='POWER';
      NO_LOAD_CHECK='Both';
      NO_IO_CHECK='Both';
      NO_ASSERT_CHECK='TRUE';
      NO_DIR_CHECK='TRUE';
      ALLOW_CONNECT='TRUE';
    'VSS_F15':
      PIN_NUMBER='(0,0,0,0,0,0,0,0,0,0,0,0,0,0,0,0,0,0,0,0,0,0,0,0,0,0,0,F15,0,0,0,0,0,0,0,0,0,0,0,0)';
      PINUSE='POWER';
      NO_LOAD_CHECK='Both';
      NO_IO_CHECK='Both';
      NO_ASSERT_CHECK='TRUE';
      NO_DIR_CHECK='TRUE';
      ALLOW_CONNECT='TRUE';
    'VSS_F17':
      PIN_NUMBER='(0,0,0,0,0,0,0,0,0,0,0,0,0,0,0,0,0,0,0,0,0,0,0,0,0,0,0,F17,0,0,0,0,0,0,0,0,0,0,0,0)';
      PINUSE='POWER';
      NO_LOAD_CHECK='Both';
      NO_IO_CHECK='Both';
      NO_ASSERT_CHECK='TRUE';
      NO_DIR_CHECK='TRUE';
      ALLOW_CONNECT='TRUE';
    'VSS_F19':
      PIN_NUMBER='(0,0,0,0,0,0,0,0,0,0,0,0,0,0,0,0,0,0,0,0,0,0,0,0,0,0,0,F19,0,0,0,0,0,0,0,0,0,0,0,0)';
      PINUSE='POWER';
      NO_LOAD_CHECK='Both';
      NO_IO_CHECK='Both';
      NO_ASSERT_CHECK='TRUE';
      NO_DIR_CHECK='TRUE';
      ALLOW_CONNECT='TRUE';
    'VSS_F23':
      PIN_NUMBER='(0,0,0,0,0,0,0,0,0,0,0,0,0,0,0,0,0,0,0,0,0,0,0,0,0,0,0,F23,0,0,0,0,0,0,0,0,0,0,0,0)';
      PINUSE='POWER';
      NO_LOAD_CHECK='Both';
      NO_IO_CHECK='Both';
      NO_ASSERT_CHECK='TRUE';
      NO_DIR_CHECK='TRUE';
      ALLOW_CONNECT='TRUE';
    'VSS_F24':
      PIN_NUMBER='(0,0,0,0,0,0,0,0,0,0,0,0,0,0,0,0,0,0,0,0,0,0,0,0,0,0,0,F24,0,0,0,0,0,0,0,0,0,0,0,0)';
      PINUSE='POWER';
      NO_LOAD_CHECK='Both';
      NO_IO_CHECK='Both';
      NO_ASSERT_CHECK='TRUE';
      NO_DIR_CHECK='TRUE';
      ALLOW_CONNECT='TRUE';
    'VSS_F26':
      PIN_NUMBER='(0,0,0,0,0,0,0,0,0,0,0,0,0,0,0,0,0,0,0,0,0,0,0,0,0,0,0,F26,0,0,0,0,0,0,0,0,0,0,0,0)';
      PINUSE='POWER';
      NO_LOAD_CHECK='Both';
      NO_IO_CHECK='Both';
      NO_ASSERT_CHECK='TRUE';
      NO_DIR_CHECK='TRUE';
      ALLOW_CONNECT='TRUE';
    'VSS_F27':
      PIN_NUMBER='(0,0,0,0,0,0,0,0,0,0,0,0,0,0,0,0,0,0,0,0,0,0,0,0,0,0,0,F27,0,0,0,0,0,0,0,0,0,0,0,0)';
      PINUSE='POWER';
      NO_LOAD_CHECK='Both';
      NO_IO_CHECK='Both';
      NO_ASSERT_CHECK='TRUE';
      NO_DIR_CHECK='TRUE';
      ALLOW_CONNECT='TRUE';
    'VSS_F29':
      PIN_NUMBER='(0,0,0,0,0,0,0,0,0,0,0,0,0,0,0,0,0,0,0,0,0,0,0,0,0,0,0,F29,0,0,0,0,0,0,0,0,0,0,0,0)';
      PINUSE='POWER';
      NO_LOAD_CHECK='Both';
      NO_IO_CHECK='Both';
      NO_ASSERT_CHECK='TRUE';
      NO_DIR_CHECK='TRUE';
      ALLOW_CONNECT='TRUE';
    'VSS_F30':
      PIN_NUMBER='(0,0,0,0,0,0,0,0,0,0,0,0,0,0,0,0,0,0,0,0,0,0,0,0,0,0,0,F30,0,0,0,0,0,0,0,0,0,0,0,0)';
      PINUSE='POWER';
      NO_LOAD_CHECK='Both';
      NO_IO_CHECK='Both';
      NO_ASSERT_CHECK='TRUE';
      NO_DIR_CHECK='TRUE';
      ALLOW_CONNECT='TRUE';
    'VSS_F32':
      PIN_NUMBER='(0,0,0,0,0,0,0,0,0,0,0,0,0,0,0,0,0,0,0,0,0,0,0,0,0,0,0,F32,0,0,0,0,0,0,0,0,0,0,0,0)';
      PINUSE='POWER';
      NO_LOAD_CHECK='Both';
      NO_IO_CHECK='Both';
      NO_ASSERT_CHECK='TRUE';
      NO_DIR_CHECK='TRUE';
      ALLOW_CONNECT='TRUE';
    'VSS_F33':
      PIN_NUMBER='(0,0,0,0,0,0,0,0,0,0,0,0,0,0,0,0,0,0,0,0,0,0,0,0,0,0,0,F33,0,0,0,0,0,0,0,0,0,0,0,0)';
      PINUSE='POWER';
      NO_LOAD_CHECK='Both';
      NO_IO_CHECK='Both';
      NO_ASSERT_CHECK='TRUE';
      NO_DIR_CHECK='TRUE';
      ALLOW_CONNECT='TRUE';
    'VSS_F35':
      PIN_NUMBER='(0,0,0,0,0,0,0,0,0,0,0,0,0,0,0,0,0,0,0,0,0,0,0,0,0,0,0,F35,0,0,0,0,0,0,0,0,0,0,0,0)';
      PINUSE='POWER';
      NO_LOAD_CHECK='Both';
      NO_IO_CHECK='Both';
      NO_ASSERT_CHECK='TRUE';
      NO_DIR_CHECK='TRUE';
      ALLOW_CONNECT='TRUE';
    'VSS_F36':
      PIN_NUMBER='(0,0,0,0,0,0,0,0,0,0,0,0,0,0,0,0,0,0,0,0,0,0,0,0,0,0,0,F36,0,0,0,0,0,0,0,0,0,0,0,0)';
      PINUSE='POWER';
      NO_LOAD_CHECK='Both';
      NO_IO_CHECK='Both';
      NO_ASSERT_CHECK='TRUE';
      NO_DIR_CHECK='TRUE';
      ALLOW_CONNECT='TRUE';
    'VSS_F37':
      PIN_NUMBER='(0,0,0,0,0,0,0,0,0,0,0,0,0,0,0,0,0,0,0,0,0,0,0,0,0,0,0,F37,0,0,0,0,0,0,0,0,0,0,0,0)';
      PINUSE='POWER';
      NO_LOAD_CHECK='Both';
      NO_IO_CHECK='Both';
      NO_ASSERT_CHECK='TRUE';
      NO_DIR_CHECK='TRUE';
      ALLOW_CONNECT='TRUE';
    'VSS_F39':
      PIN_NUMBER='(0,0,0,0,0,0,0,0,0,0,0,0,0,0,0,0,0,0,0,0,0,0,0,0,0,0,0,F39,0,0,0,0,0,0,0,0,0,0,0,0)';
      PINUSE='POWER';
      NO_LOAD_CHECK='Both';
      NO_IO_CHECK='Both';
      NO_ASSERT_CHECK='TRUE';
      NO_DIR_CHECK='TRUE';
      ALLOW_CONNECT='TRUE';
    'VSS_F40':
      PIN_NUMBER='(0,0,0,0,0,0,0,0,0,0,0,0,0,0,0,0,0,0,0,0,0,0,0,0,0,0,0,F40,0,0,0,0,0,0,0,0,0,0,0,0)';
      PINUSE='POWER';
      NO_LOAD_CHECK='Both';
      NO_IO_CHECK='Both';
      NO_ASSERT_CHECK='TRUE';
      NO_DIR_CHECK='TRUE';
      ALLOW_CONNECT='TRUE';
    'VSS_F41':
      PIN_NUMBER='(0,0,0,0,0,0,0,0,0,0,0,0,0,0,0,0,0,0,0,0,0,0,0,0,0,0,0,F41,0,0,0,0,0,0,0,0,0,0,0,0)';
      PINUSE='POWER';
      NO_LOAD_CHECK='Both';
      NO_IO_CHECK='Both';
      NO_ASSERT_CHECK='TRUE';
      NO_DIR_CHECK='TRUE';
      ALLOW_CONNECT='TRUE';
    'VSS_F43':
      PIN_NUMBER='(0,0,0,0,0,0,0,0,0,0,0,0,0,0,0,0,0,0,0,0,0,0,0,0,0,0,0,F43,0,0,0,0,0,0,0,0,0,0,0,0)';
      PINUSE='POWER';
      NO_LOAD_CHECK='Both';
      NO_IO_CHECK='Both';
      NO_ASSERT_CHECK='TRUE';
      NO_DIR_CHECK='TRUE';
      ALLOW_CONNECT='TRUE';
    'VSS_F44':
      PIN_NUMBER='(0,0,0,0,0,0,0,0,0,0,0,0,0,0,0,0,0,0,0,0,0,0,0,0,0,0,0,F44,0,0,0,0,0,0,0,0,0,0,0,0)';
      PINUSE='POWER';
      NO_LOAD_CHECK='Both';
      NO_IO_CHECK='Both';
      NO_ASSERT_CHECK='TRUE';
      NO_DIR_CHECK='TRUE';
      ALLOW_CONNECT='TRUE';
    'VSS_F46':
      PIN_NUMBER='(0,0,0,0,0,0,0,0,0,0,0,0,0,0,0,0,0,0,0,0,0,0,0,0,0,0,0,F46,0,0,0,0,0,0,0,0,0,0,0,0)';
      PINUSE='POWER';
      NO_LOAD_CHECK='Both';
      NO_IO_CHECK='Both';
      NO_ASSERT_CHECK='TRUE';
      NO_DIR_CHECK='TRUE';
      ALLOW_CONNECT='TRUE';
    'VSS_F47':
      PIN_NUMBER='(0,0,0,0,0,0,0,0,0,0,0,0,0,0,0,0,0,0,0,0,0,0,0,0,0,0,0,F47,0,0,0,0,0,0,0,0,0,0,0,0)';
      PINUSE='POWER';
      NO_LOAD_CHECK='Both';
      NO_IO_CHECK='Both';
      NO_ASSERT_CHECK='TRUE';
      NO_DIR_CHECK='TRUE';
      ALLOW_CONNECT='TRUE';
    'VSS_F49':
      PIN_NUMBER='(0,0,0,0,0,0,0,0,0,0,0,0,0,0,0,0,0,0,0,0,0,0,0,0,0,0,0,F49,0,0,0,0,0,0,0,0,0,0,0,0)';
      PINUSE='POWER';
      NO_LOAD_CHECK='Both';
      NO_IO_CHECK='Both';
      NO_ASSERT_CHECK='TRUE';
      NO_DIR_CHECK='TRUE';
      ALLOW_CONNECT='TRUE';
    'VSS_F50':
      PIN_NUMBER='(0,0,0,0,0,0,0,0,0,0,0,0,0,0,0,0,0,0,0,0,0,0,0,0,0,0,0,F50,0,0,0,0,0,0,0,0,0,0,0,0)';
      PINUSE='POWER';
      NO_LOAD_CHECK='Both';
      NO_IO_CHECK='Both';
      NO_ASSERT_CHECK='TRUE';
      NO_DIR_CHECK='TRUE';
      ALLOW_CONNECT='TRUE';
    'VSS_F52':
      PIN_NUMBER='(0,0,0,0,0,0,0,0,0,0,0,0,0,0,0,0,0,0,0,0,0,0,0,0,0,0,0,F52,0,0,0,0,0,0,0,0,0,0,0,0)';
      PINUSE='POWER';
      NO_LOAD_CHECK='Both';
      NO_IO_CHECK='Both';
      NO_ASSERT_CHECK='TRUE';
      NO_DIR_CHECK='TRUE';
      ALLOW_CONNECT='TRUE';
    'VSS_F53':
      PIN_NUMBER='(0,0,0,0,0,0,0,0,0,0,0,0,0,0,0,0,0,0,0,0,0,0,0,0,0,0,0,F53,0,0,0,0,0,0,0,0,0,0,0,0)';
      PINUSE='POWER';
      NO_LOAD_CHECK='Both';
      NO_IO_CHECK='Both';
      NO_ASSERT_CHECK='TRUE';
      NO_DIR_CHECK='TRUE';
      ALLOW_CONNECT='TRUE';
    'VSS_F57':
      PIN_NUMBER='(0,0,0,0,0,0,0,0,0,0,0,0,0,0,0,0,0,0,0,0,0,0,0,0,0,0,0,F57,0,0,0,0,0,0,0,0,0,0,0,0)';
      PINUSE='POWER';
      NO_LOAD_CHECK='Both';
      NO_IO_CHECK='Both';
      NO_ASSERT_CHECK='TRUE';
      NO_DIR_CHECK='TRUE';
      ALLOW_CONNECT='TRUE';
    'VSS_F59':
      PIN_NUMBER='(0,0,0,0,0,0,0,0,0,0,0,0,0,0,0,0,0,0,0,0,0,0,0,0,0,0,0,F59,0,0,0,0,0,0,0,0,0,0,0,0)';
      PINUSE='POWER';
      NO_LOAD_CHECK='Both';
      NO_IO_CHECK='Both';
      NO_ASSERT_CHECK='TRUE';
      NO_DIR_CHECK='TRUE';
      ALLOW_CONNECT='TRUE';
    'VSS_F61':
      PIN_NUMBER='(0,0,0,0,0,0,0,0,0,0,0,0,0,0,0,0,0,0,0,0,0,0,0,0,0,0,0,F61,0,0,0,0,0,0,0,0,0,0,0,0)';
      PINUSE='POWER';
      NO_LOAD_CHECK='Both';
      NO_IO_CHECK='Both';
      NO_ASSERT_CHECK='TRUE';
      NO_DIR_CHECK='TRUE';
      ALLOW_CONNECT='TRUE';
    'VSS_F64':
      PIN_NUMBER='(0,0,0,0,0,0,0,0,0,0,0,0,0,0,0,0,0,0,0,0,0,0,0,0,0,0,0,F64,0,0,0,0,0,0,0,0,0,0,0,0)';
      PINUSE='POWER';
      NO_LOAD_CHECK='Both';
      NO_IO_CHECK='Both';
      NO_ASSERT_CHECK='TRUE';
      NO_DIR_CHECK='TRUE';
      ALLOW_CONNECT='TRUE';
    'VSS_F66':
      PIN_NUMBER='(0,0,0,0,0,0,0,0,0,0,0,0,0,0,0,0,0,0,0,0,0,0,0,0,0,0,0,F66,0,0,0,0,0,0,0,0,0,0,0,0)';
      PINUSE='POWER';
      NO_LOAD_CHECK='Both';
      NO_IO_CHECK='Both';
      NO_ASSERT_CHECK='TRUE';
      NO_DIR_CHECK='TRUE';
      ALLOW_CONNECT='TRUE';
    'VSS_F68':
      PIN_NUMBER='(0,0,0,0,0,0,0,0,0,0,0,0,0,0,0,0,0,0,0,0,0,0,0,0,0,0,0,F68,0,0,0,0,0,0,0,0,0,0,0,0)';
      PINUSE='POWER';
      NO_LOAD_CHECK='Both';
      NO_IO_CHECK='Both';
      NO_ASSERT_CHECK='TRUE';
      NO_DIR_CHECK='TRUE';
      ALLOW_CONNECT='TRUE';
    'VSS_F71':
      PIN_NUMBER='(0,0,0,0,0,0,0,0,0,0,0,0,0,0,0,0,0,0,0,0,0,0,0,0,0,0,0,F71,0,0,0,0,0,0,0,0,0,0,0,0)';
      PINUSE='POWER';
      NO_LOAD_CHECK='Both';
      NO_IO_CHECK='Both';
      NO_ASSERT_CHECK='TRUE';
      NO_DIR_CHECK='TRUE';
      ALLOW_CONNECT='TRUE';
    'VSS_F73':
      PIN_NUMBER='(0,0,0,0,0,0,0,0,0,0,0,0,0,0,0,0,0,0,0,0,0,0,0,0,0,0,0,F73,0,0,0,0,0,0,0,0,0,0,0,0)';
      PINUSE='POWER';
      NO_LOAD_CHECK='Both';
      NO_IO_CHECK='Both';
      NO_ASSERT_CHECK='TRUE';
      NO_DIR_CHECK='TRUE';
      ALLOW_CONNECT='TRUE';
    'VSS_G1':
      PIN_NUMBER='(0,0,0,0,0,0,0,0,0,0,0,0,0,0,0,0,0,0,0,0,0,0,0,0,0,0,0,G1,0,0,0,0,0,0,0,0,0,0,0,0)';
      PINUSE='POWER';
      NO_LOAD_CHECK='Both';
      NO_IO_CHECK='Both';
      NO_ASSERT_CHECK='TRUE';
      NO_DIR_CHECK='TRUE';
      ALLOW_CONNECT='TRUE';
    'VSS_G4':
      PIN_NUMBER='(0,0,0,0,0,0,0,0,0,0,0,0,0,0,0,0,0,0,0,0,0,0,0,0,0,0,0,G4,0,0,0,0,0,0,0,0,0,0,0,0)';
      PINUSE='POWER';
      NO_LOAD_CHECK='Both';
      NO_IO_CHECK='Both';
      NO_ASSERT_CHECK='TRUE';
      NO_DIR_CHECK='TRUE';
      ALLOW_CONNECT='TRUE';
    'VSS_G6':
      PIN_NUMBER='(0,0,0,0,0,0,0,0,0,0,0,0,0,0,0,0,0,0,0,0,0,0,0,0,0,0,0,G6,0,0,0,0,0,0,0,0,0,0,0,0)';
      PINUSE='POWER';
      NO_LOAD_CHECK='Both';
      NO_IO_CHECK='Both';
      NO_ASSERT_CHECK='TRUE';
      NO_DIR_CHECK='TRUE';
      ALLOW_CONNECT='TRUE';
    'VSS_G8':
      PIN_NUMBER='(0,0,0,0,0,0,0,0,0,0,0,0,0,0,0,0,0,0,0,0,0,0,0,0,0,0,0,G8,0,0,0,0,0,0,0,0,0,0,0,0)';
      PINUSE='POWER';
      NO_LOAD_CHECK='Both';
      NO_IO_CHECK='Both';
      NO_ASSERT_CHECK='TRUE';
      NO_DIR_CHECK='TRUE';
      ALLOW_CONNECT='TRUE';
    'VSS_G11':
      PIN_NUMBER='(0,0,0,0,0,0,0,0,0,0,0,0,0,0,0,0,0,0,0,0,0,0,0,0,0,0,0,G11,0,0,0,0,0,0,0,0,0,0,0,0)';
      PINUSE='POWER';
      NO_LOAD_CHECK='Both';
      NO_IO_CHECK='Both';
      NO_ASSERT_CHECK='TRUE';
      NO_DIR_CHECK='TRUE';
      ALLOW_CONNECT='TRUE';
    'VSS_G13':
      PIN_NUMBER='(0,0,0,0,0,0,0,0,0,0,0,0,0,0,0,0,0,0,0,0,0,0,0,0,0,0,0,G13,0,0,0,0,0,0,0,0,0,0,0,0)';
      PINUSE='POWER';
      NO_LOAD_CHECK='Both';
      NO_IO_CHECK='Both';
      NO_ASSERT_CHECK='TRUE';
      NO_DIR_CHECK='TRUE';
      ALLOW_CONNECT='TRUE';
    'VSS_G15':
      PIN_NUMBER='(0,0,0,0,0,0,0,0,0,0,0,0,0,0,0,0,0,0,0,0,0,0,0,0,0,0,0,G15,0,0,0,0,0,0,0,0,0,0,0,0)';
      PINUSE='POWER';
      NO_LOAD_CHECK='Both';
      NO_IO_CHECK='Both';
      NO_ASSERT_CHECK='TRUE';
      NO_DIR_CHECK='TRUE';
      ALLOW_CONNECT='TRUE';
    'VSS_G18':
      PIN_NUMBER='(0,0,0,0,0,0,0,0,0,0,0,0,0,0,0,0,0,0,0,0,0,0,0,0,0,0,0,G18,0,0,0,0,0,0,0,0,0,0,0,0)';
      PINUSE='POWER';
      NO_LOAD_CHECK='Both';
      NO_IO_CHECK='Both';
      NO_ASSERT_CHECK='TRUE';
      NO_DIR_CHECK='TRUE';
      ALLOW_CONNECT='TRUE';
    'VSS_G20':
      PIN_NUMBER='(0,0,0,0,0,0,0,0,0,0,0,0,0,0,0,0,0,0,0,0,0,0,0,0,0,0,0,G20,0,0,0,0,0,0,0,0,0,0,0,0)';
      PINUSE='POWER';
      NO_LOAD_CHECK='Both';
      NO_IO_CHECK='Both';
      NO_ASSERT_CHECK='TRUE';
      NO_DIR_CHECK='TRUE';
      ALLOW_CONNECT='TRUE';
    'VSS_G22':
      PIN_NUMBER='(0,0,0,0,0,0,0,0,0,0,0,0,0,0,0,0,0,0,0,0,0,0,0,0,0,0,0,G22,0,0,0,0,0,0,0,0,0,0,0,0)';
      PINUSE='POWER';
      NO_LOAD_CHECK='Both';
      NO_IO_CHECK='Both';
      NO_ASSERT_CHECK='TRUE';
      NO_DIR_CHECK='TRUE';
      ALLOW_CONNECT='TRUE';
    'VSS_G25':
      PIN_NUMBER='(0,0,0,0,0,0,0,0,0,0,0,0,0,0,0,0,0,0,0,0,0,0,0,0,0,0,0,G25,0,0,0,0,0,0,0,0,0,0,0,0)';
      PINUSE='POWER';
      NO_LOAD_CHECK='Both';
      NO_IO_CHECK='Both';
      NO_ASSERT_CHECK='TRUE';
      NO_DIR_CHECK='TRUE';
      ALLOW_CONNECT='TRUE';
    'VSS_G28':
      PIN_NUMBER='(0,0,0,0,0,0,0,0,0,0,0,0,0,0,0,0,0,0,0,0,0,0,0,0,0,0,0,G28,0,0,0,0,0,0,0,0,0,0,0,0)';
      PINUSE='POWER';
      NO_LOAD_CHECK='Both';
      NO_IO_CHECK='Both';
      NO_ASSERT_CHECK='TRUE';
      NO_DIR_CHECK='TRUE';
      ALLOW_CONNECT='TRUE';
    'VSS_G31':
      PIN_NUMBER='(0,0,0,0,0,0,0,0,0,0,0,0,0,0,0,0,0,0,0,0,0,0,0,0,0,0,0,G31,0,0,0,0,0,0,0,0,0,0,0,0)';
      PINUSE='POWER';
      NO_LOAD_CHECK='Both';
      NO_IO_CHECK='Both';
      NO_ASSERT_CHECK='TRUE';
      NO_DIR_CHECK='TRUE';
      ALLOW_CONNECT='TRUE';
    'VSS_G34':
      PIN_NUMBER='(0,0,0,0,0,0,0,0,0,0,0,0,0,0,0,0,0,0,0,0,0,0,0,0,0,0,0,G34,0,0,0,0,0,0,0,0,0,0,0,0)';
      PINUSE='POWER';
      NO_LOAD_CHECK='Both';
      NO_IO_CHECK='Both';
      NO_ASSERT_CHECK='TRUE';
      NO_DIR_CHECK='TRUE';
      ALLOW_CONNECT='TRUE';
    'VSS_G42':
      PIN_NUMBER='(0,0,0,0,0,0,0,0,0,0,0,0,0,0,0,0,0,0,0,0,0,0,0,0,0,0,0,G42,0,0,0,0,0,0,0,0,0,0,0,0)';
      PINUSE='POWER';
      NO_LOAD_CHECK='Both';
      NO_IO_CHECK='Both';
      NO_ASSERT_CHECK='TRUE';
      NO_DIR_CHECK='TRUE';
      ALLOW_CONNECT='TRUE';
    'VSS_G45':
      PIN_NUMBER='(0,0,0,0,0,0,0,0,0,0,0,0,0,0,0,0,0,0,0,0,0,0,0,0,0,0,0,G45,0,0,0,0,0,0,0,0,0,0,0,0)';
      PINUSE='POWER';
      NO_LOAD_CHECK='Both';
      NO_IO_CHECK='Both';
      NO_ASSERT_CHECK='TRUE';
      NO_DIR_CHECK='TRUE';
      ALLOW_CONNECT='TRUE';
    'VSS_G48':
      PIN_NUMBER='(0,0,0,0,0,0,0,0,0,0,0,0,0,0,0,0,0,0,0,0,0,0,0,0,0,0,0,G48,0,0,0,0,0,0,0,0,0,0,0,0)';
      PINUSE='POWER';
      NO_LOAD_CHECK='Both';
      NO_IO_CHECK='Both';
      NO_ASSERT_CHECK='TRUE';
      NO_DIR_CHECK='TRUE';
      ALLOW_CONNECT='TRUE';
    'VSS_G51':
      PIN_NUMBER='(0,0,0,0,0,0,0,0,0,0,0,0,0,0,0,0,0,0,0,0,0,0,0,0,0,0,0,G51,0,0,0,0,0,0,0,0,0,0,0,0)';
      PINUSE='POWER';
      NO_LOAD_CHECK='Both';
      NO_IO_CHECK='Both';
      NO_ASSERT_CHECK='TRUE';
      NO_DIR_CHECK='TRUE';
      ALLOW_CONNECT='TRUE';
    'VSS_G54':
      PIN_NUMBER='(0,0,0,0,0,0,0,0,0,0,0,0,0,0,0,0,0,0,0,0,0,0,0,0,0,0,0,G54,0,0,0,0,0,0,0,0,0,0,0,0)';
      PINUSE='POWER';
      NO_LOAD_CHECK='Both';
      NO_IO_CHECK='Both';
      NO_ASSERT_CHECK='TRUE';
      NO_DIR_CHECK='TRUE';
      ALLOW_CONNECT='TRUE';
    'VSS_G56':
      PIN_NUMBER='(0,0,0,0,0,0,0,0,0,0,0,0,0,0,0,0,0,0,0,0,0,0,0,0,0,0,0,G56,0,0,0,0,0,0,0,0,0,0,0,0)';
      PINUSE='POWER';
      NO_LOAD_CHECK='Both';
      NO_IO_CHECK='Both';
      NO_ASSERT_CHECK='TRUE';
      NO_DIR_CHECK='TRUE';
      ALLOW_CONNECT='TRUE';
    'VSS_G58':
      PIN_NUMBER='(0,0,0,0,0,0,0,0,0,0,0,0,0,0,0,0,0,0,0,0,0,0,0,0,0,0,0,G58,0,0,0,0,0,0,0,0,0,0,0,0)';
      PINUSE='POWER';
      NO_LOAD_CHECK='Both';
      NO_IO_CHECK='Both';
      NO_ASSERT_CHECK='TRUE';
      NO_DIR_CHECK='TRUE';
      ALLOW_CONNECT='TRUE';
    'VSS_G61':
      PIN_NUMBER='(0,0,0,0,0,0,0,0,0,0,0,0,0,0,0,0,0,0,0,0,0,0,0,0,0,0,0,G61,0,0,0,0,0,0,0,0,0,0,0,0)';
      PINUSE='POWER';
      NO_LOAD_CHECK='Both';
      NO_IO_CHECK='Both';
      NO_ASSERT_CHECK='TRUE';
      NO_DIR_CHECK='TRUE';
      ALLOW_CONNECT='TRUE';
    'VSS_G63':
      PIN_NUMBER='(0,0,0,0,0,0,0,0,0,0,0,0,0,0,0,0,0,0,0,0,0,0,0,0,0,0,0,G63,0,0,0,0,0,0,0,0,0,0,0,0)';
      PINUSE='POWER';
      NO_LOAD_CHECK='Both';
      NO_IO_CHECK='Both';
      NO_ASSERT_CHECK='TRUE';
      NO_DIR_CHECK='TRUE';
      ALLOW_CONNECT='TRUE';
    'VSS_G65':
      PIN_NUMBER='(0,0,0,0,0,0,0,0,0,0,0,0,0,0,0,0,0,0,0,0,0,0,0,0,0,0,0,G65,0,0,0,0,0,0,0,0,0,0,0,0)';
      PINUSE='POWER';
      NO_LOAD_CHECK='Both';
      NO_IO_CHECK='Both';
      NO_ASSERT_CHECK='TRUE';
      NO_DIR_CHECK='TRUE';
      ALLOW_CONNECT='TRUE';
    'VSS_G68':
      PIN_NUMBER='(0,0,0,0,0,0,0,0,0,0,0,0,0,0,0,0,0,0,0,0,0,0,0,0,0,0,0,G68,0,0,0,0,0,0,0,0,0,0,0,0)';
      PINUSE='POWER';
      NO_LOAD_CHECK='Both';
      NO_IO_CHECK='Both';
      NO_ASSERT_CHECK='TRUE';
      NO_DIR_CHECK='TRUE';
      ALLOW_CONNECT='TRUE';
    'VSS_G70':
      PIN_NUMBER='(0,0,0,0,0,0,0,0,0,0,0,0,0,0,0,0,0,0,0,0,0,0,0,0,0,0,0,G70,0,0,0,0,0,0,0,0,0,0,0,0)';
      PINUSE='POWER';
      NO_LOAD_CHECK='Both';
      NO_IO_CHECK='Both';
      NO_ASSERT_CHECK='TRUE';
      NO_DIR_CHECK='TRUE';
      ALLOW_CONNECT='TRUE';
    'VSS_G72':
      PIN_NUMBER='(0,0,0,0,0,0,0,0,0,0,0,0,0,0,0,0,0,0,0,0,0,0,0,0,0,0,0,G72,0,0,0,0,0,0,0,0,0,0,0,0)';
      PINUSE='POWER';
      NO_LOAD_CHECK='Both';
      NO_IO_CHECK='Both';
      NO_ASSERT_CHECK='TRUE';
      NO_DIR_CHECK='TRUE';
      ALLOW_CONNECT='TRUE';
    'VSS_G75':
      PIN_NUMBER='(0,0,0,0,0,0,0,0,0,0,0,0,0,0,0,0,0,0,0,0,0,0,0,0,0,0,0,G75,0,0,0,0,0,0,0,0,0,0,0,0)';
      PINUSE='POWER';
      NO_LOAD_CHECK='Both';
      NO_IO_CHECK='Both';
      NO_ASSERT_CHECK='TRUE';
      NO_DIR_CHECK='TRUE';
      ALLOW_CONNECT='TRUE';
    'VSS_H3':
      PIN_NUMBER='(0,0,0,0,0,0,0,0,0,0,0,0,0,0,0,0,0,0,0,0,0,0,0,0,0,0,0,H3,0,0,0,0,0,0,0,0,0,0,0,0)';
      PINUSE='POWER';
      NO_LOAD_CHECK='Both';
      NO_IO_CHECK='Both';
      NO_ASSERT_CHECK='TRUE';
      NO_DIR_CHECK='TRUE';
      ALLOW_CONNECT='TRUE';
    'VSS_H8':
      PIN_NUMBER='(0,0,0,0,0,0,0,0,0,0,0,0,0,0,0,0,0,0,0,0,0,0,0,0,0,0,0,H8,0,0,0,0,0,0,0,0,0,0,0,0)';
      PINUSE='POWER';
      NO_LOAD_CHECK='Both';
      NO_IO_CHECK='Both';
      NO_ASSERT_CHECK='TRUE';
      NO_DIR_CHECK='TRUE';
      ALLOW_CONNECT='TRUE';
    'VSS_H10':
      PIN_NUMBER='(0,0,0,0,0,0,0,0,0,0,0,0,0,0,0,0,0,0,0,0,0,0,0,0,0,0,0,H10,0,0,0,0,0,0,0,0,0,0,0,0)';
      PINUSE='POWER';
      NO_LOAD_CHECK='Both';
      NO_IO_CHECK='Both';
      NO_ASSERT_CHECK='TRUE';
      NO_DIR_CHECK='TRUE';
      ALLOW_CONNECT='TRUE';
    'VSS_H15':
      PIN_NUMBER='(0,0,0,0,0,0,0,0,0,0,0,0,0,0,0,0,0,0,0,0,0,0,0,0,0,0,0,H15,0,0,0,0,0,0,0,0,0,0,0,0)';
      PINUSE='POWER';
      NO_LOAD_CHECK='Both';
      NO_IO_CHECK='Both';
      NO_ASSERT_CHECK='TRUE';
      NO_DIR_CHECK='TRUE';
      ALLOW_CONNECT='TRUE';
    'VSS_H17':
      PIN_NUMBER='(0,0,0,0,0,0,0,0,0,0,0,0,0,0,0,0,0,0,0,0,0,0,0,0,0,0,0,H17,0,0,0,0,0,0,0,0,0,0,0,0)';
      PINUSE='POWER';
      NO_LOAD_CHECK='Both';
      NO_IO_CHECK='Both';
      NO_ASSERT_CHECK='TRUE';
      NO_DIR_CHECK='TRUE';
      ALLOW_CONNECT='TRUE';
    'VSS_H22':
      PIN_NUMBER='(0,0,0,0,0,0,0,0,0,0,0,0,0,0,0,0,0,0,0,0,0,0,0,0,0,0,0,H22,0,0,0,0,0,0,0,0,0,0,0,0)';
      PINUSE='POWER';
      NO_LOAD_CHECK='Both';
      NO_IO_CHECK='Both';
      NO_ASSERT_CHECK='TRUE';
      NO_DIR_CHECK='TRUE';
      ALLOW_CONNECT='TRUE';
    'VSS_H25':
      PIN_NUMBER='(0,0,0,0,0,0,0,0,0,0,0,0,0,0,0,0,0,0,0,0,0,0,0,0,0,0,0,H25,0,0,0,0,0,0,0,0,0,0,0,0)';
      PINUSE='POWER';
      NO_LOAD_CHECK='Both';
      NO_IO_CHECK='Both';
      NO_ASSERT_CHECK='TRUE';
      NO_DIR_CHECK='TRUE';
      ALLOW_CONNECT='TRUE';
    'VSS_H28':
      PIN_NUMBER='(0,0,0,0,0,0,0,0,0,0,0,0,0,0,0,0,0,0,0,0,0,0,0,0,0,0,0,H28,0,0,0,0,0,0,0,0,0,0,0,0)';
      PINUSE='POWER';
      NO_LOAD_CHECK='Both';
      NO_IO_CHECK='Both';
      NO_ASSERT_CHECK='TRUE';
      NO_DIR_CHECK='TRUE';
      ALLOW_CONNECT='TRUE';
    'VSS_H31':
      PIN_NUMBER='(0,0,0,0,0,0,0,0,0,0,0,0,0,0,0,0,0,0,0,0,0,0,0,0,0,0,0,H31,0,0,0,0,0,0,0,0,0,0,0,0)';
      PINUSE='POWER';
      NO_LOAD_CHECK='Both';
      NO_IO_CHECK='Both';
      NO_ASSERT_CHECK='TRUE';
      NO_DIR_CHECK='TRUE';
      ALLOW_CONNECT='TRUE';
    'VSS_H34':
      PIN_NUMBER='(0,0,0,0,0,0,0,0,0,0,0,0,0,0,0,0,0,0,0,0,0,0,0,0,0,0,0,H34,0,0,0,0,0,0,0,0,0,0,0,0)';
      PINUSE='POWER';
      NO_LOAD_CHECK='Both';
      NO_IO_CHECK='Both';
      NO_ASSERT_CHECK='TRUE';
      NO_DIR_CHECK='TRUE';
      ALLOW_CONNECT='TRUE';
    'VSS_R48':
      PIN_NUMBER='(0,0,0,0,0,0,0,0,0,0,0,0,0,0,0,0,0,0,0,0,0,0,0,0,0,0,0,0,R48,0,0,0,0,0,0,0,0,0,0,0)';
      PINUSE='POWER';
      NO_LOAD_CHECK='Both';
      NO_IO_CHECK='Both';
      NO_ASSERT_CHECK='TRUE';
      NO_DIR_CHECK='TRUE';
      ALLOW_CONNECT='TRUE';
    'VSS_R51':
      PIN_NUMBER='(0,0,0,0,0,0,0,0,0,0,0,0,0,0,0,0,0,0,0,0,0,0,0,0,0,0,0,0,R51,0,0,0,0,0,0,0,0,0,0,0)';
      PINUSE='POWER';
      NO_LOAD_CHECK='Both';
      NO_IO_CHECK='Both';
      NO_ASSERT_CHECK='TRUE';
      NO_DIR_CHECK='TRUE';
      ALLOW_CONNECT='TRUE';
    'VSS_R54':
      PIN_NUMBER='(0,0,0,0,0,0,0,0,0,0,0,0,0,0,0,0,0,0,0,0,0,0,0,0,0,0,0,0,R54,0,0,0,0,0,0,0,0,0,0,0)';
      PINUSE='POWER';
      NO_LOAD_CHECK='Both';
      NO_IO_CHECK='Both';
      NO_ASSERT_CHECK='TRUE';
      NO_DIR_CHECK='TRUE';
      ALLOW_CONNECT='TRUE';
    'VSS_R56':
      PIN_NUMBER='(0,0,0,0,0,0,0,0,0,0,0,0,0,0,0,0,0,0,0,0,0,0,0,0,0,0,0,0,R56,0,0,0,0,0,0,0,0,0,0,0)';
      PINUSE='POWER';
      NO_LOAD_CHECK='Both';
      NO_IO_CHECK='Both';
      NO_ASSERT_CHECK='TRUE';
      NO_DIR_CHECK='TRUE';
      ALLOW_CONNECT='TRUE';
    'VSS_R58':
      PIN_NUMBER='(0,0,0,0,0,0,0,0,0,0,0,0,0,0,0,0,0,0,0,0,0,0,0,0,0,0,0,0,R58,0,0,0,0,0,0,0,0,0,0,0)';
      PINUSE='POWER';
      NO_LOAD_CHECK='Both';
      NO_IO_CHECK='Both';
      NO_ASSERT_CHECK='TRUE';
      NO_DIR_CHECK='TRUE';
      ALLOW_CONNECT='TRUE';
    'VSS_R61':
      PIN_NUMBER='(0,0,0,0,0,0,0,0,0,0,0,0,0,0,0,0,0,0,0,0,0,0,0,0,0,0,0,0,R61,0,0,0,0,0,0,0,0,0,0,0)';
      PINUSE='POWER';
      NO_LOAD_CHECK='Both';
      NO_IO_CHECK='Both';
      NO_ASSERT_CHECK='TRUE';
      NO_DIR_CHECK='TRUE';
      ALLOW_CONNECT='TRUE';
    'VSS_R63':
      PIN_NUMBER='(0,0,0,0,0,0,0,0,0,0,0,0,0,0,0,0,0,0,0,0,0,0,0,0,0,0,0,0,R63,0,0,0,0,0,0,0,0,0,0,0)';
      PINUSE='POWER';
      NO_LOAD_CHECK='Both';
      NO_IO_CHECK='Both';
      NO_ASSERT_CHECK='TRUE';
      NO_DIR_CHECK='TRUE';
      ALLOW_CONNECT='TRUE';
    'VSS_R65':
      PIN_NUMBER='(0,0,0,0,0,0,0,0,0,0,0,0,0,0,0,0,0,0,0,0,0,0,0,0,0,0,0,0,R65,0,0,0,0,0,0,0,0,0,0,0)';
      PINUSE='POWER';
      NO_LOAD_CHECK='Both';
      NO_IO_CHECK='Both';
      NO_ASSERT_CHECK='TRUE';
      NO_DIR_CHECK='TRUE';
      ALLOW_CONNECT='TRUE';
    'VSS_R68':
      PIN_NUMBER='(0,0,0,0,0,0,0,0,0,0,0,0,0,0,0,0,0,0,0,0,0,0,0,0,0,0,0,0,R68,0,0,0,0,0,0,0,0,0,0,0)';
      PINUSE='POWER';
      NO_LOAD_CHECK='Both';
      NO_IO_CHECK='Both';
      NO_ASSERT_CHECK='TRUE';
      NO_DIR_CHECK='TRUE';
      ALLOW_CONNECT='TRUE';
    'VSS_R70':
      PIN_NUMBER='(0,0,0,0,0,0,0,0,0,0,0,0,0,0,0,0,0,0,0,0,0,0,0,0,0,0,0,0,R70,0,0,0,0,0,0,0,0,0,0,0)';
      PINUSE='POWER';
      NO_LOAD_CHECK='Both';
      NO_IO_CHECK='Both';
      NO_ASSERT_CHECK='TRUE';
      NO_DIR_CHECK='TRUE';
      ALLOW_CONNECT='TRUE';
    'VSS_R72':
      PIN_NUMBER='(0,0,0,0,0,0,0,0,0,0,0,0,0,0,0,0,0,0,0,0,0,0,0,0,0,0,0,0,R72,0,0,0,0,0,0,0,0,0,0,0)';
      PINUSE='POWER';
      NO_LOAD_CHECK='Both';
      NO_IO_CHECK='Both';
      NO_ASSERT_CHECK='TRUE';
      NO_DIR_CHECK='TRUE';
      ALLOW_CONNECT='TRUE';
    'VSS_R75':
      PIN_NUMBER='(0,0,0,0,0,0,0,0,0,0,0,0,0,0,0,0,0,0,0,0,0,0,0,0,0,0,0,0,R75,0,0,0,0,0,0,0,0,0,0,0)';
      PINUSE='POWER';
      NO_LOAD_CHECK='Both';
      NO_IO_CHECK='Both';
      NO_ASSERT_CHECK='TRUE';
      NO_DIR_CHECK='TRUE';
      ALLOW_CONNECT='TRUE';
    'VSS_T3':
      PIN_NUMBER='(0,0,0,0,0,0,0,0,0,0,0,0,0,0,0,0,0,0,0,0,0,0,0,0,0,0,0,0,T3,0,0,0,0,0,0,0,0,0,0,0)';
      PINUSE='POWER';
      NO_LOAD_CHECK='Both';
      NO_IO_CHECK='Both';
      NO_ASSERT_CHECK='TRUE';
      NO_DIR_CHECK='TRUE';
      ALLOW_CONNECT='TRUE';
    'VSS_T5':
      PIN_NUMBER='(0,0,0,0,0,0,0,0,0,0,0,0,0,0,0,0,0,0,0,0,0,0,0,0,0,0,0,0,T5,0,0,0,0,0,0,0,0,0,0,0)';
      PINUSE='POWER';
      NO_LOAD_CHECK='Both';
      NO_IO_CHECK='Both';
      NO_ASSERT_CHECK='TRUE';
      NO_DIR_CHECK='TRUE';
      ALLOW_CONNECT='TRUE';
    'VSS_T8':
      PIN_NUMBER='(0,0,0,0,0,0,0,0,0,0,0,0,0,0,0,0,0,0,0,0,0,0,0,0,0,0,0,0,T8,0,0,0,0,0,0,0,0,0,0,0)';
      PINUSE='POWER';
      NO_LOAD_CHECK='Both';
      NO_IO_CHECK='Both';
      NO_ASSERT_CHECK='TRUE';
      NO_DIR_CHECK='TRUE';
      ALLOW_CONNECT='TRUE';
    'VSS_T10':
      PIN_NUMBER='(0,0,0,0,0,0,0,0,0,0,0,0,0,0,0,0,0,0,0,0,0,0,0,0,0,0,0,0,T10,0,0,0,0,0,0,0,0,0,0,0)';
      PINUSE='POWER';
      NO_LOAD_CHECK='Both';
      NO_IO_CHECK='Both';
      NO_ASSERT_CHECK='TRUE';
      NO_DIR_CHECK='TRUE';
      ALLOW_CONNECT='TRUE';
    'VSS_T12':
      PIN_NUMBER='(0,0,0,0,0,0,0,0,0,0,0,0,0,0,0,0,0,0,0,0,0,0,0,0,0,0,0,0,T12,0,0,0,0,0,0,0,0,0,0,0)';
      PINUSE='POWER';
      NO_LOAD_CHECK='Both';
      NO_IO_CHECK='Both';
      NO_ASSERT_CHECK='TRUE';
      NO_DIR_CHECK='TRUE';
      ALLOW_CONNECT='TRUE';
    'VSS_T15':
      PIN_NUMBER='(0,0,0,0,0,0,0,0,0,0,0,0,0,0,0,0,0,0,0,0,0,0,0,0,0,0,0,0,T15,0,0,0,0,0,0,0,0,0,0,0)';
      PINUSE='POWER';
      NO_LOAD_CHECK='Both';
      NO_IO_CHECK='Both';
      NO_ASSERT_CHECK='TRUE';
      NO_DIR_CHECK='TRUE';
      ALLOW_CONNECT='TRUE';
    'VSS_T17':
      PIN_NUMBER='(0,0,0,0,0,0,0,0,0,0,0,0,0,0,0,0,0,0,0,0,0,0,0,0,0,0,0,0,T17,0,0,0,0,0,0,0,0,0,0,0)';
      PINUSE='POWER';
      NO_LOAD_CHECK='Both';
      NO_IO_CHECK='Both';
      NO_ASSERT_CHECK='TRUE';
      NO_DIR_CHECK='TRUE';
      ALLOW_CONNECT='TRUE';
    'VSS_T19':
      PIN_NUMBER='(0,0,0,0,0,0,0,0,0,0,0,0,0,0,0,0,0,0,0,0,0,0,0,0,0,0,0,0,T19,0,0,0,0,0,0,0,0,0,0,0)';
      PINUSE='POWER';
      NO_LOAD_CHECK='Both';
      NO_IO_CHECK='Both';
      NO_ASSERT_CHECK='TRUE';
      NO_DIR_CHECK='TRUE';
      ALLOW_CONNECT='TRUE';
    'VSS_T22':
      PIN_NUMBER='(0,0,0,0,0,0,0,0,0,0,0,0,0,0,0,0,0,0,0,0,0,0,0,0,0,0,0,0,T22,0,0,0,0,0,0,0,0,0,0,0)';
      PINUSE='POWER';
      NO_LOAD_CHECK='Both';
      NO_IO_CHECK='Both';
      NO_ASSERT_CHECK='TRUE';
      NO_DIR_CHECK='TRUE';
      ALLOW_CONNECT='TRUE';
    'VSS_T25':
      PIN_NUMBER='(0,0,0,0,0,0,0,0,0,0,0,0,0,0,0,0,0,0,0,0,0,0,0,0,0,0,0,0,T25,0,0,0,0,0,0,0,0,0,0,0)';
      PINUSE='POWER';
      NO_LOAD_CHECK='Both';
      NO_IO_CHECK='Both';
      NO_ASSERT_CHECK='TRUE';
      NO_DIR_CHECK='TRUE';
      ALLOW_CONNECT='TRUE';
    'VSS_T28':
      PIN_NUMBER='(0,0,0,0,0,0,0,0,0,0,0,0,0,0,0,0,0,0,0,0,0,0,0,0,0,0,0,0,T28,0,0,0,0,0,0,0,0,0,0,0)';
      PINUSE='POWER';
      NO_LOAD_CHECK='Both';
      NO_IO_CHECK='Both';
      NO_ASSERT_CHECK='TRUE';
      NO_DIR_CHECK='TRUE';
      ALLOW_CONNECT='TRUE';
    'VSS_T31':
      PIN_NUMBER='(0,0,0,0,0,0,0,0,0,0,0,0,0,0,0,0,0,0,0,0,0,0,0,0,0,0,0,0,T31,0,0,0,0,0,0,0,0,0,0,0)';
      PINUSE='POWER';
      NO_LOAD_CHECK='Both';
      NO_IO_CHECK='Both';
      NO_ASSERT_CHECK='TRUE';
      NO_DIR_CHECK='TRUE';
      ALLOW_CONNECT='TRUE';
    'VSS_T34':
      PIN_NUMBER='(0,0,0,0,0,0,0,0,0,0,0,0,0,0,0,0,0,0,0,0,0,0,0,0,0,0,0,0,T34,0,0,0,0,0,0,0,0,0,0,0)';
      PINUSE='POWER';
      NO_LOAD_CHECK='Both';
      NO_IO_CHECK='Both';
      NO_ASSERT_CHECK='TRUE';
      NO_DIR_CHECK='TRUE';
      ALLOW_CONNECT='TRUE';
    'VSS_T37':
      PIN_NUMBER='(0,0,0,0,0,0,0,0,0,0,0,0,0,0,0,0,0,0,0,0,0,0,0,0,0,0,0,0,T37,0,0,0,0,0,0,0,0,0,0,0)';
      PINUSE='POWER';
      NO_LOAD_CHECK='Both';
      NO_IO_CHECK='Both';
      NO_ASSERT_CHECK='TRUE';
      NO_DIR_CHECK='TRUE';
      ALLOW_CONNECT='TRUE';
    'VSS_T39':
      PIN_NUMBER='(0,0,0,0,0,0,0,0,0,0,0,0,0,0,0,0,0,0,0,0,0,0,0,0,0,0,0,0,T39,0,0,0,0,0,0,0,0,0,0,0)';
      PINUSE='POWER';
      NO_LOAD_CHECK='Both';
      NO_IO_CHECK='Both';
      NO_ASSERT_CHECK='TRUE';
      NO_DIR_CHECK='TRUE';
      ALLOW_CONNECT='TRUE';
    'VSS_T42':
      PIN_NUMBER='(0,0,0,0,0,0,0,0,0,0,0,0,0,0,0,0,0,0,0,0,0,0,0,0,0,0,0,0,T42,0,0,0,0,0,0,0,0,0,0,0)';
      PINUSE='POWER';
      NO_LOAD_CHECK='Both';
      NO_IO_CHECK='Both';
      NO_ASSERT_CHECK='TRUE';
      NO_DIR_CHECK='TRUE';
      ALLOW_CONNECT='TRUE';
    'VSS_T45':
      PIN_NUMBER='(0,0,0,0,0,0,0,0,0,0,0,0,0,0,0,0,0,0,0,0,0,0,0,0,0,0,0,0,T45,0,0,0,0,0,0,0,0,0,0,0)';
      PINUSE='POWER';
      NO_LOAD_CHECK='Both';
      NO_IO_CHECK='Both';
      NO_ASSERT_CHECK='TRUE';
      NO_DIR_CHECK='TRUE';
      ALLOW_CONNECT='TRUE';
    'VSS_T48':
      PIN_NUMBER='(0,0,0,0,0,0,0,0,0,0,0,0,0,0,0,0,0,0,0,0,0,0,0,0,0,0,0,0,T48,0,0,0,0,0,0,0,0,0,0,0)';
      PINUSE='POWER';
      NO_LOAD_CHECK='Both';
      NO_IO_CHECK='Both';
      NO_ASSERT_CHECK='TRUE';
      NO_DIR_CHECK='TRUE';
      ALLOW_CONNECT='TRUE';
    'VSS_T51':
      PIN_NUMBER='(0,0,0,0,0,0,0,0,0,0,0,0,0,0,0,0,0,0,0,0,0,0,0,0,0,0,0,0,T51,0,0,0,0,0,0,0,0,0,0,0)';
      PINUSE='POWER';
      NO_LOAD_CHECK='Both';
      NO_IO_CHECK='Both';
      NO_ASSERT_CHECK='TRUE';
      NO_DIR_CHECK='TRUE';
      ALLOW_CONNECT='TRUE';
    'VSS_T54':
      PIN_NUMBER='(0,0,0,0,0,0,0,0,0,0,0,0,0,0,0,0,0,0,0,0,0,0,0,0,0,0,0,0,T54,0,0,0,0,0,0,0,0,0,0,0)';
      PINUSE='POWER';
      NO_LOAD_CHECK='Both';
      NO_IO_CHECK='Both';
      NO_ASSERT_CHECK='TRUE';
      NO_DIR_CHECK='TRUE';
      ALLOW_CONNECT='TRUE';
    'VSS_T57':
      PIN_NUMBER='(0,0,0,0,0,0,0,0,0,0,0,0,0,0,0,0,0,0,0,0,0,0,0,0,0,0,0,0,T57,0,0,0,0,0,0,0,0,0,0,0)';
      PINUSE='POWER';
      NO_LOAD_CHECK='Both';
      NO_IO_CHECK='Both';
      NO_ASSERT_CHECK='TRUE';
      NO_DIR_CHECK='TRUE';
      ALLOW_CONNECT='TRUE';
    'VSS_T59':
      PIN_NUMBER='(0,0,0,0,0,0,0,0,0,0,0,0,0,0,0,0,0,0,0,0,0,0,0,0,0,0,0,0,T59,0,0,0,0,0,0,0,0,0,0,0)';
      PINUSE='POWER';
      NO_LOAD_CHECK='Both';
      NO_IO_CHECK='Both';
      NO_ASSERT_CHECK='TRUE';
      NO_DIR_CHECK='TRUE';
      ALLOW_CONNECT='TRUE';
    'VSS_T61':
      PIN_NUMBER='(0,0,0,0,0,0,0,0,0,0,0,0,0,0,0,0,0,0,0,0,0,0,0,0,0,0,0,0,T61,0,0,0,0,0,0,0,0,0,0,0)';
      PINUSE='POWER';
      NO_LOAD_CHECK='Both';
      NO_IO_CHECK='Both';
      NO_ASSERT_CHECK='TRUE';
      NO_DIR_CHECK='TRUE';
      ALLOW_CONNECT='TRUE';
    'VSS_T64':
      PIN_NUMBER='(0,0,0,0,0,0,0,0,0,0,0,0,0,0,0,0,0,0,0,0,0,0,0,0,0,0,0,0,T64,0,0,0,0,0,0,0,0,0,0,0)';
      PINUSE='POWER';
      NO_LOAD_CHECK='Both';
      NO_IO_CHECK='Both';
      NO_ASSERT_CHECK='TRUE';
      NO_DIR_CHECK='TRUE';
      ALLOW_CONNECT='TRUE';
    'VSS_J15':
      PIN_NUMBER='(0,0,0,0,0,0,0,0,0,0,0,0,0,0,0,0,0,0,0,0,0,0,0,0,0,0,0,0,J15,0,0,0,0,0,0,0,0,0,0,0)';
      PINUSE='POWER';
      NO_LOAD_CHECK='Both';
      NO_IO_CHECK='Both';
      NO_ASSERT_CHECK='TRUE';
      NO_DIR_CHECK='TRUE';
      ALLOW_CONNECT='TRUE';
    'VSS_J18':
      PIN_NUMBER='(0,0,0,0,0,0,0,0,0,0,0,0,0,0,0,0,0,0,0,0,0,0,0,0,0,0,0,0,J18,0,0,0,0,0,0,0,0,0,0,0)';
      PINUSE='POWER';
      NO_LOAD_CHECK='Both';
      NO_IO_CHECK='Both';
      NO_ASSERT_CHECK='TRUE';
      NO_DIR_CHECK='TRUE';
      ALLOW_CONNECT='TRUE';
    'VSS_J20':
      PIN_NUMBER='(0,0,0,0,0,0,0,0,0,0,0,0,0,0,0,0,0,0,0,0,0,0,0,0,0,0,0,0,J20,0,0,0,0,0,0,0,0,0,0,0)';
      PINUSE='POWER';
      NO_LOAD_CHECK='Both';
      NO_IO_CHECK='Both';
      NO_ASSERT_CHECK='TRUE';
      NO_DIR_CHECK='TRUE';
      ALLOW_CONNECT='TRUE';
    'VSS_J22':
      PIN_NUMBER='(0,0,0,0,0,0,0,0,0,0,0,0,0,0,0,0,0,0,0,0,0,0,0,0,0,0,0,0,J22,0,0,0,0,0,0,0,0,0,0,0)';
      PINUSE='POWER';
      NO_LOAD_CHECK='Both';
      NO_IO_CHECK='Both';
      NO_ASSERT_CHECK='TRUE';
      NO_DIR_CHECK='TRUE';
      ALLOW_CONNECT='TRUE';
    'VSS_J25':
      PIN_NUMBER='(0,0,0,0,0,0,0,0,0,0,0,0,0,0,0,0,0,0,0,0,0,0,0,0,0,0,0,0,J25,0,0,0,0,0,0,0,0,0,0,0)';
      PINUSE='POWER';
      NO_LOAD_CHECK='Both';
      NO_IO_CHECK='Both';
      NO_ASSERT_CHECK='TRUE';
      NO_DIR_CHECK='TRUE';
      ALLOW_CONNECT='TRUE';
    'VSS_J28':
      PIN_NUMBER='(0,0,0,0,0,0,0,0,0,0,0,0,0,0,0,0,0,0,0,0,0,0,0,0,0,0,0,0,J28,0,0,0,0,0,0,0,0,0,0,0)';
      PINUSE='POWER';
      NO_LOAD_CHECK='Both';
      NO_IO_CHECK='Both';
      NO_ASSERT_CHECK='TRUE';
      NO_DIR_CHECK='TRUE';
      ALLOW_CONNECT='TRUE';
    'VSS_J31':
      PIN_NUMBER='(0,0,0,0,0,0,0,0,0,0,0,0,0,0,0,0,0,0,0,0,0,0,0,0,0,0,0,0,J31,0,0,0,0,0,0,0,0,0,0,0)';
      PINUSE='POWER';
      NO_LOAD_CHECK='Both';
      NO_IO_CHECK='Both';
      NO_ASSERT_CHECK='TRUE';
      NO_DIR_CHECK='TRUE';
      ALLOW_CONNECT='TRUE';
    'VSS_J34':
      PIN_NUMBER='(0,0,0,0,0,0,0,0,0,0,0,0,0,0,0,0,0,0,0,0,0,0,0,0,0,0,0,0,J34,0,0,0,0,0,0,0,0,0,0,0)';
      PINUSE='POWER';
      NO_LOAD_CHECK='Both';
      NO_IO_CHECK='Both';
      NO_ASSERT_CHECK='TRUE';
      NO_DIR_CHECK='TRUE';
      ALLOW_CONNECT='TRUE';
    'VSS_J42':
      PIN_NUMBER='(0,0,0,0,0,0,0,0,0,0,0,0,0,0,0,0,0,0,0,0,0,0,0,0,0,0,0,0,J42,0,0,0,0,0,0,0,0,0,0,0)';
      PINUSE='POWER';
      NO_LOAD_CHECK='Both';
      NO_IO_CHECK='Both';
      NO_ASSERT_CHECK='TRUE';
      NO_DIR_CHECK='TRUE';
      ALLOW_CONNECT='TRUE';
    'VSS_J45':
      PIN_NUMBER='(0,0,0,0,0,0,0,0,0,0,0,0,0,0,0,0,0,0,0,0,0,0,0,0,0,0,0,0,J45,0,0,0,0,0,0,0,0,0,0,0)';
      PINUSE='POWER';
      NO_LOAD_CHECK='Both';
      NO_IO_CHECK='Both';
      NO_ASSERT_CHECK='TRUE';
      NO_DIR_CHECK='TRUE';
      ALLOW_CONNECT='TRUE';
    'VSS_J48':
      PIN_NUMBER='(0,0,0,0,0,0,0,0,0,0,0,0,0,0,0,0,0,0,0,0,0,0,0,0,0,0,0,0,J48,0,0,0,0,0,0,0,0,0,0,0)';
      PINUSE='POWER';
      NO_LOAD_CHECK='Both';
      NO_IO_CHECK='Both';
      NO_ASSERT_CHECK='TRUE';
      NO_DIR_CHECK='TRUE';
      ALLOW_CONNECT='TRUE';
    'VSS_J51':
      PIN_NUMBER='(0,0,0,0,0,0,0,0,0,0,0,0,0,0,0,0,0,0,0,0,0,0,0,0,0,0,0,0,J51,0,0,0,0,0,0,0,0,0,0,0)';
      PINUSE='POWER';
      NO_LOAD_CHECK='Both';
      NO_IO_CHECK='Both';
      NO_ASSERT_CHECK='TRUE';
      NO_DIR_CHECK='TRUE';
      ALLOW_CONNECT='TRUE';
    'VSS_J54':
      PIN_NUMBER='(0,0,0,0,0,0,0,0,0,0,0,0,0,0,0,0,0,0,0,0,0,0,0,0,0,0,0,0,J54,0,0,0,0,0,0,0,0,0,0,0)';
      PINUSE='POWER';
      NO_LOAD_CHECK='Both';
      NO_IO_CHECK='Both';
      NO_ASSERT_CHECK='TRUE';
      NO_DIR_CHECK='TRUE';
      ALLOW_CONNECT='TRUE';
    'VSS_J56':
      PIN_NUMBER='(0,0,0,0,0,0,0,0,0,0,0,0,0,0,0,0,0,0,0,0,0,0,0,0,0,0,0,0,J56,0,0,0,0,0,0,0,0,0,0,0)';
      PINUSE='POWER';
      NO_LOAD_CHECK='Both';
      NO_IO_CHECK='Both';
      NO_ASSERT_CHECK='TRUE';
      NO_DIR_CHECK='TRUE';
      ALLOW_CONNECT='TRUE';
    'VSS_J58':
      PIN_NUMBER='(0,0,0,0,0,0,0,0,0,0,0,0,0,0,0,0,0,0,0,0,0,0,0,0,0,0,0,0,J58,0,0,0,0,0,0,0,0,0,0,0)';
      PINUSE='POWER';
      NO_LOAD_CHECK='Both';
      NO_IO_CHECK='Both';
      NO_ASSERT_CHECK='TRUE';
      NO_DIR_CHECK='TRUE';
      ALLOW_CONNECT='TRUE';
    'VSS_J61':
      PIN_NUMBER='(0,0,0,0,0,0,0,0,0,0,0,0,0,0,0,0,0,0,0,0,0,0,0,0,0,0,0,0,J61,0,0,0,0,0,0,0,0,0,0,0)';
      PINUSE='POWER';
      NO_LOAD_CHECK='Both';
      NO_IO_CHECK='Both';
      NO_ASSERT_CHECK='TRUE';
      NO_DIR_CHECK='TRUE';
      ALLOW_CONNECT='TRUE';
    'VSS_J63':
      PIN_NUMBER='(0,0,0,0,0,0,0,0,0,0,0,0,0,0,0,0,0,0,0,0,0,0,0,0,0,0,0,0,J63,0,0,0,0,0,0,0,0,0,0,0)';
      PINUSE='POWER';
      NO_LOAD_CHECK='Both';
      NO_IO_CHECK='Both';
      NO_ASSERT_CHECK='TRUE';
      NO_DIR_CHECK='TRUE';
      ALLOW_CONNECT='TRUE';
    'VSS_J65':
      PIN_NUMBER='(0,0,0,0,0,0,0,0,0,0,0,0,0,0,0,0,0,0,0,0,0,0,0,0,0,0,0,0,J65,0,0,0,0,0,0,0,0,0,0,0)';
      PINUSE='POWER';
      NO_LOAD_CHECK='Both';
      NO_IO_CHECK='Both';
      NO_ASSERT_CHECK='TRUE';
      NO_DIR_CHECK='TRUE';
      ALLOW_CONNECT='TRUE';
    'VSS_J68':
      PIN_NUMBER='(0,0,0,0,0,0,0,0,0,0,0,0,0,0,0,0,0,0,0,0,0,0,0,0,0,0,0,0,J68,0,0,0,0,0,0,0,0,0,0,0)';
      PINUSE='POWER';
      NO_LOAD_CHECK='Both';
      NO_IO_CHECK='Both';
      NO_ASSERT_CHECK='TRUE';
      NO_DIR_CHECK='TRUE';
      ALLOW_CONNECT='TRUE';
    'VSS_J70':
      PIN_NUMBER='(0,0,0,0,0,0,0,0,0,0,0,0,0,0,0,0,0,0,0,0,0,0,0,0,0,0,0,0,J70,0,0,0,0,0,0,0,0,0,0,0)';
      PINUSE='POWER';
      NO_LOAD_CHECK='Both';
      NO_IO_CHECK='Both';
      NO_ASSERT_CHECK='TRUE';
      NO_DIR_CHECK='TRUE';
      ALLOW_CONNECT='TRUE';
    'VSS_J72':
      PIN_NUMBER='(0,0,0,0,0,0,0,0,0,0,0,0,0,0,0,0,0,0,0,0,0,0,0,0,0,0,0,0,J72,0,0,0,0,0,0,0,0,0,0,0)';
      PINUSE='POWER';
      NO_LOAD_CHECK='Both';
      NO_IO_CHECK='Both';
      NO_ASSERT_CHECK='TRUE';
      NO_DIR_CHECK='TRUE';
      ALLOW_CONNECT='TRUE';
    'VSS_J75':
      PIN_NUMBER='(0,0,0,0,0,0,0,0,0,0,0,0,0,0,0,0,0,0,0,0,0,0,0,0,0,0,0,0,J75,0,0,0,0,0,0,0,0,0,0,0)';
      PINUSE='POWER';
      NO_LOAD_CHECK='Both';
      NO_IO_CHECK='Both';
      NO_ASSERT_CHECK='TRUE';
      NO_DIR_CHECK='TRUE';
      ALLOW_CONNECT='TRUE';
    'VSS_K3':
      PIN_NUMBER='(0,0,0,0,0,0,0,0,0,0,0,0,0,0,0,0,0,0,0,0,0,0,0,0,0,0,0,0,K3,0,0,0,0,0,0,0,0,0,0,0)';
      PINUSE='POWER';
      NO_LOAD_CHECK='Both';
      NO_IO_CHECK='Both';
      NO_ASSERT_CHECK='TRUE';
      NO_DIR_CHECK='TRUE';
      ALLOW_CONNECT='TRUE';
    'VSS_K5':
      PIN_NUMBER='(0,0,0,0,0,0,0,0,0,0,0,0,0,0,0,0,0,0,0,0,0,0,0,0,0,0,0,0,K5,0,0,0,0,0,0,0,0,0,0,0)';
      PINUSE='POWER';
      NO_LOAD_CHECK='Both';
      NO_IO_CHECK='Both';
      NO_ASSERT_CHECK='TRUE';
      NO_DIR_CHECK='TRUE';
      ALLOW_CONNECT='TRUE';
    'VSS_K8':
      PIN_NUMBER='(0,0,0,0,0,0,0,0,0,0,0,0,0,0,0,0,0,0,0,0,0,0,0,0,0,0,0,0,K8,0,0,0,0,0,0,0,0,0,0,0)';
      PINUSE='POWER';
      NO_LOAD_CHECK='Both';
      NO_IO_CHECK='Both';
      NO_ASSERT_CHECK='TRUE';
      NO_DIR_CHECK='TRUE';
      ALLOW_CONNECT='TRUE';
    'VSS_K10':
      PIN_NUMBER='(0,0,0,0,0,0,0,0,0,0,0,0,0,0,0,0,0,0,0,0,0,0,0,0,0,0,0,0,K10,0,0,0,0,0,0,0,0,0,0,0)';
      PINUSE='POWER';
      NO_LOAD_CHECK='Both';
      NO_IO_CHECK='Both';
      NO_ASSERT_CHECK='TRUE';
      NO_DIR_CHECK='TRUE';
      ALLOW_CONNECT='TRUE';
    'VSS_K12':
      PIN_NUMBER='(0,0,0,0,0,0,0,0,0,0,0,0,0,0,0,0,0,0,0,0,0,0,0,0,0,0,0,0,K12,0,0,0,0,0,0,0,0,0,0,0)';
      PINUSE='POWER';
      NO_LOAD_CHECK='Both';
      NO_IO_CHECK='Both';
      NO_ASSERT_CHECK='TRUE';
      NO_DIR_CHECK='TRUE';
      ALLOW_CONNECT='TRUE';
    'VSS_K15':
      PIN_NUMBER='(0,0,0,0,0,0,0,0,0,0,0,0,0,0,0,0,0,0,0,0,0,0,0,0,0,0,0,0,K15,0,0,0,0,0,0,0,0,0,0,0)';
      PINUSE='POWER';
      NO_LOAD_CHECK='Both';
      NO_IO_CHECK='Both';
      NO_ASSERT_CHECK='TRUE';
      NO_DIR_CHECK='TRUE';
      ALLOW_CONNECT='TRUE';
    'VSS_K17':
      PIN_NUMBER='(0,0,0,0,0,0,0,0,0,0,0,0,0,0,0,0,0,0,0,0,0,0,0,0,0,0,0,0,K17,0,0,0,0,0,0,0,0,0,0,0)';
      PINUSE='POWER';
      NO_LOAD_CHECK='Both';
      NO_IO_CHECK='Both';
      NO_ASSERT_CHECK='TRUE';
      NO_DIR_CHECK='TRUE';
      ALLOW_CONNECT='TRUE';
    'VSS_K19':
      PIN_NUMBER='(0,0,0,0,0,0,0,0,0,0,0,0,0,0,0,0,0,0,0,0,0,0,0,0,0,0,0,0,K19,0,0,0,0,0,0,0,0,0,0,0)';
      PINUSE='POWER';
      NO_LOAD_CHECK='Both';
      NO_IO_CHECK='Both';
      NO_ASSERT_CHECK='TRUE';
      NO_DIR_CHECK='TRUE';
      ALLOW_CONNECT='TRUE';
    'VSS_K24':
      PIN_NUMBER='(0,0,0,0,0,0,0,0,0,0,0,0,0,0,0,0,0,0,0,0,0,0,0,0,0,0,0,0,K24,0,0,0,0,0,0,0,0,0,0,0)';
      PINUSE='POWER';
      NO_LOAD_CHECK='Both';
      NO_IO_CHECK='Both';
      NO_ASSERT_CHECK='TRUE';
      NO_DIR_CHECK='TRUE';
      ALLOW_CONNECT='TRUE';
    'VSS_K25':
      PIN_NUMBER='(0,0,0,0,0,0,0,0,0,0,0,0,0,0,0,0,0,0,0,0,0,0,0,0,0,0,0,0,K25,0,0,0,0,0,0,0,0,0,0,0)';
      PINUSE='POWER';
      NO_LOAD_CHECK='Both';
      NO_IO_CHECK='Both';
      NO_ASSERT_CHECK='TRUE';
      NO_DIR_CHECK='TRUE';
      ALLOW_CONNECT='TRUE';
    'VSS_K26':
      PIN_NUMBER='(0,0,0,0,0,0,0,0,0,0,0,0,0,0,0,0,0,0,0,0,0,0,0,0,0,0,0,0,K26,0,0,0,0,0,0,0,0,0,0,0)';
      PINUSE='POWER';
      NO_LOAD_CHECK='Both';
      NO_IO_CHECK='Both';
      NO_ASSERT_CHECK='TRUE';
      NO_DIR_CHECK='TRUE';
      ALLOW_CONNECT='TRUE';
    'VSS_K27':
      PIN_NUMBER='(0,0,0,0,0,0,0,0,0,0,0,0,0,0,0,0,0,0,0,0,0,0,0,0,0,0,0,0,K27,0,0,0,0,0,0,0,0,0,0,0)';
      PINUSE='POWER';
      NO_LOAD_CHECK='Both';
      NO_IO_CHECK='Both';
      NO_ASSERT_CHECK='TRUE';
      NO_DIR_CHECK='TRUE';
      ALLOW_CONNECT='TRUE';
    'VSS_K28':
      PIN_NUMBER='(0,0,0,0,0,0,0,0,0,0,0,0,0,0,0,0,0,0,0,0,0,0,0,0,0,0,0,0,K28,0,0,0,0,0,0,0,0,0,0,0)';
      PINUSE='POWER';
      NO_LOAD_CHECK='Both';
      NO_IO_CHECK='Both';
      NO_ASSERT_CHECK='TRUE';
      NO_DIR_CHECK='TRUE';
      ALLOW_CONNECT='TRUE';
    'VSS_K29':
      PIN_NUMBER='(0,0,0,0,0,0,0,0,0,0,0,0,0,0,0,0,0,0,0,0,0,0,0,0,0,0,0,0,K29,0,0,0,0,0,0,0,0,0,0,0)';
      PINUSE='POWER';
      NO_LOAD_CHECK='Both';
      NO_IO_CHECK='Both';
      NO_ASSERT_CHECK='TRUE';
      NO_DIR_CHECK='TRUE';
      ALLOW_CONNECT='TRUE';
    'VSS_K30':
      PIN_NUMBER='(0,0,0,0,0,0,0,0,0,0,0,0,0,0,0,0,0,0,0,0,0,0,0,0,0,0,0,0,K30,0,0,0,0,0,0,0,0,0,0,0)';
      PINUSE='POWER';
      NO_LOAD_CHECK='Both';
      NO_IO_CHECK='Both';
      NO_ASSERT_CHECK='TRUE';
      NO_DIR_CHECK='TRUE';
      ALLOW_CONNECT='TRUE';
    'VSS_K31':
      PIN_NUMBER='(0,0,0,0,0,0,0,0,0,0,0,0,0,0,0,0,0,0,0,0,0,0,0,0,0,0,0,0,K31,0,0,0,0,0,0,0,0,0,0,0)';
      PINUSE='POWER';
      NO_LOAD_CHECK='Both';
      NO_IO_CHECK='Both';
      NO_ASSERT_CHECK='TRUE';
      NO_DIR_CHECK='TRUE';
      ALLOW_CONNECT='TRUE';
    'VSS_K32':
      PIN_NUMBER='(0,0,0,0,0,0,0,0,0,0,0,0,0,0,0,0,0,0,0,0,0,0,0,0,0,0,0,0,K32,0,0,0,0,0,0,0,0,0,0,0)';
      PINUSE='POWER';
      NO_LOAD_CHECK='Both';
      NO_IO_CHECK='Both';
      NO_ASSERT_CHECK='TRUE';
      NO_DIR_CHECK='TRUE';
      ALLOW_CONNECT='TRUE';
    'VSS_K33':
      PIN_NUMBER='(0,0,0,0,0,0,0,0,0,0,0,0,0,0,0,0,0,0,0,0,0,0,0,0,0,0,0,0,K33,0,0,0,0,0,0,0,0,0,0,0)';
      PINUSE='POWER';
      NO_LOAD_CHECK='Both';
      NO_IO_CHECK='Both';
      NO_ASSERT_CHECK='TRUE';
      NO_DIR_CHECK='TRUE';
      ALLOW_CONNECT='TRUE';
    'VSS_K34':
      PIN_NUMBER='(0,0,0,0,0,0,0,0,0,0,0,0,0,0,0,0,0,0,0,0,0,0,0,0,0,0,0,0,K34,0,0,0,0,0,0,0,0,0,0,0)';
      PINUSE='POWER';
      NO_LOAD_CHECK='Both';
      NO_IO_CHECK='Both';
      NO_ASSERT_CHECK='TRUE';
      NO_DIR_CHECK='TRUE';
      ALLOW_CONNECT='TRUE';
    'VSS_K37':
      PIN_NUMBER='(0,0,0,0,0,0,0,0,0,0,0,0,0,0,0,0,0,0,0,0,0,0,0,0,0,0,0,0,K37,0,0,0,0,0,0,0,0,0,0,0)';
      PINUSE='POWER';
      NO_LOAD_CHECK='Both';
      NO_IO_CHECK='Both';
      NO_ASSERT_CHECK='TRUE';
      NO_DIR_CHECK='TRUE';
      ALLOW_CONNECT='TRUE';
    'VSS_K39':
      PIN_NUMBER='(0,0,0,0,0,0,0,0,0,0,0,0,0,0,0,0,0,0,0,0,0,0,0,0,0,0,0,0,K39,0,0,0,0,0,0,0,0,0,0,0)';
      PINUSE='POWER';
      NO_LOAD_CHECK='Both';
      NO_IO_CHECK='Both';
      NO_ASSERT_CHECK='TRUE';
      NO_DIR_CHECK='TRUE';
      ALLOW_CONNECT='TRUE';
    'VSS_K42':
      PIN_NUMBER='(0,0,0,0,0,0,0,0,0,0,0,0,0,0,0,0,0,0,0,0,0,0,0,0,0,0,0,0,K42,0,0,0,0,0,0,0,0,0,0,0)';
      PINUSE='POWER';
      NO_LOAD_CHECK='Both';
      NO_IO_CHECK='Both';
      NO_ASSERT_CHECK='TRUE';
      NO_DIR_CHECK='TRUE';
      ALLOW_CONNECT='TRUE';
    'VSS_K43':
      PIN_NUMBER='(0,0,0,0,0,0,0,0,0,0,0,0,0,0,0,0,0,0,0,0,0,0,0,0,0,0,0,0,K43,0,0,0,0,0,0,0,0,0,0,0)';
      PINUSE='POWER';
      NO_LOAD_CHECK='Both';
      NO_IO_CHECK='Both';
      NO_ASSERT_CHECK='TRUE';
      NO_DIR_CHECK='TRUE';
      ALLOW_CONNECT='TRUE';
    'VSS_K44':
      PIN_NUMBER='(0,0,0,0,0,0,0,0,0,0,0,0,0,0,0,0,0,0,0,0,0,0,0,0,0,0,0,0,K44,0,0,0,0,0,0,0,0,0,0,0)';
      PINUSE='POWER';
      NO_LOAD_CHECK='Both';
      NO_IO_CHECK='Both';
      NO_ASSERT_CHECK='TRUE';
      NO_DIR_CHECK='TRUE';
      ALLOW_CONNECT='TRUE';
    'VSS_K45':
      PIN_NUMBER='(0,0,0,0,0,0,0,0,0,0,0,0,0,0,0,0,0,0,0,0,0,0,0,0,0,0,0,0,K45,0,0,0,0,0,0,0,0,0,0,0)';
      PINUSE='POWER';
      NO_LOAD_CHECK='Both';
      NO_IO_CHECK='Both';
      NO_ASSERT_CHECK='TRUE';
      NO_DIR_CHECK='TRUE';
      ALLOW_CONNECT='TRUE';
    'VSS_K46':
      PIN_NUMBER='(0,0,0,0,0,0,0,0,0,0,0,0,0,0,0,0,0,0,0,0,0,0,0,0,0,0,0,0,K46,0,0,0,0,0,0,0,0,0,0,0)';
      PINUSE='POWER';
      NO_LOAD_CHECK='Both';
      NO_IO_CHECK='Both';
      NO_ASSERT_CHECK='TRUE';
      NO_DIR_CHECK='TRUE';
      ALLOW_CONNECT='TRUE';
    'VSS_K47':
      PIN_NUMBER='(0,0,0,0,0,0,0,0,0,0,0,0,0,0,0,0,0,0,0,0,0,0,0,0,0,0,0,0,K47,0,0,0,0,0,0,0,0,0,0,0)';
      PINUSE='POWER';
      NO_LOAD_CHECK='Both';
      NO_IO_CHECK='Both';
      NO_ASSERT_CHECK='TRUE';
      NO_DIR_CHECK='TRUE';
      ALLOW_CONNECT='TRUE';
    'VSS_K48':
      PIN_NUMBER='(0,0,0,0,0,0,0,0,0,0,0,0,0,0,0,0,0,0,0,0,0,0,0,0,0,0,0,0,K48,0,0,0,0,0,0,0,0,0,0,0)';
      PINUSE='POWER';
      NO_LOAD_CHECK='Both';
      NO_IO_CHECK='Both';
      NO_ASSERT_CHECK='TRUE';
      NO_DIR_CHECK='TRUE';
      ALLOW_CONNECT='TRUE';
    'VSS_K49':
      PIN_NUMBER='(0,0,0,0,0,0,0,0,0,0,0,0,0,0,0,0,0,0,0,0,0,0,0,0,0,0,0,0,K49,0,0,0,0,0,0,0,0,0,0,0)';
      PINUSE='POWER';
      NO_LOAD_CHECK='Both';
      NO_IO_CHECK='Both';
      NO_ASSERT_CHECK='TRUE';
      NO_DIR_CHECK='TRUE';
      ALLOW_CONNECT='TRUE';
    'VSS_K50':
      PIN_NUMBER='(0,0,0,0,0,0,0,0,0,0,0,0,0,0,0,0,0,0,0,0,0,0,0,0,0,0,0,0,K50,0,0,0,0,0,0,0,0,0,0,0)';
      PINUSE='POWER';
      NO_LOAD_CHECK='Both';
      NO_IO_CHECK='Both';
      NO_ASSERT_CHECK='TRUE';
      NO_DIR_CHECK='TRUE';
      ALLOW_CONNECT='TRUE';
    'VSS_K51':
      PIN_NUMBER='(0,0,0,0,0,0,0,0,0,0,0,0,0,0,0,0,0,0,0,0,0,0,0,0,0,0,0,0,K51,0,0,0,0,0,0,0,0,0,0,0)';
      PINUSE='POWER';
      NO_LOAD_CHECK='Both';
      NO_IO_CHECK='Both';
      NO_ASSERT_CHECK='TRUE';
      NO_DIR_CHECK='TRUE';
      ALLOW_CONNECT='TRUE';
    'VSS_K52':
      PIN_NUMBER='(0,0,0,0,0,0,0,0,0,0,0,0,0,0,0,0,0,0,0,0,0,0,0,0,0,0,0,0,K52,0,0,0,0,0,0,0,0,0,0,0)';
      PINUSE='POWER';
      NO_LOAD_CHECK='Both';
      NO_IO_CHECK='Both';
      NO_ASSERT_CHECK='TRUE';
      NO_DIR_CHECK='TRUE';
      ALLOW_CONNECT='TRUE';
    'VSS_K53':
      PIN_NUMBER='(0,0,0,0,0,0,0,0,0,0,0,0,0,0,0,0,0,0,0,0,0,0,0,0,0,0,0,0,K53,0,0,0,0,0,0,0,0,0,0,0)';
      PINUSE='POWER';
      NO_LOAD_CHECK='Both';
      NO_IO_CHECK='Both';
      NO_ASSERT_CHECK='TRUE';
      NO_DIR_CHECK='TRUE';
      ALLOW_CONNECT='TRUE';
    'VSS_K57':
      PIN_NUMBER='(0,0,0,0,0,0,0,0,0,0,0,0,0,0,0,0,0,0,0,0,0,0,0,0,0,0,0,0,K57,0,0,0,0,0,0,0,0,0,0,0)';
      PINUSE='POWER';
      NO_LOAD_CHECK='Both';
      NO_IO_CHECK='Both';
      NO_ASSERT_CHECK='TRUE';
      NO_DIR_CHECK='TRUE';
      ALLOW_CONNECT='TRUE';
    'VSS_K61':
      PIN_NUMBER='(0,0,0,0,0,0,0,0,0,0,0,0,0,0,0,0,0,0,0,0,0,0,0,0,0,0,0,0,K61,0,0,0,0,0,0,0,0,0,0,0)';
      PINUSE='POWER';
      NO_LOAD_CHECK='Both';
      NO_IO_CHECK='Both';
      NO_ASSERT_CHECK='TRUE';
      NO_DIR_CHECK='TRUE';
      ALLOW_CONNECT='TRUE';
    'VSS_K64':
      PIN_NUMBER='(0,0,0,0,0,0,0,0,0,0,0,0,0,0,0,0,0,0,0,0,0,0,0,0,0,0,0,0,K64,0,0,0,0,0,0,0,0,0,0,0)';
      PINUSE='POWER';
      NO_LOAD_CHECK='Both';
      NO_IO_CHECK='Both';
      NO_ASSERT_CHECK='TRUE';
      NO_DIR_CHECK='TRUE';
      ALLOW_CONNECT='TRUE';
    'VSS_K66':
      PIN_NUMBER='(0,0,0,0,0,0,0,0,0,0,0,0,0,0,0,0,0,0,0,0,0,0,0,0,0,0,0,0,K66,0,0,0,0,0,0,0,0,0,0,0)';
      PINUSE='POWER';
      NO_LOAD_CHECK='Both';
      NO_IO_CHECK='Both';
      NO_ASSERT_CHECK='TRUE';
      NO_DIR_CHECK='TRUE';
      ALLOW_CONNECT='TRUE';
    'VSS_K68':
      PIN_NUMBER='(0,0,0,0,0,0,0,0,0,0,0,0,0,0,0,0,0,0,0,0,0,0,0,0,0,0,0,0,K68,0,0,0,0,0,0,0,0,0,0,0)';
      PINUSE='POWER';
      NO_LOAD_CHECK='Both';
      NO_IO_CHECK='Both';
      NO_ASSERT_CHECK='TRUE';
      NO_DIR_CHECK='TRUE';
      ALLOW_CONNECT='TRUE';
    'VSS_K71':
      PIN_NUMBER='(0,0,0,0,0,0,0,0,0,0,0,0,0,0,0,0,0,0,0,0,0,0,0,0,0,0,0,0,K71,0,0,0,0,0,0,0,0,0,0,0)';
      PINUSE='POWER';
      NO_LOAD_CHECK='Both';
      NO_IO_CHECK='Both';
      NO_ASSERT_CHECK='TRUE';
      NO_DIR_CHECK='TRUE';
      ALLOW_CONNECT='TRUE';
    'VSS_K73':
      PIN_NUMBER='(0,0,0,0,0,0,0,0,0,0,0,0,0,0,0,0,0,0,0,0,0,0,0,0,0,0,0,0,K73,0,0,0,0,0,0,0,0,0,0,0)';
      PINUSE='POWER';
      NO_LOAD_CHECK='Both';
      NO_IO_CHECK='Both';
      NO_ASSERT_CHECK='TRUE';
      NO_DIR_CHECK='TRUE';
      ALLOW_CONNECT='TRUE';
    'VSS_L1':
      PIN_NUMBER='(0,0,0,0,0,0,0,0,0,0,0,0,0,0,0,0,0,0,0,0,0,0,0,0,0,0,0,0,L1,0,0,0,0,0,0,0,0,0,0,0)';
      PINUSE='POWER';
      NO_LOAD_CHECK='Both';
      NO_IO_CHECK='Both';
      NO_ASSERT_CHECK='TRUE';
      NO_DIR_CHECK='TRUE';
      ALLOW_CONNECT='TRUE';
    'VSS_L6':
      PIN_NUMBER='(0,0,0,0,0,0,0,0,0,0,0,0,0,0,0,0,0,0,0,0,0,0,0,0,0,0,0,0,L6,0,0,0,0,0,0,0,0,0,0,0)';
      PINUSE='POWER';
      NO_LOAD_CHECK='Both';
      NO_IO_CHECK='Both';
      NO_ASSERT_CHECK='TRUE';
      NO_DIR_CHECK='TRUE';
      ALLOW_CONNECT='TRUE';
    'VSS_L8':
      PIN_NUMBER='(0,0,0,0,0,0,0,0,0,0,0,0,0,0,0,0,0,0,0,0,0,0,0,0,0,0,0,0,L8,0,0,0,0,0,0,0,0,0,0,0)';
      PINUSE='POWER';
      NO_LOAD_CHECK='Both';
      NO_IO_CHECK='Both';
      NO_ASSERT_CHECK='TRUE';
      NO_DIR_CHECK='TRUE';
      ALLOW_CONNECT='TRUE';
    'VSS_L13':
      PIN_NUMBER='(0,0,0,0,0,0,0,0,0,0,0,0,0,0,0,0,0,0,0,0,0,0,0,0,0,0,0,0,L13,0,0,0,0,0,0,0,0,0,0,0)';
      PINUSE='POWER';
      NO_LOAD_CHECK='Both';
      NO_IO_CHECK='Both';
      NO_ASSERT_CHECK='TRUE';
      NO_DIR_CHECK='TRUE';
      ALLOW_CONNECT='TRUE';
    'VSS_L15':
      PIN_NUMBER='(0,0,0,0,0,0,0,0,0,0,0,0,0,0,0,0,0,0,0,0,0,0,0,0,0,0,0,0,L15,0,0,0,0,0,0,0,0,0,0,0)';
      PINUSE='POWER';
      NO_LOAD_CHECK='Both';
      NO_IO_CHECK='Both';
      NO_ASSERT_CHECK='TRUE';
      NO_DIR_CHECK='TRUE';
      ALLOW_CONNECT='TRUE';
    'VSS_L20':
      PIN_NUMBER='(0,0,0,0,0,0,0,0,0,0,0,0,0,0,0,0,0,0,0,0,0,0,0,0,0,0,0,0,L20,0,0,0,0,0,0,0,0,0,0,0)';
      PINUSE='POWER';
      NO_LOAD_CHECK='Both';
      NO_IO_CHECK='Both';
      NO_ASSERT_CHECK='TRUE';
      NO_DIR_CHECK='TRUE';
      ALLOW_CONNECT='TRUE';
    'VSS_L22':
      PIN_NUMBER='(0,0,0,0,0,0,0,0,0,0,0,0,0,0,0,0,0,0,0,0,0,0,0,0,0,0,0,0,L22,0,0,0,0,0,0,0,0,0,0,0)';
      PINUSE='POWER';
      NO_LOAD_CHECK='Both';
      NO_IO_CHECK='Both';
      NO_ASSERT_CHECK='TRUE';
      NO_DIR_CHECK='TRUE';
      ALLOW_CONNECT='TRUE';
    'VSS_L25':
      PIN_NUMBER='(0,0,0,0,0,0,0,0,0,0,0,0,0,0,0,0,0,0,0,0,0,0,0,0,0,0,0,0,L25,0,0,0,0,0,0,0,0,0,0,0)';
      PINUSE='POWER';
      NO_LOAD_CHECK='Both';
      NO_IO_CHECK='Both';
      NO_ASSERT_CHECK='TRUE';
      NO_DIR_CHECK='TRUE';
      ALLOW_CONNECT='TRUE';
    'VSS_L28':
      PIN_NUMBER='(0,0,0,0,0,0,0,0,0,0,0,0,0,0,0,0,0,0,0,0,0,0,0,0,0,0,0,0,L28,0,0,0,0,0,0,0,0,0,0,0)';
      PINUSE='POWER';
      NO_LOAD_CHECK='Both';
      NO_IO_CHECK='Both';
      NO_ASSERT_CHECK='TRUE';
      NO_DIR_CHECK='TRUE';
      ALLOW_CONNECT='TRUE';
    'VSS_L31':
      PIN_NUMBER='(0,0,0,0,0,0,0,0,0,0,0,0,0,0,0,0,0,0,0,0,0,0,0,0,0,0,0,0,L31,0,0,0,0,0,0,0,0,0,0,0)';
      PINUSE='POWER';
      NO_LOAD_CHECK='Both';
      NO_IO_CHECK='Both';
      NO_ASSERT_CHECK='TRUE';
      NO_DIR_CHECK='TRUE';
      ALLOW_CONNECT='TRUE';
    'VSS_L34':
      PIN_NUMBER='(0,0,0,0,0,0,0,0,0,0,0,0,0,0,0,0,0,0,0,0,0,0,0,0,0,0,0,0,L34,0,0,0,0,0,0,0,0,0,0,0)';
      PINUSE='POWER';
      NO_LOAD_CHECK='Both';
      NO_IO_CHECK='Both';
      NO_ASSERT_CHECK='TRUE';
      NO_DIR_CHECK='TRUE';
      ALLOW_CONNECT='TRUE';
    'VSS_L35':
      PIN_NUMBER='(0,0,0,0,0,0,0,0,0,0,0,0,0,0,0,0,0,0,0,0,0,0,0,0,0,0,0,0,L35,0,0,0,0,0,0,0,0,0,0,0)';
      PINUSE='POWER';
      NO_LOAD_CHECK='Both';
      NO_IO_CHECK='Both';
      NO_ASSERT_CHECK='TRUE';
      NO_DIR_CHECK='TRUE';
      ALLOW_CONNECT='TRUE';
    'VSS_L36':
      PIN_NUMBER='(0,0,0,0,0,0,0,0,0,0,0,0,0,0,0,0,0,0,0,0,0,0,0,0,0,0,0,0,L36,0,0,0,0,0,0,0,0,0,0,0)';
      PINUSE='POWER';
      NO_LOAD_CHECK='Both';
      NO_IO_CHECK='Both';
      NO_ASSERT_CHECK='TRUE';
      NO_DIR_CHECK='TRUE';
      ALLOW_CONNECT='TRUE';
    'VSS_L40':
      PIN_NUMBER='(0,0,0,0,0,0,0,0,0,0,0,0,0,0,0,0,0,0,0,0,0,0,0,0,0,0,0,0,L40,0,0,0,0,0,0,0,0,0,0,0)';
      PINUSE='POWER';
      NO_LOAD_CHECK='Both';
      NO_IO_CHECK='Both';
      NO_ASSERT_CHECK='TRUE';
      NO_DIR_CHECK='TRUE';
      ALLOW_CONNECT='TRUE';
    'VSS_L41':
      PIN_NUMBER='(0,0,0,0,0,0,0,0,0,0,0,0,0,0,0,0,0,0,0,0,0,0,0,0,0,0,0,0,L41,0,0,0,0,0,0,0,0,0,0,0)';
      PINUSE='POWER';
      NO_LOAD_CHECK='Both';
      NO_IO_CHECK='Both';
      NO_ASSERT_CHECK='TRUE';
      NO_DIR_CHECK='TRUE';
      ALLOW_CONNECT='TRUE';
    'VSS_L42':
      PIN_NUMBER='(0,0,0,0,0,0,0,0,0,0,0,0,0,0,0,0,0,0,0,0,0,0,0,0,0,0,0,0,L42,0,0,0,0,0,0,0,0,0,0,0)';
      PINUSE='POWER';
      NO_LOAD_CHECK='Both';
      NO_IO_CHECK='Both';
      NO_ASSERT_CHECK='TRUE';
      NO_DIR_CHECK='TRUE';
      ALLOW_CONNECT='TRUE';
    'VSS_L45':
      PIN_NUMBER='(0,0,0,0,0,0,0,0,0,0,0,0,0,0,0,0,0,0,0,0,0,0,0,0,0,0,0,0,L45,0,0,0,0,0,0,0,0,0,0,0)';
      PINUSE='POWER';
      NO_LOAD_CHECK='Both';
      NO_IO_CHECK='Both';
      NO_ASSERT_CHECK='TRUE';
      NO_DIR_CHECK='TRUE';
      ALLOW_CONNECT='TRUE';
    'VSS_L48':
      PIN_NUMBER='(0,0,0,0,0,0,0,0,0,0,0,0,0,0,0,0,0,0,0,0,0,0,0,0,0,0,0,0,L48,0,0,0,0,0,0,0,0,0,0,0)';
      PINUSE='POWER';
      NO_LOAD_CHECK='Both';
      NO_IO_CHECK='Both';
      NO_ASSERT_CHECK='TRUE';
      NO_DIR_CHECK='TRUE';
      ALLOW_CONNECT='TRUE';
    'VSS_L51':
      PIN_NUMBER='(0,0,0,0,0,0,0,0,0,0,0,0,0,0,0,0,0,0,0,0,0,0,0,0,0,0,0,0,L51,0,0,0,0,0,0,0,0,0,0,0)';
      PINUSE='POWER';
      NO_LOAD_CHECK='Both';
      NO_IO_CHECK='Both';
      NO_ASSERT_CHECK='TRUE';
      NO_DIR_CHECK='TRUE';
      ALLOW_CONNECT='TRUE';
    'VSS_L54':
      PIN_NUMBER='(0,0,0,0,0,0,0,0,0,0,0,0,0,0,0,0,0,0,0,0,0,0,0,0,0,0,0,0,L54,0,0,0,0,0,0,0,0,0,0,0)';
      PINUSE='POWER';
      NO_LOAD_CHECK='Both';
      NO_IO_CHECK='Both';
      NO_ASSERT_CHECK='TRUE';
      NO_DIR_CHECK='TRUE';
      ALLOW_CONNECT='TRUE';
    'VSS_L56':
      PIN_NUMBER='(0,0,0,0,0,0,0,0,0,0,0,0,0,0,0,0,0,0,0,0,0,0,0,0,0,0,0,0,L56,0,0,0,0,0,0,0,0,0,0,0)';
      PINUSE='POWER';
      NO_LOAD_CHECK='Both';
      NO_IO_CHECK='Both';
      NO_ASSERT_CHECK='TRUE';
      NO_DIR_CHECK='TRUE';
      ALLOW_CONNECT='TRUE';
    'VSS_L61':
      PIN_NUMBER='(0,0,0,0,0,0,0,0,0,0,0,0,0,0,0,0,0,0,0,0,0,0,0,0,0,0,0,0,L61,0,0,0,0,0,0,0,0,0,0,0)';
      PINUSE='POWER';
      NO_LOAD_CHECK='Both';
      NO_IO_CHECK='Both';
      NO_ASSERT_CHECK='TRUE';
      NO_DIR_CHECK='TRUE';
      ALLOW_CONNECT='TRUE';
    'VSS_L63':
      PIN_NUMBER='(0,0,0,0,0,0,0,0,0,0,0,0,0,0,0,0,0,0,0,0,0,0,0,0,0,0,0,0,L63,0,0,0,0,0,0,0,0,0,0,0)';
      PINUSE='POWER';
      NO_LOAD_CHECK='Both';
      NO_IO_CHECK='Both';
      NO_ASSERT_CHECK='TRUE';
      NO_DIR_CHECK='TRUE';
      ALLOW_CONNECT='TRUE';
    'VSS_L68':
      PIN_NUMBER='(0,0,0,0,0,0,0,0,0,0,0,0,0,0,0,0,0,0,0,0,0,0,0,0,0,0,0,0,L68,0,0,0,0,0,0,0,0,0,0,0)';
      PINUSE='POWER';
      NO_LOAD_CHECK='Both';
      NO_IO_CHECK='Both';
      NO_ASSERT_CHECK='TRUE';
      NO_DIR_CHECK='TRUE';
      ALLOW_CONNECT='TRUE';
    'VSS_L70':
      PIN_NUMBER='(0,0,0,0,0,0,0,0,0,0,0,0,0,0,0,0,0,0,0,0,0,0,0,0,0,0,0,0,L70,0,0,0,0,0,0,0,0,0,0,0)';
      PINUSE='POWER';
      NO_LOAD_CHECK='Both';
      NO_IO_CHECK='Both';
      NO_ASSERT_CHECK='TRUE';
      NO_DIR_CHECK='TRUE';
      ALLOW_CONNECT='TRUE';
    'VSS_L75':
      PIN_NUMBER='(0,0,0,0,0,0,0,0,0,0,0,0,0,0,0,0,0,0,0,0,0,0,0,0,0,0,0,0,L75,0,0,0,0,0,0,0,0,0,0,0)';
      PINUSE='POWER';
      NO_LOAD_CHECK='Both';
      NO_IO_CHECK='Both';
      NO_ASSERT_CHECK='TRUE';
      NO_DIR_CHECK='TRUE';
      ALLOW_CONNECT='TRUE';
    'VSS_M3':
      PIN_NUMBER='(0,0,0,0,0,0,0,0,0,0,0,0,0,0,0,0,0,0,0,0,0,0,0,0,0,0,0,0,M3,0,0,0,0,0,0,0,0,0,0,0)';
      PINUSE='POWER';
      NO_LOAD_CHECK='Both';
      NO_IO_CHECK='Both';
      NO_ASSERT_CHECK='TRUE';
      NO_DIR_CHECK='TRUE';
      ALLOW_CONNECT='TRUE';
    'VSS_M5':
      PIN_NUMBER='(0,0,0,0,0,0,0,0,0,0,0,0,0,0,0,0,0,0,0,0,0,0,0,0,0,0,0,0,M5,0,0,0,0,0,0,0,0,0,0,0)';
      PINUSE='POWER';
      NO_LOAD_CHECK='Both';
      NO_IO_CHECK='Both';
      NO_ASSERT_CHECK='TRUE';
      NO_DIR_CHECK='TRUE';
      ALLOW_CONNECT='TRUE';
    'VSS_M8':
      PIN_NUMBER='(0,0,0,0,0,0,0,0,0,0,0,0,0,0,0,0,0,0,0,0,0,0,0,0,0,0,0,0,M8,0,0,0,0,0,0,0,0,0,0,0)';
      PINUSE='POWER';
      NO_LOAD_CHECK='Both';
      NO_IO_CHECK='Both';
      NO_ASSERT_CHECK='TRUE';
      NO_DIR_CHECK='TRUE';
      ALLOW_CONNECT='TRUE';
    'VSS_M10':
      PIN_NUMBER='(0,0,0,0,0,0,0,0,0,0,0,0,0,0,0,0,0,0,0,0,0,0,0,0,0,0,0,0,M10,0,0,0,0,0,0,0,0,0,0,0)';
      PINUSE='POWER';
      NO_LOAD_CHECK='Both';
      NO_IO_CHECK='Both';
      NO_ASSERT_CHECK='TRUE';
      NO_DIR_CHECK='TRUE';
      ALLOW_CONNECT='TRUE';
    'VSS_M12':
      PIN_NUMBER='(0,0,0,0,0,0,0,0,0,0,0,0,0,0,0,0,0,0,0,0,0,0,0,0,0,0,0,0,M12,0,0,0,0,0,0,0,0,0,0,0)';
      PINUSE='POWER';
      NO_LOAD_CHECK='Both';
      NO_IO_CHECK='Both';
      NO_ASSERT_CHECK='TRUE';
      NO_DIR_CHECK='TRUE';
      ALLOW_CONNECT='TRUE';
    'VSS_M15':
      PIN_NUMBER='(0,0,0,0,0,0,0,0,0,0,0,0,0,0,0,0,0,0,0,0,0,0,0,0,0,0,0,0,M15,0,0,0,0,0,0,0,0,0,0,0)';
      PINUSE='POWER';
      NO_LOAD_CHECK='Both';
      NO_IO_CHECK='Both';
      NO_ASSERT_CHECK='TRUE';
      NO_DIR_CHECK='TRUE';
      ALLOW_CONNECT='TRUE';
    'VSS_M17':
      PIN_NUMBER='(0,0,0,0,0,0,0,0,0,0,0,0,0,0,0,0,0,0,0,0,0,0,0,0,0,0,0,0,M17,0,0,0,0,0,0,0,0,0,0,0)';
      PINUSE='POWER';
      NO_LOAD_CHECK='Both';
      NO_IO_CHECK='Both';
      NO_ASSERT_CHECK='TRUE';
      NO_DIR_CHECK='TRUE';
      ALLOW_CONNECT='TRUE';
    'VSS_M19':
      PIN_NUMBER='(0,0,0,0,0,0,0,0,0,0,0,0,0,0,0,0,0,0,0,0,0,0,0,0,0,0,0,0,M19,0,0,0,0,0,0,0,0,0,0,0)';
      PINUSE='POWER';
      NO_LOAD_CHECK='Both';
      NO_IO_CHECK='Both';
      NO_ASSERT_CHECK='TRUE';
      NO_DIR_CHECK='TRUE';
      ALLOW_CONNECT='TRUE';
    'VSS_M22':
      PIN_NUMBER='(0,0,0,0,0,0,0,0,0,0,0,0,0,0,0,0,0,0,0,0,0,0,0,0,0,0,0,0,M22,0,0,0,0,0,0,0,0,0,0,0)';
      PINUSE='POWER';
      NO_LOAD_CHECK='Both';
      NO_IO_CHECK='Both';
      NO_ASSERT_CHECK='TRUE';
      NO_DIR_CHECK='TRUE';
      ALLOW_CONNECT='TRUE';
    'VSS_M25':
      PIN_NUMBER='(0,0,0,0,0,0,0,0,0,0,0,0,0,0,0,0,0,0,0,0,0,0,0,0,0,0,0,0,M25,0,0,0,0,0,0,0,0,0,0,0)';
      PINUSE='POWER';
      NO_LOAD_CHECK='Both';
      NO_IO_CHECK='Both';
      NO_ASSERT_CHECK='TRUE';
      NO_DIR_CHECK='TRUE';
      ALLOW_CONNECT='TRUE';
    'VSS_M28':
      PIN_NUMBER='(0,0,0,0,0,0,0,0,0,0,0,0,0,0,0,0,0,0,0,0,0,0,0,0,0,0,0,0,M28,0,0,0,0,0,0,0,0,0,0,0)';
      PINUSE='POWER';
      NO_LOAD_CHECK='Both';
      NO_IO_CHECK='Both';
      NO_ASSERT_CHECK='TRUE';
      NO_DIR_CHECK='TRUE';
      ALLOW_CONNECT='TRUE';
    'VSS_M31':
      PIN_NUMBER='(0,0,0,0,0,0,0,0,0,0,0,0,0,0,0,0,0,0,0,0,0,0,0,0,0,0,0,0,M31,0,0,0,0,0,0,0,0,0,0,0)';
      PINUSE='POWER';
      NO_LOAD_CHECK='Both';
      NO_IO_CHECK='Both';
      NO_ASSERT_CHECK='TRUE';
      NO_DIR_CHECK='TRUE';
      ALLOW_CONNECT='TRUE';
    'VSS_M34':
      PIN_NUMBER='(0,0,0,0,0,0,0,0,0,0,0,0,0,0,0,0,0,0,0,0,0,0,0,0,0,0,0,0,M34,0,0,0,0,0,0,0,0,0,0,0)';
      PINUSE='POWER';
      NO_LOAD_CHECK='Both';
      NO_IO_CHECK='Both';
      NO_ASSERT_CHECK='TRUE';
      NO_DIR_CHECK='TRUE';
      ALLOW_CONNECT='TRUE';
    'VSS_M37':
      PIN_NUMBER='(0,0,0,0,0,0,0,0,0,0,0,0,0,0,0,0,0,0,0,0,0,0,0,0,0,0,0,0,M37,0,0,0,0,0,0,0,0,0,0,0)';
      PINUSE='POWER';
      NO_LOAD_CHECK='Both';
      NO_IO_CHECK='Both';
      NO_ASSERT_CHECK='TRUE';
      NO_DIR_CHECK='TRUE';
      ALLOW_CONNECT='TRUE';
    'VSS_M39':
      PIN_NUMBER='(0,0,0,0,0,0,0,0,0,0,0,0,0,0,0,0,0,0,0,0,0,0,0,0,0,0,0,0,M39,0,0,0,0,0,0,0,0,0,0,0)';
      PINUSE='POWER';
      NO_LOAD_CHECK='Both';
      NO_IO_CHECK='Both';
      NO_ASSERT_CHECK='TRUE';
      NO_DIR_CHECK='TRUE';
      ALLOW_CONNECT='TRUE';
    'VSS_M42':
      PIN_NUMBER='(0,0,0,0,0,0,0,0,0,0,0,0,0,0,0,0,0,0,0,0,0,0,0,0,0,0,0,0,M42,0,0,0,0,0,0,0,0,0,0,0)';
      PINUSE='POWER';
      NO_LOAD_CHECK='Both';
      NO_IO_CHECK='Both';
      NO_ASSERT_CHECK='TRUE';
      NO_DIR_CHECK='TRUE';
      ALLOW_CONNECT='TRUE';
    'VSS_M45':
      PIN_NUMBER='(0,0,0,0,0,0,0,0,0,0,0,0,0,0,0,0,0,0,0,0,0,0,0,0,0,0,0,0,M45,0,0,0,0,0,0,0,0,0,0,0)';
      PINUSE='POWER';
      NO_LOAD_CHECK='Both';
      NO_IO_CHECK='Both';
      NO_ASSERT_CHECK='TRUE';
      NO_DIR_CHECK='TRUE';
      ALLOW_CONNECT='TRUE';
    'VSS_M48':
      PIN_NUMBER='(0,0,0,0,0,0,0,0,0,0,0,0,0,0,0,0,0,0,0,0,0,0,0,0,0,0,0,0,M48,0,0,0,0,0,0,0,0,0,0,0)';
      PINUSE='POWER';
      NO_LOAD_CHECK='Both';
      NO_IO_CHECK='Both';
      NO_ASSERT_CHECK='TRUE';
      NO_DIR_CHECK='TRUE';
      ALLOW_CONNECT='TRUE';
    'VSS_M51':
      PIN_NUMBER='(0,0,0,0,0,0,0,0,0,0,0,0,0,0,0,0,0,0,0,0,0,0,0,0,0,0,0,0,M51,0,0,0,0,0,0,0,0,0,0,0)';
      PINUSE='POWER';
      NO_LOAD_CHECK='Both';
      NO_IO_CHECK='Both';
      NO_ASSERT_CHECK='TRUE';
      NO_DIR_CHECK='TRUE';
      ALLOW_CONNECT='TRUE';
    'VSS_M54':
      PIN_NUMBER='(0,0,0,0,0,0,0,0,0,0,0,0,0,0,0,0,0,0,0,0,0,0,0,0,0,0,0,0,M54,0,0,0,0,0,0,0,0,0,0,0)';
      PINUSE='POWER';
      NO_LOAD_CHECK='Both';
      NO_IO_CHECK='Both';
      NO_ASSERT_CHECK='TRUE';
      NO_DIR_CHECK='TRUE';
      ALLOW_CONNECT='TRUE';
    'VSS_M57':
      PIN_NUMBER='(0,0,0,0,0,0,0,0,0,0,0,0,0,0,0,0,0,0,0,0,0,0,0,0,0,0,0,0,M57,0,0,0,0,0,0,0,0,0,0,0)';
      PINUSE='POWER';
      NO_LOAD_CHECK='Both';
      NO_IO_CHECK='Both';
      NO_ASSERT_CHECK='TRUE';
      NO_DIR_CHECK='TRUE';
      ALLOW_CONNECT='TRUE';
    'VSS_M59':
      PIN_NUMBER='(0,0,0,0,0,0,0,0,0,0,0,0,0,0,0,0,0,0,0,0,0,0,0,0,0,0,0,0,M59,0,0,0,0,0,0,0,0,0,0,0)';
      PINUSE='POWER';
      NO_LOAD_CHECK='Both';
      NO_IO_CHECK='Both';
      NO_ASSERT_CHECK='TRUE';
      NO_DIR_CHECK='TRUE';
      ALLOW_CONNECT='TRUE';
    'VSS_M61':
      PIN_NUMBER='(0,0,0,0,0,0,0,0,0,0,0,0,0,0,0,0,0,0,0,0,0,0,0,0,0,0,0,0,M61,0,0,0,0,0,0,0,0,0,0,0)';
      PINUSE='POWER';
      NO_LOAD_CHECK='Both';
      NO_IO_CHECK='Both';
      NO_ASSERT_CHECK='TRUE';
      NO_DIR_CHECK='TRUE';
      ALLOW_CONNECT='TRUE';
    'VSS_M64':
      PIN_NUMBER='(0,0,0,0,0,0,0,0,0,0,0,0,0,0,0,0,0,0,0,0,0,0,0,0,0,0,0,0,M64,0,0,0,0,0,0,0,0,0,0,0)';
      PINUSE='POWER';
      NO_LOAD_CHECK='Both';
      NO_IO_CHECK='Both';
      NO_ASSERT_CHECK='TRUE';
      NO_DIR_CHECK='TRUE';
      ALLOW_CONNECT='TRUE';
    'VSS_M66':
      PIN_NUMBER='(0,0,0,0,0,0,0,0,0,0,0,0,0,0,0,0,0,0,0,0,0,0,0,0,0,0,0,0,M66,0,0,0,0,0,0,0,0,0,0,0)';
      PINUSE='POWER';
      NO_LOAD_CHECK='Both';
      NO_IO_CHECK='Both';
      NO_ASSERT_CHECK='TRUE';
      NO_DIR_CHECK='TRUE';
      ALLOW_CONNECT='TRUE';
    'VSS_M68':
      PIN_NUMBER='(0,0,0,0,0,0,0,0,0,0,0,0,0,0,0,0,0,0,0,0,0,0,0,0,0,0,0,0,M68,0,0,0,0,0,0,0,0,0,0,0)';
      PINUSE='POWER';
      NO_LOAD_CHECK='Both';
      NO_IO_CHECK='Both';
      NO_ASSERT_CHECK='TRUE';
      NO_DIR_CHECK='TRUE';
      ALLOW_CONNECT='TRUE';
    'VSS_M71':
      PIN_NUMBER='(0,0,0,0,0,0,0,0,0,0,0,0,0,0,0,0,0,0,0,0,0,0,0,0,0,0,0,0,M71,0,0,0,0,0,0,0,0,0,0,0)';
      PINUSE='POWER';
      NO_LOAD_CHECK='Both';
      NO_IO_CHECK='Both';
      NO_ASSERT_CHECK='TRUE';
      NO_DIR_CHECK='TRUE';
      ALLOW_CONNECT='TRUE';
    'VSS_M73':
      PIN_NUMBER='(0,0,0,0,0,0,0,0,0,0,0,0,0,0,0,0,0,0,0,0,0,0,0,0,0,0,0,0,M73,0,0,0,0,0,0,0,0,0,0,0)';
      PINUSE='POWER';
      NO_LOAD_CHECK='Both';
      NO_IO_CHECK='Both';
      NO_ASSERT_CHECK='TRUE';
      NO_DIR_CHECK='TRUE';
      ALLOW_CONNECT='TRUE';
    'VSS_N1':
      PIN_NUMBER='(0,0,0,0,0,0,0,0,0,0,0,0,0,0,0,0,0,0,0,0,0,0,0,0,0,0,0,0,N1,0,0,0,0,0,0,0,0,0,0,0)';
      PINUSE='POWER';
      NO_LOAD_CHECK='Both';
      NO_IO_CHECK='Both';
      NO_ASSERT_CHECK='TRUE';
      NO_DIR_CHECK='TRUE';
      ALLOW_CONNECT='TRUE';
    'VSS_N4':
      PIN_NUMBER='(0,0,0,0,0,0,0,0,0,0,0,0,0,0,0,0,0,0,0,0,0,0,0,0,0,0,0,0,N4,0,0,0,0,0,0,0,0,0,0,0)';
      PINUSE='POWER';
      NO_LOAD_CHECK='Both';
      NO_IO_CHECK='Both';
      NO_ASSERT_CHECK='TRUE';
      NO_DIR_CHECK='TRUE';
      ALLOW_CONNECT='TRUE';
    'VSS_N6':
      PIN_NUMBER='(0,0,0,0,0,0,0,0,0,0,0,0,0,0,0,0,0,0,0,0,0,0,0,0,0,0,0,0,N6,0,0,0,0,0,0,0,0,0,0,0)';
      PINUSE='POWER';
      NO_LOAD_CHECK='Both';
      NO_IO_CHECK='Both';
      NO_ASSERT_CHECK='TRUE';
      NO_DIR_CHECK='TRUE';
      ALLOW_CONNECT='TRUE';
    'VSS_N8':
      PIN_NUMBER='(0,0,0,0,0,0,0,0,0,0,0,0,0,0,0,0,0,0,0,0,0,0,0,0,0,0,0,0,N8,0,0,0,0,0,0,0,0,0,0,0)';
      PINUSE='POWER';
      NO_LOAD_CHECK='Both';
      NO_IO_CHECK='Both';
      NO_ASSERT_CHECK='TRUE';
      NO_DIR_CHECK='TRUE';
      ALLOW_CONNECT='TRUE';
    'VSS_N11':
      PIN_NUMBER='(0,0,0,0,0,0,0,0,0,0,0,0,0,0,0,0,0,0,0,0,0,0,0,0,0,0,0,0,N11,0,0,0,0,0,0,0,0,0,0,0)';
      PINUSE='POWER';
      NO_LOAD_CHECK='Both';
      NO_IO_CHECK='Both';
      NO_ASSERT_CHECK='TRUE';
      NO_DIR_CHECK='TRUE';
      ALLOW_CONNECT='TRUE';
    'VSS_N13':
      PIN_NUMBER='(0,0,0,0,0,0,0,0,0,0,0,0,0,0,0,0,0,0,0,0,0,0,0,0,0,0,0,0,N13,0,0,0,0,0,0,0,0,0,0,0)';
      PINUSE='POWER';
      NO_LOAD_CHECK='Both';
      NO_IO_CHECK='Both';
      NO_ASSERT_CHECK='TRUE';
      NO_DIR_CHECK='TRUE';
      ALLOW_CONNECT='TRUE';
    'VSS_N15':
      PIN_NUMBER='(0,0,0,0,0,0,0,0,0,0,0,0,0,0,0,0,0,0,0,0,0,0,0,0,0,0,0,0,N15,0,0,0,0,0,0,0,0,0,0,0)';
      PINUSE='POWER';
      NO_LOAD_CHECK='Both';
      NO_IO_CHECK='Both';
      NO_ASSERT_CHECK='TRUE';
      NO_DIR_CHECK='TRUE';
      ALLOW_CONNECT='TRUE';
    'VSS_N18':
      PIN_NUMBER='(0,0,0,0,0,0,0,0,0,0,0,0,0,0,0,0,0,0,0,0,0,0,0,0,0,0,0,0,N18,0,0,0,0,0,0,0,0,0,0,0)';
      PINUSE='POWER';
      NO_LOAD_CHECK='Both';
      NO_IO_CHECK='Both';
      NO_ASSERT_CHECK='TRUE';
      NO_DIR_CHECK='TRUE';
      ALLOW_CONNECT='TRUE';
    'VSS_N20':
      PIN_NUMBER='(0,0,0,0,0,0,0,0,0,0,0,0,0,0,0,0,0,0,0,0,0,0,0,0,0,0,0,0,N20,0,0,0,0,0,0,0,0,0,0,0)';
      PINUSE='POWER';
      NO_LOAD_CHECK='Both';
      NO_IO_CHECK='Both';
      NO_ASSERT_CHECK='TRUE';
      NO_DIR_CHECK='TRUE';
      ALLOW_CONNECT='TRUE';
    'VSS_N22':
      PIN_NUMBER='(0,0,0,0,0,0,0,0,0,0,0,0,0,0,0,0,0,0,0,0,0,0,0,0,0,0,0,0,N22,0,0,0,0,0,0,0,0,0,0,0)';
      PINUSE='POWER';
      NO_LOAD_CHECK='Both';
      NO_IO_CHECK='Both';
      NO_ASSERT_CHECK='TRUE';
      NO_DIR_CHECK='TRUE';
      ALLOW_CONNECT='TRUE';
    'VSS_N25':
      PIN_NUMBER='(0,0,0,0,0,0,0,0,0,0,0,0,0,0,0,0,0,0,0,0,0,0,0,0,0,0,0,0,N25,0,0,0,0,0,0,0,0,0,0,0)';
      PINUSE='POWER';
      NO_LOAD_CHECK='Both';
      NO_IO_CHECK='Both';
      NO_ASSERT_CHECK='TRUE';
      NO_DIR_CHECK='TRUE';
      ALLOW_CONNECT='TRUE';
    'VSS_N28':
      PIN_NUMBER='(0,0,0,0,0,0,0,0,0,0,0,0,0,0,0,0,0,0,0,0,0,0,0,0,0,0,0,0,N28,0,0,0,0,0,0,0,0,0,0,0)';
      PINUSE='POWER';
      NO_LOAD_CHECK='Both';
      NO_IO_CHECK='Both';
      NO_ASSERT_CHECK='TRUE';
      NO_DIR_CHECK='TRUE';
      ALLOW_CONNECT='TRUE';
    'VSS_N31':
      PIN_NUMBER='(0,0,0,0,0,0,0,0,0,0,0,0,0,0,0,0,0,0,0,0,0,0,0,0,0,0,0,0,N31,0,0,0,0,0,0,0,0,0,0,0)';
      PINUSE='POWER';
      NO_LOAD_CHECK='Both';
      NO_IO_CHECK='Both';
      NO_ASSERT_CHECK='TRUE';
      NO_DIR_CHECK='TRUE';
      ALLOW_CONNECT='TRUE';
    'VSS_N34':
      PIN_NUMBER='(0,0,0,0,0,0,0,0,0,0,0,0,0,0,0,0,0,0,0,0,0,0,0,0,0,0,0,0,N34,0,0,0,0,0,0,0,0,0,0,0)';
      PINUSE='POWER';
      NO_LOAD_CHECK='Both';
      NO_IO_CHECK='Both';
      NO_ASSERT_CHECK='TRUE';
      NO_DIR_CHECK='TRUE';
      ALLOW_CONNECT='TRUE';
    'VSS_N42':
      PIN_NUMBER='(0,0,0,0,0,0,0,0,0,0,0,0,0,0,0,0,0,0,0,0,0,0,0,0,0,0,0,0,N42,0,0,0,0,0,0,0,0,0,0,0)';
      PINUSE='POWER';
      NO_LOAD_CHECK='Both';
      NO_IO_CHECK='Both';
      NO_ASSERT_CHECK='TRUE';
      NO_DIR_CHECK='TRUE';
      ALLOW_CONNECT='TRUE';
    'VSS_N45':
      PIN_NUMBER='(0,0,0,0,0,0,0,0,0,0,0,0,0,0,0,0,0,0,0,0,0,0,0,0,0,0,0,0,N45,0,0,0,0,0,0,0,0,0,0,0)';
      PINUSE='POWER';
      NO_LOAD_CHECK='Both';
      NO_IO_CHECK='Both';
      NO_ASSERT_CHECK='TRUE';
      NO_DIR_CHECK='TRUE';
      ALLOW_CONNECT='TRUE';
    'VSS_N48':
      PIN_NUMBER='(0,0,0,0,0,0,0,0,0,0,0,0,0,0,0,0,0,0,0,0,0,0,0,0,0,0,0,0,N48,0,0,0,0,0,0,0,0,0,0,0)';
      PINUSE='POWER';
      NO_LOAD_CHECK='Both';
      NO_IO_CHECK='Both';
      NO_ASSERT_CHECK='TRUE';
      NO_DIR_CHECK='TRUE';
      ALLOW_CONNECT='TRUE';
    'VSS_N51':
      PIN_NUMBER='(0,0,0,0,0,0,0,0,0,0,0,0,0,0,0,0,0,0,0,0,0,0,0,0,0,0,0,0,N51,0,0,0,0,0,0,0,0,0,0,0)';
      PINUSE='POWER';
      NO_LOAD_CHECK='Both';
      NO_IO_CHECK='Both';
      NO_ASSERT_CHECK='TRUE';
      NO_DIR_CHECK='TRUE';
      ALLOW_CONNECT='TRUE';
    'VSS_N54':
      PIN_NUMBER='(0,0,0,0,0,0,0,0,0,0,0,0,0,0,0,0,0,0,0,0,0,0,0,0,0,0,0,0,N54,0,0,0,0,0,0,0,0,0,0,0)';
      PINUSE='POWER';
      NO_LOAD_CHECK='Both';
      NO_IO_CHECK='Both';
      NO_ASSERT_CHECK='TRUE';
      NO_DIR_CHECK='TRUE';
      ALLOW_CONNECT='TRUE';
    'VSS_N56':
      PIN_NUMBER='(0,0,0,0,0,0,0,0,0,0,0,0,0,0,0,0,0,0,0,0,0,0,0,0,0,0,0,0,N56,0,0,0,0,0,0,0,0,0,0,0)';
      PINUSE='POWER';
      NO_LOAD_CHECK='Both';
      NO_IO_CHECK='Both';
      NO_ASSERT_CHECK='TRUE';
      NO_DIR_CHECK='TRUE';
      ALLOW_CONNECT='TRUE';
    'VSS_N58':
      PIN_NUMBER='(0,0,0,0,0,0,0,0,0,0,0,0,0,0,0,0,0,0,0,0,0,0,0,0,0,0,0,0,N58,0,0,0,0,0,0,0,0,0,0,0)';
      PINUSE='POWER';
      NO_LOAD_CHECK='Both';
      NO_IO_CHECK='Both';
      NO_ASSERT_CHECK='TRUE';
      NO_DIR_CHECK='TRUE';
      ALLOW_CONNECT='TRUE';
    'VSS_N61':
      PIN_NUMBER='(0,0,0,0,0,0,0,0,0,0,0,0,0,0,0,0,0,0,0,0,0,0,0,0,0,0,0,0,N61,0,0,0,0,0,0,0,0,0,0,0)';
      PINUSE='POWER';
      NO_LOAD_CHECK='Both';
      NO_IO_CHECK='Both';
      NO_ASSERT_CHECK='TRUE';
      NO_DIR_CHECK='TRUE';
      ALLOW_CONNECT='TRUE';
    'VSS_N63':
      PIN_NUMBER='(0,0,0,0,0,0,0,0,0,0,0,0,0,0,0,0,0,0,0,0,0,0,0,0,0,0,0,0,N63,0,0,0,0,0,0,0,0,0,0,0)';
      PINUSE='POWER';
      NO_LOAD_CHECK='Both';
      NO_IO_CHECK='Both';
      NO_ASSERT_CHECK='TRUE';
      NO_DIR_CHECK='TRUE';
      ALLOW_CONNECT='TRUE';
    'VSS_N65':
      PIN_NUMBER='(0,0,0,0,0,0,0,0,0,0,0,0,0,0,0,0,0,0,0,0,0,0,0,0,0,0,0,0,N65,0,0,0,0,0,0,0,0,0,0,0)';
      PINUSE='POWER';
      NO_LOAD_CHECK='Both';
      NO_IO_CHECK='Both';
      NO_ASSERT_CHECK='TRUE';
      NO_DIR_CHECK='TRUE';
      ALLOW_CONNECT='TRUE';
    'VSS_N68':
      PIN_NUMBER='(0,0,0,0,0,0,0,0,0,0,0,0,0,0,0,0,0,0,0,0,0,0,0,0,0,0,0,0,N68,0,0,0,0,0,0,0,0,0,0,0)';
      PINUSE='POWER';
      NO_LOAD_CHECK='Both';
      NO_IO_CHECK='Both';
      NO_ASSERT_CHECK='TRUE';
      NO_DIR_CHECK='TRUE';
      ALLOW_CONNECT='TRUE';
    'VSS_N70':
      PIN_NUMBER='(0,0,0,0,0,0,0,0,0,0,0,0,0,0,0,0,0,0,0,0,0,0,0,0,0,0,0,0,N70,0,0,0,0,0,0,0,0,0,0,0)';
      PINUSE='POWER';
      NO_LOAD_CHECK='Both';
      NO_IO_CHECK='Both';
      NO_ASSERT_CHECK='TRUE';
      NO_DIR_CHECK='TRUE';
      ALLOW_CONNECT='TRUE';
    'VSS_N72':
      PIN_NUMBER='(0,0,0,0,0,0,0,0,0,0,0,0,0,0,0,0,0,0,0,0,0,0,0,0,0,0,0,0,N72,0,0,0,0,0,0,0,0,0,0,0)';
      PINUSE='POWER';
      NO_LOAD_CHECK='Both';
      NO_IO_CHECK='Both';
      NO_ASSERT_CHECK='TRUE';
      NO_DIR_CHECK='TRUE';
      ALLOW_CONNECT='TRUE';
    'VSS_N75':
      PIN_NUMBER='(0,0,0,0,0,0,0,0,0,0,0,0,0,0,0,0,0,0,0,0,0,0,0,0,0,0,0,0,N75,0,0,0,0,0,0,0,0,0,0,0)';
      PINUSE='POWER';
      NO_LOAD_CHECK='Both';
      NO_IO_CHECK='Both';
      NO_ASSERT_CHECK='TRUE';
      NO_DIR_CHECK='TRUE';
      ALLOW_CONNECT='TRUE';
    'VSS_P3':
      PIN_NUMBER='(0,0,0,0,0,0,0,0,0,0,0,0,0,0,0,0,0,0,0,0,0,0,0,0,0,0,0,0,P3,0,0,0,0,0,0,0,0,0,0,0)';
      PINUSE='POWER';
      NO_LOAD_CHECK='Both';
      NO_IO_CHECK='Both';
      NO_ASSERT_CHECK='TRUE';
      NO_DIR_CHECK='TRUE';
      ALLOW_CONNECT='TRUE';
    'VSS_P8':
      PIN_NUMBER='(0,0,0,0,0,0,0,0,0,0,0,0,0,0,0,0,0,0,0,0,0,0,0,0,0,0,0,0,P8,0,0,0,0,0,0,0,0,0,0,0)';
      PINUSE='POWER';
      NO_LOAD_CHECK='Both';
      NO_IO_CHECK='Both';
      NO_ASSERT_CHECK='TRUE';
      NO_DIR_CHECK='TRUE';
      ALLOW_CONNECT='TRUE';
    'VSS_P10':
      PIN_NUMBER='(0,0,0,0,0,0,0,0,0,0,0,0,0,0,0,0,0,0,0,0,0,0,0,0,0,0,0,0,P10,0,0,0,0,0,0,0,0,0,0,0)';
      PINUSE='POWER';
      NO_LOAD_CHECK='Both';
      NO_IO_CHECK='Both';
      NO_ASSERT_CHECK='TRUE';
      NO_DIR_CHECK='TRUE';
      ALLOW_CONNECT='TRUE';
    'VSS_P15':
      PIN_NUMBER='(0,0,0,0,0,0,0,0,0,0,0,0,0,0,0,0,0,0,0,0,0,0,0,0,0,0,0,0,P15,0,0,0,0,0,0,0,0,0,0,0)';
      PINUSE='POWER';
      NO_LOAD_CHECK='Both';
      NO_IO_CHECK='Both';
      NO_ASSERT_CHECK='TRUE';
      NO_DIR_CHECK='TRUE';
      ALLOW_CONNECT='TRUE';
    'VSS_P17':
      PIN_NUMBER='(0,0,0,0,0,0,0,0,0,0,0,0,0,0,0,0,0,0,0,0,0,0,0,0,0,0,0,0,P17,0,0,0,0,0,0,0,0,0,0,0)';
      PINUSE='POWER';
      NO_LOAD_CHECK='Both';
      NO_IO_CHECK='Both';
      NO_ASSERT_CHECK='TRUE';
      NO_DIR_CHECK='TRUE';
      ALLOW_CONNECT='TRUE';
    'VSS_P23':
      PIN_NUMBER='(0,0,0,0,0,0,0,0,0,0,0,0,0,0,0,0,0,0,0,0,0,0,0,0,0,0,0,0,P23,0,0,0,0,0,0,0,0,0,0,0)';
      PINUSE='POWER';
      NO_LOAD_CHECK='Both';
      NO_IO_CHECK='Both';
      NO_ASSERT_CHECK='TRUE';
      NO_DIR_CHECK='TRUE';
      ALLOW_CONNECT='TRUE';
    'VSS_P24':
      PIN_NUMBER='(0,0,0,0,0,0,0,0,0,0,0,0,0,0,0,0,0,0,0,0,0,0,0,0,0,0,0,0,P24,0,0,0,0,0,0,0,0,0,0,0)';
      PINUSE='POWER';
      NO_LOAD_CHECK='Both';
      NO_IO_CHECK='Both';
      NO_ASSERT_CHECK='TRUE';
      NO_DIR_CHECK='TRUE';
      ALLOW_CONNECT='TRUE';
    'VSS_P26':
      PIN_NUMBER='(0,0,0,0,0,0,0,0,0,0,0,0,0,0,0,0,0,0,0,0,0,0,0,0,0,0,0,0,P26,0,0,0,0,0,0,0,0,0,0,0)';
      PINUSE='POWER';
      NO_LOAD_CHECK='Both';
      NO_IO_CHECK='Both';
      NO_ASSERT_CHECK='TRUE';
      NO_DIR_CHECK='TRUE';
      ALLOW_CONNECT='TRUE';
    'VSS_P27':
      PIN_NUMBER='(0,0,0,0,0,0,0,0,0,0,0,0,0,0,0,0,0,0,0,0,0,0,0,0,0,0,0,0,P27,0,0,0,0,0,0,0,0,0,0,0)';
      PINUSE='POWER';
      NO_LOAD_CHECK='Both';
      NO_IO_CHECK='Both';
      NO_ASSERT_CHECK='TRUE';
      NO_DIR_CHECK='TRUE';
      ALLOW_CONNECT='TRUE';
    'VSS_P28':
      PIN_NUMBER='(0,0,0,0,0,0,0,0,0,0,0,0,0,0,0,0,0,0,0,0,0,0,0,0,0,0,0,0,P28,0,0,0,0,0,0,0,0,0,0,0)';
      PINUSE='POWER';
      NO_LOAD_CHECK='Both';
      NO_IO_CHECK='Both';
      NO_ASSERT_CHECK='TRUE';
      NO_DIR_CHECK='TRUE';
      ALLOW_CONNECT='TRUE';
    'VSS_P29':
      PIN_NUMBER='(0,0,0,0,0,0,0,0,0,0,0,0,0,0,0,0,0,0,0,0,0,0,0,0,0,0,0,0,P29,0,0,0,0,0,0,0,0,0,0,0)';
      PINUSE='POWER';
      NO_LOAD_CHECK='Both';
      NO_IO_CHECK='Both';
      NO_ASSERT_CHECK='TRUE';
      NO_DIR_CHECK='TRUE';
      ALLOW_CONNECT='TRUE';
    'VSS_P30':
      PIN_NUMBER='(0,0,0,0,0,0,0,0,0,0,0,0,0,0,0,0,0,0,0,0,0,0,0,0,0,0,0,0,P30,0,0,0,0,0,0,0,0,0,0,0)';
      PINUSE='POWER';
      NO_LOAD_CHECK='Both';
      NO_IO_CHECK='Both';
      NO_ASSERT_CHECK='TRUE';
      NO_DIR_CHECK='TRUE';
      ALLOW_CONNECT='TRUE';
    'VSS_P31':
      PIN_NUMBER='(0,0,0,0,0,0,0,0,0,0,0,0,0,0,0,0,0,0,0,0,0,0,0,0,0,0,0,0,P31,0,0,0,0,0,0,0,0,0,0,0)';
      PINUSE='POWER';
      NO_LOAD_CHECK='Both';
      NO_IO_CHECK='Both';
      NO_ASSERT_CHECK='TRUE';
      NO_DIR_CHECK='TRUE';
      ALLOW_CONNECT='TRUE';
    'VSS_P32':
      PIN_NUMBER='(0,0,0,0,0,0,0,0,0,0,0,0,0,0,0,0,0,0,0,0,0,0,0,0,0,0,0,0,P32,0,0,0,0,0,0,0,0,0,0,0)';
      PINUSE='POWER';
      NO_LOAD_CHECK='Both';
      NO_IO_CHECK='Both';
      NO_ASSERT_CHECK='TRUE';
      NO_DIR_CHECK='TRUE';
      ALLOW_CONNECT='TRUE';
    'VSS_P33':
      PIN_NUMBER='(0,0,0,0,0,0,0,0,0,0,0,0,0,0,0,0,0,0,0,0,0,0,0,0,0,0,0,0,P33,0,0,0,0,0,0,0,0,0,0,0)';
      PINUSE='POWER';
      NO_LOAD_CHECK='Both';
      NO_IO_CHECK='Both';
      NO_ASSERT_CHECK='TRUE';
      NO_DIR_CHECK='TRUE';
      ALLOW_CONNECT='TRUE';
    'VSS_P34':
      PIN_NUMBER='(0,0,0,0,0,0,0,0,0,0,0,0,0,0,0,0,0,0,0,0,0,0,0,0,0,0,0,0,P34,0,0,0,0,0,0,0,0,0,0,0)';
      PINUSE='POWER';
      NO_LOAD_CHECK='Both';
      NO_IO_CHECK='Both';
      NO_ASSERT_CHECK='TRUE';
      NO_DIR_CHECK='TRUE';
      ALLOW_CONNECT='TRUE';
    'VSS_P37':
      PIN_NUMBER='(0,0,0,0,0,0,0,0,0,0,0,0,0,0,0,0,0,0,0,0,0,0,0,0,0,0,0,0,P37,0,0,0,0,0,0,0,0,0,0,0)';
      PINUSE='POWER';
      NO_LOAD_CHECK='Both';
      NO_IO_CHECK='Both';
      NO_ASSERT_CHECK='TRUE';
      NO_DIR_CHECK='TRUE';
      ALLOW_CONNECT='TRUE';
    'VSS_P39':
      PIN_NUMBER='(0,0,0,0,0,0,0,0,0,0,0,0,0,0,0,0,0,0,0,0,0,0,0,0,0,0,0,0,P39,0,0,0,0,0,0,0,0,0,0,0)';
      PINUSE='POWER';
      NO_LOAD_CHECK='Both';
      NO_IO_CHECK='Both';
      NO_ASSERT_CHECK='TRUE';
      NO_DIR_CHECK='TRUE';
      ALLOW_CONNECT='TRUE';
    'VSS_P42':
      PIN_NUMBER='(0,0,0,0,0,0,0,0,0,0,0,0,0,0,0,0,0,0,0,0,0,0,0,0,0,0,0,0,P42,0,0,0,0,0,0,0,0,0,0,0)';
      PINUSE='POWER';
      NO_LOAD_CHECK='Both';
      NO_IO_CHECK='Both';
      NO_ASSERT_CHECK='TRUE';
      NO_DIR_CHECK='TRUE';
      ALLOW_CONNECT='TRUE';
    'VSS_P43':
      PIN_NUMBER='(0,0,0,0,0,0,0,0,0,0,0,0,0,0,0,0,0,0,0,0,0,0,0,0,0,0,0,0,P43,0,0,0,0,0,0,0,0,0,0,0)';
      PINUSE='POWER';
      NO_LOAD_CHECK='Both';
      NO_IO_CHECK='Both';
      NO_ASSERT_CHECK='TRUE';
      NO_DIR_CHECK='TRUE';
      ALLOW_CONNECT='TRUE';
    'VSS_P44':
      PIN_NUMBER='(0,0,0,0,0,0,0,0,0,0,0,0,0,0,0,0,0,0,0,0,0,0,0,0,0,0,0,0,P44,0,0,0,0,0,0,0,0,0,0,0)';
      PINUSE='POWER';
      NO_LOAD_CHECK='Both';
      NO_IO_CHECK='Both';
      NO_ASSERT_CHECK='TRUE';
      NO_DIR_CHECK='TRUE';
      ALLOW_CONNECT='TRUE';
    'VSS_P45':
      PIN_NUMBER='(0,0,0,0,0,0,0,0,0,0,0,0,0,0,0,0,0,0,0,0,0,0,0,0,0,0,0,0,P45,0,0,0,0,0,0,0,0,0,0,0)';
      PINUSE='POWER';
      NO_LOAD_CHECK='Both';
      NO_IO_CHECK='Both';
      NO_ASSERT_CHECK='TRUE';
      NO_DIR_CHECK='TRUE';
      ALLOW_CONNECT='TRUE';
    'VSS_P46':
      PIN_NUMBER='(0,0,0,0,0,0,0,0,0,0,0,0,0,0,0,0,0,0,0,0,0,0,0,0,0,0,0,0,P46,0,0,0,0,0,0,0,0,0,0,0)';
      PINUSE='POWER';
      NO_LOAD_CHECK='Both';
      NO_IO_CHECK='Both';
      NO_ASSERT_CHECK='TRUE';
      NO_DIR_CHECK='TRUE';
      ALLOW_CONNECT='TRUE';
    'VSS_P47':
      PIN_NUMBER='(0,0,0,0,0,0,0,0,0,0,0,0,0,0,0,0,0,0,0,0,0,0,0,0,0,0,0,0,P47,0,0,0,0,0,0,0,0,0,0,0)';
      PINUSE='POWER';
      NO_LOAD_CHECK='Both';
      NO_IO_CHECK='Both';
      NO_ASSERT_CHECK='TRUE';
      NO_DIR_CHECK='TRUE';
      ALLOW_CONNECT='TRUE';
    'VSS_P48':
      PIN_NUMBER='(0,0,0,0,0,0,0,0,0,0,0,0,0,0,0,0,0,0,0,0,0,0,0,0,0,0,0,0,P48,0,0,0,0,0,0,0,0,0,0,0)';
      PINUSE='POWER';
      NO_LOAD_CHECK='Both';
      NO_IO_CHECK='Both';
      NO_ASSERT_CHECK='TRUE';
      NO_DIR_CHECK='TRUE';
      ALLOW_CONNECT='TRUE';
    'VSS_P49':
      PIN_NUMBER='(0,0,0,0,0,0,0,0,0,0,0,0,0,0,0,0,0,0,0,0,0,0,0,0,0,0,0,0,P49,0,0,0,0,0,0,0,0,0,0,0)';
      PINUSE='POWER';
      NO_LOAD_CHECK='Both';
      NO_IO_CHECK='Both';
      NO_ASSERT_CHECK='TRUE';
      NO_DIR_CHECK='TRUE';
      ALLOW_CONNECT='TRUE';
    'VSS_P50':
      PIN_NUMBER='(0,0,0,0,0,0,0,0,0,0,0,0,0,0,0,0,0,0,0,0,0,0,0,0,0,0,0,0,P50,0,0,0,0,0,0,0,0,0,0,0)';
      PINUSE='POWER';
      NO_LOAD_CHECK='Both';
      NO_IO_CHECK='Both';
      NO_ASSERT_CHECK='TRUE';
      NO_DIR_CHECK='TRUE';
      ALLOW_CONNECT='TRUE';
    'VSS_P51':
      PIN_NUMBER='(0,0,0,0,0,0,0,0,0,0,0,0,0,0,0,0,0,0,0,0,0,0,0,0,0,0,0,0,P51,0,0,0,0,0,0,0,0,0,0,0)';
      PINUSE='POWER';
      NO_LOAD_CHECK='Both';
      NO_IO_CHECK='Both';
      NO_ASSERT_CHECK='TRUE';
      NO_DIR_CHECK='TRUE';
      ALLOW_CONNECT='TRUE';
    'VSS_P52':
      PIN_NUMBER='(0,0,0,0,0,0,0,0,0,0,0,0,0,0,0,0,0,0,0,0,0,0,0,0,0,0,0,0,P52,0,0,0,0,0,0,0,0,0,0,0)';
      PINUSE='POWER';
      NO_LOAD_CHECK='Both';
      NO_IO_CHECK='Both';
      NO_ASSERT_CHECK='TRUE';
      NO_DIR_CHECK='TRUE';
      ALLOW_CONNECT='TRUE';
    'VSS_P53':
      PIN_NUMBER='(0,0,0,0,0,0,0,0,0,0,0,0,0,0,0,0,0,0,0,0,0,0,0,0,0,0,0,0,P53,0,0,0,0,0,0,0,0,0,0,0)';
      PINUSE='POWER';
      NO_LOAD_CHECK='Both';
      NO_IO_CHECK='Both';
      NO_ASSERT_CHECK='TRUE';
      NO_DIR_CHECK='TRUE';
      ALLOW_CONNECT='TRUE';
    'VSS_P59':
      PIN_NUMBER='(0,0,0,0,0,0,0,0,0,0,0,0,0,0,0,0,0,0,0,0,0,0,0,0,0,0,0,0,P59,0,0,0,0,0,0,0,0,0,0,0)';
      PINUSE='POWER';
      NO_LOAD_CHECK='Both';
      NO_IO_CHECK='Both';
      NO_ASSERT_CHECK='TRUE';
      NO_DIR_CHECK='TRUE';
      ALLOW_CONNECT='TRUE';
    'VSS_P61':
      PIN_NUMBER='(0,0,0,0,0,0,0,0,0,0,0,0,0,0,0,0,0,0,0,0,0,0,0,0,0,0,0,0,P61,0,0,0,0,0,0,0,0,0,0,0)';
      PINUSE='POWER';
      NO_LOAD_CHECK='Both';
      NO_IO_CHECK='Both';
      NO_ASSERT_CHECK='TRUE';
      NO_DIR_CHECK='TRUE';
      ALLOW_CONNECT='TRUE';
    'VSS_P66':
      PIN_NUMBER='(0,0,0,0,0,0,0,0,0,0,0,0,0,0,0,0,0,0,0,0,0,0,0,0,0,0,0,0,P66,0,0,0,0,0,0,0,0,0,0,0)';
      PINUSE='POWER';
      NO_LOAD_CHECK='Both';
      NO_IO_CHECK='Both';
      NO_ASSERT_CHECK='TRUE';
      NO_DIR_CHECK='TRUE';
      ALLOW_CONNECT='TRUE';
    'VSS_P73':
      PIN_NUMBER='(0,0,0,0,0,0,0,0,0,0,0,0,0,0,0,0,0,0,0,0,0,0,0,0,0,0,0,0,P73,0,0,0,0,0,0,0,0,0,0,0)';
      PINUSE='POWER';
      NO_LOAD_CHECK='Both';
      NO_IO_CHECK='Both';
      NO_ASSERT_CHECK='TRUE';
      NO_DIR_CHECK='TRUE';
      ALLOW_CONNECT='TRUE';
    'VSS_R1':
      PIN_NUMBER='(0,0,0,0,0,0,0,0,0,0,0,0,0,0,0,0,0,0,0,0,0,0,0,0,0,0,0,0,R1,0,0,0,0,0,0,0,0,0,0,0)';
      PINUSE='POWER';
      NO_LOAD_CHECK='Both';
      NO_IO_CHECK='Both';
      NO_ASSERT_CHECK='TRUE';
      NO_DIR_CHECK='TRUE';
      ALLOW_CONNECT='TRUE';
    'VSS_R4':
      PIN_NUMBER='(0,0,0,0,0,0,0,0,0,0,0,0,0,0,0,0,0,0,0,0,0,0,0,0,0,0,0,0,R4,0,0,0,0,0,0,0,0,0,0,0)';
      PINUSE='POWER';
      NO_LOAD_CHECK='Both';
      NO_IO_CHECK='Both';
      NO_ASSERT_CHECK='TRUE';
      NO_DIR_CHECK='TRUE';
      ALLOW_CONNECT='TRUE';
    'VSS_R6':
      PIN_NUMBER='(0,0,0,0,0,0,0,0,0,0,0,0,0,0,0,0,0,0,0,0,0,0,0,0,0,0,0,0,R6,0,0,0,0,0,0,0,0,0,0,0)';
      PINUSE='POWER';
      NO_LOAD_CHECK='Both';
      NO_IO_CHECK='Both';
      NO_ASSERT_CHECK='TRUE';
      NO_DIR_CHECK='TRUE';
      ALLOW_CONNECT='TRUE';
    'VSS_R8':
      PIN_NUMBER='(0,0,0,0,0,0,0,0,0,0,0,0,0,0,0,0,0,0,0,0,0,0,0,0,0,0,0,0,R8,0,0,0,0,0,0,0,0,0,0,0)';
      PINUSE='POWER';
      NO_LOAD_CHECK='Both';
      NO_IO_CHECK='Both';
      NO_ASSERT_CHECK='TRUE';
      NO_DIR_CHECK='TRUE';
      ALLOW_CONNECT='TRUE';
    'VSS_R11':
      PIN_NUMBER='(0,0,0,0,0,0,0,0,0,0,0,0,0,0,0,0,0,0,0,0,0,0,0,0,0,0,0,0,R11,0,0,0,0,0,0,0,0,0,0,0)';
      PINUSE='POWER';
      NO_LOAD_CHECK='Both';
      NO_IO_CHECK='Both';
      NO_ASSERT_CHECK='TRUE';
      NO_DIR_CHECK='TRUE';
      ALLOW_CONNECT='TRUE';
    'VSS_R13':
      PIN_NUMBER='(0,0,0,0,0,0,0,0,0,0,0,0,0,0,0,0,0,0,0,0,0,0,0,0,0,0,0,0,R13,0,0,0,0,0,0,0,0,0,0,0)';
      PINUSE='POWER';
      NO_LOAD_CHECK='Both';
      NO_IO_CHECK='Both';
      NO_ASSERT_CHECK='TRUE';
      NO_DIR_CHECK='TRUE';
      ALLOW_CONNECT='TRUE';
    'VSS_R15':
      PIN_NUMBER='(0,0,0,0,0,0,0,0,0,0,0,0,0,0,0,0,0,0,0,0,0,0,0,0,0,0,0,0,R15,0,0,0,0,0,0,0,0,0,0,0)';
      PINUSE='POWER';
      NO_LOAD_CHECK='Both';
      NO_IO_CHECK='Both';
      NO_ASSERT_CHECK='TRUE';
      NO_DIR_CHECK='TRUE';
      ALLOW_CONNECT='TRUE';
    'VSS_R18':
      PIN_NUMBER='(0,0,0,0,0,0,0,0,0,0,0,0,0,0,0,0,0,0,0,0,0,0,0,0,0,0,0,0,R18,0,0,0,0,0,0,0,0,0,0,0)';
      PINUSE='POWER';
      NO_LOAD_CHECK='Both';
      NO_IO_CHECK='Both';
      NO_ASSERT_CHECK='TRUE';
      NO_DIR_CHECK='TRUE';
      ALLOW_CONNECT='TRUE';
    'VSS_R20':
      PIN_NUMBER='(0,0,0,0,0,0,0,0,0,0,0,0,0,0,0,0,0,0,0,0,0,0,0,0,0,0,0,0,R20,0,0,0,0,0,0,0,0,0,0,0)';
      PINUSE='POWER';
      NO_LOAD_CHECK='Both';
      NO_IO_CHECK='Both';
      NO_ASSERT_CHECK='TRUE';
      NO_DIR_CHECK='TRUE';
      ALLOW_CONNECT='TRUE';
    'VSS_R22':
      PIN_NUMBER='(0,0,0,0,0,0,0,0,0,0,0,0,0,0,0,0,0,0,0,0,0,0,0,0,0,0,0,0,R22,0,0,0,0,0,0,0,0,0,0,0)';
      PINUSE='POWER';
      NO_LOAD_CHECK='Both';
      NO_IO_CHECK='Both';
      NO_ASSERT_CHECK='TRUE';
      NO_DIR_CHECK='TRUE';
      ALLOW_CONNECT='TRUE';
    'VSS_R25':
      PIN_NUMBER='(0,0,0,0,0,0,0,0,0,0,0,0,0,0,0,0,0,0,0,0,0,0,0,0,0,0,0,0,R25,0,0,0,0,0,0,0,0,0,0,0)';
      PINUSE='POWER';
      NO_LOAD_CHECK='Both';
      NO_IO_CHECK='Both';
      NO_ASSERT_CHECK='TRUE';
      NO_DIR_CHECK='TRUE';
      ALLOW_CONNECT='TRUE';
    'VSS_R28':
      PIN_NUMBER='(0,0,0,0,0,0,0,0,0,0,0,0,0,0,0,0,0,0,0,0,0,0,0,0,0,0,0,0,R28,0,0,0,0,0,0,0,0,0,0,0)';
      PINUSE='POWER';
      NO_LOAD_CHECK='Both';
      NO_IO_CHECK='Both';
      NO_ASSERT_CHECK='TRUE';
      NO_DIR_CHECK='TRUE';
      ALLOW_CONNECT='TRUE';
    'VSS_R31':
      PIN_NUMBER='(0,0,0,0,0,0,0,0,0,0,0,0,0,0,0,0,0,0,0,0,0,0,0,0,0,0,0,0,R31,0,0,0,0,0,0,0,0,0,0,0)';
      PINUSE='POWER';
      NO_LOAD_CHECK='Both';
      NO_IO_CHECK='Both';
      NO_ASSERT_CHECK='TRUE';
      NO_DIR_CHECK='TRUE';
      ALLOW_CONNECT='TRUE';
    'VSS_R34':
      PIN_NUMBER='(0,0,0,0,0,0,0,0,0,0,0,0,0,0,0,0,0,0,0,0,0,0,0,0,0,0,0,0,R34,0,0,0,0,0,0,0,0,0,0,0)';
      PINUSE='POWER';
      NO_LOAD_CHECK='Both';
      NO_IO_CHECK='Both';
      NO_ASSERT_CHECK='TRUE';
      NO_DIR_CHECK='TRUE';
      ALLOW_CONNECT='TRUE';
    'VSS_R35':
      PIN_NUMBER='(0,0,0,0,0,0,0,0,0,0,0,0,0,0,0,0,0,0,0,0,0,0,0,0,0,0,0,0,R35,0,0,0,0,0,0,0,0,0,0,0)';
      PINUSE='POWER';
      NO_LOAD_CHECK='Both';
      NO_IO_CHECK='Both';
      NO_ASSERT_CHECK='TRUE';
      NO_DIR_CHECK='TRUE';
      ALLOW_CONNECT='TRUE';
    'VSS_R36':
      PIN_NUMBER='(0,0,0,0,0,0,0,0,0,0,0,0,0,0,0,0,0,0,0,0,0,0,0,0,0,0,0,0,R36,0,0,0,0,0,0,0,0,0,0,0)';
      PINUSE='POWER';
      NO_LOAD_CHECK='Both';
      NO_IO_CHECK='Both';
      NO_ASSERT_CHECK='TRUE';
      NO_DIR_CHECK='TRUE';
      ALLOW_CONNECT='TRUE';
    'VSS_R40':
      PIN_NUMBER='(0,0,0,0,0,0,0,0,0,0,0,0,0,0,0,0,0,0,0,0,0,0,0,0,0,0,0,0,R40,0,0,0,0,0,0,0,0,0,0,0)';
      PINUSE='POWER';
      NO_LOAD_CHECK='Both';
      NO_IO_CHECK='Both';
      NO_ASSERT_CHECK='TRUE';
      NO_DIR_CHECK='TRUE';
      ALLOW_CONNECT='TRUE';
    'VSS_R41':
      PIN_NUMBER='(0,0,0,0,0,0,0,0,0,0,0,0,0,0,0,0,0,0,0,0,0,0,0,0,0,0,0,0,R41,0,0,0,0,0,0,0,0,0,0,0)';
      PINUSE='POWER';
      NO_LOAD_CHECK='Both';
      NO_IO_CHECK='Both';
      NO_ASSERT_CHECK='TRUE';
      NO_DIR_CHECK='TRUE';
      ALLOW_CONNECT='TRUE';
    'VSS_R42':
      PIN_NUMBER='(0,0,0,0,0,0,0,0,0,0,0,0,0,0,0,0,0,0,0,0,0,0,0,0,0,0,0,0,R42,0,0,0,0,0,0,0,0,0,0,0)';
      PINUSE='POWER';
      NO_LOAD_CHECK='Both';
      NO_IO_CHECK='Both';
      NO_ASSERT_CHECK='TRUE';
      NO_DIR_CHECK='TRUE';
      ALLOW_CONNECT='TRUE';
    'VSS_R45':
      PIN_NUMBER='(0,0,0,0,0,0,0,0,0,0,0,0,0,0,0,0,0,0,0,0,0,0,0,0,0,0,0,0,R45,0,0,0,0,0,0,0,0,0,0,0)';
      PINUSE='POWER';
      NO_LOAD_CHECK='Both';
      NO_IO_CHECK='Both';
      NO_ASSERT_CHECK='TRUE';
      NO_DIR_CHECK='TRUE';
      ALLOW_CONNECT='TRUE';
    'VSS_AB68':
      PIN_NUMBER='(0,0,0,0,0,0,0,0,0,0,0,0,0,0,0,0,0,0,0,0,0,0,0,0,0,0,0,0,0,AB68,0,0,0,0,0,0,0,0,0,0)';
      PINUSE='POWER';
      NO_LOAD_CHECK='Both';
      NO_IO_CHECK='Both';
      NO_ASSERT_CHECK='TRUE';
      NO_DIR_CHECK='TRUE';
      ALLOW_CONNECT='TRUE';
    'VSS_AB71':
      PIN_NUMBER='(0,0,0,0,0,0,0,0,0,0,0,0,0,0,0,0,0,0,0,0,0,0,0,0,0,0,0,0,0,AB71,0,0,0,0,0,0,0,0,0,0)';
      PINUSE='POWER';
      NO_LOAD_CHECK='Both';
      NO_IO_CHECK='Both';
      NO_ASSERT_CHECK='TRUE';
      NO_DIR_CHECK='TRUE';
      ALLOW_CONNECT='TRUE';
    'VSS_AB73':
      PIN_NUMBER='(0,0,0,0,0,0,0,0,0,0,0,0,0,0,0,0,0,0,0,0,0,0,0,0,0,0,0,0,0,AB73,0,0,0,0,0,0,0,0,0,0)';
      PINUSE='POWER';
      NO_LOAD_CHECK='Both';
      NO_IO_CHECK='Both';
      NO_ASSERT_CHECK='TRUE';
      NO_DIR_CHECK='TRUE';
      ALLOW_CONNECT='TRUE';
    'VSS_AC1':
      PIN_NUMBER='(0,0,0,0,0,0,0,0,0,0,0,0,0,0,0,0,0,0,0,0,0,0,0,0,0,0,0,0,0,AC1,0,0,0,0,0,0,0,0,0,0)';
      PINUSE='POWER';
      NO_LOAD_CHECK='Both';
      NO_IO_CHECK='Both';
      NO_ASSERT_CHECK='TRUE';
      NO_DIR_CHECK='TRUE';
      ALLOW_CONNECT='TRUE';
    'VSS_AC6':
      PIN_NUMBER='(0,0,0,0,0,0,0,0,0,0,0,0,0,0,0,0,0,0,0,0,0,0,0,0,0,0,0,0,0,AC6,0,0,0,0,0,0,0,0,0,0)';
      PINUSE='POWER';
      NO_LOAD_CHECK='Both';
      NO_IO_CHECK='Both';
      NO_ASSERT_CHECK='TRUE';
      NO_DIR_CHECK='TRUE';
      ALLOW_CONNECT='TRUE';
    'VSS_AC8':
      PIN_NUMBER='(0,0,0,0,0,0,0,0,0,0,0,0,0,0,0,0,0,0,0,0,0,0,0,0,0,0,0,0,0,AC8,0,0,0,0,0,0,0,0,0,0)';
      PINUSE='POWER';
      NO_LOAD_CHECK='Both';
      NO_IO_CHECK='Both';
      NO_ASSERT_CHECK='TRUE';
      NO_DIR_CHECK='TRUE';
      ALLOW_CONNECT='TRUE';
    'VSS_AC13':
      PIN_NUMBER='(0,0,0,0,0,0,0,0,0,0,0,0,0,0,0,0,0,0,0,0,0,0,0,0,0,0,0,0,0,AC13,0,0,0,0,0,0,0,0,0,0)';
      PINUSE='POWER';
      NO_LOAD_CHECK='Both';
      NO_IO_CHECK='Both';
      NO_ASSERT_CHECK='TRUE';
      NO_DIR_CHECK='TRUE';
      ALLOW_CONNECT='TRUE';
    'VSS_AC15':
      PIN_NUMBER='(0,0,0,0,0,0,0,0,0,0,0,0,0,0,0,0,0,0,0,0,0,0,0,0,0,0,0,0,0,AC15,0,0,0,0,0,0,0,0,0,0)';
      PINUSE='POWER';
      NO_LOAD_CHECK='Both';
      NO_IO_CHECK='Both';
      NO_ASSERT_CHECK='TRUE';
      NO_DIR_CHECK='TRUE';
      ALLOW_CONNECT='TRUE';
    'VSS_AC20':
      PIN_NUMBER='(0,0,0,0,0,0,0,0,0,0,0,0,0,0,0,0,0,0,0,0,0,0,0,0,0,0,0,0,0,AC20,0,0,0,0,0,0,0,0,0,0)';
      PINUSE='POWER';
      NO_LOAD_CHECK='Both';
      NO_IO_CHECK='Both';
      NO_ASSERT_CHECK='TRUE';
      NO_DIR_CHECK='TRUE';
      ALLOW_CONNECT='TRUE';
    'VSS_AC22':
      PIN_NUMBER='(0,0,0,0,0,0,0,0,0,0,0,0,0,0,0,0,0,0,0,0,0,0,0,0,0,0,0,0,0,AC22,0,0,0,0,0,0,0,0,0,0)';
      PINUSE='POWER';
      NO_LOAD_CHECK='Both';
      NO_IO_CHECK='Both';
      NO_ASSERT_CHECK='TRUE';
      NO_DIR_CHECK='TRUE';
      ALLOW_CONNECT='TRUE';
    'VSS_AC25':
      PIN_NUMBER='(0,0,0,0,0,0,0,0,0,0,0,0,0,0,0,0,0,0,0,0,0,0,0,0,0,0,0,0,0,AC25,0,0,0,0,0,0,0,0,0,0)';
      PINUSE='POWER';
      NO_LOAD_CHECK='Both';
      NO_IO_CHECK='Both';
      NO_ASSERT_CHECK='TRUE';
      NO_DIR_CHECK='TRUE';
      ALLOW_CONNECT='TRUE';
    'VSS_AC28':
      PIN_NUMBER='(0,0,0,0,0,0,0,0,0,0,0,0,0,0,0,0,0,0,0,0,0,0,0,0,0,0,0,0,0,AC28,0,0,0,0,0,0,0,0,0,0)';
      PINUSE='POWER';
      NO_LOAD_CHECK='Both';
      NO_IO_CHECK='Both';
      NO_ASSERT_CHECK='TRUE';
      NO_DIR_CHECK='TRUE';
      ALLOW_CONNECT='TRUE';
    'VSS_AC31':
      PIN_NUMBER='(0,0,0,0,0,0,0,0,0,0,0,0,0,0,0,0,0,0,0,0,0,0,0,0,0,0,0,0,0,AC31,0,0,0,0,0,0,0,0,0,0)';
      PINUSE='POWER';
      NO_LOAD_CHECK='Both';
      NO_IO_CHECK='Both';
      NO_ASSERT_CHECK='TRUE';
      NO_DIR_CHECK='TRUE';
      ALLOW_CONNECT='TRUE';
    'VSS_AC34':
      PIN_NUMBER='(0,0,0,0,0,0,0,0,0,0,0,0,0,0,0,0,0,0,0,0,0,0,0,0,0,0,0,0,0,AC34,0,0,0,0,0,0,0,0,0,0)';
      PINUSE='POWER';
      NO_LOAD_CHECK='Both';
      NO_IO_CHECK='Both';
      NO_ASSERT_CHECK='TRUE';
      NO_DIR_CHECK='TRUE';
      ALLOW_CONNECT='TRUE';
    'VSS_AC42':
      PIN_NUMBER='(0,0,0,0,0,0,0,0,0,0,0,0,0,0,0,0,0,0,0,0,0,0,0,0,0,0,0,0,0,AC42,0,0,0,0,0,0,0,0,0,0)';
      PINUSE='POWER';
      NO_LOAD_CHECK='Both';
      NO_IO_CHECK='Both';
      NO_ASSERT_CHECK='TRUE';
      NO_DIR_CHECK='TRUE';
      ALLOW_CONNECT='TRUE';
    'VSS_AC45':
      PIN_NUMBER='(0,0,0,0,0,0,0,0,0,0,0,0,0,0,0,0,0,0,0,0,0,0,0,0,0,0,0,0,0,AC45,0,0,0,0,0,0,0,0,0,0)';
      PINUSE='POWER';
      NO_LOAD_CHECK='Both';
      NO_IO_CHECK='Both';
      NO_ASSERT_CHECK='TRUE';
      NO_DIR_CHECK='TRUE';
      ALLOW_CONNECT='TRUE';
    'VSS_AC48':
      PIN_NUMBER='(0,0,0,0,0,0,0,0,0,0,0,0,0,0,0,0,0,0,0,0,0,0,0,0,0,0,0,0,0,AC48,0,0,0,0,0,0,0,0,0,0)';
      PINUSE='POWER';
      NO_LOAD_CHECK='Both';
      NO_IO_CHECK='Both';
      NO_ASSERT_CHECK='TRUE';
      NO_DIR_CHECK='TRUE';
      ALLOW_CONNECT='TRUE';
    'VSS_AC51':
      PIN_NUMBER='(0,0,0,0,0,0,0,0,0,0,0,0,0,0,0,0,0,0,0,0,0,0,0,0,0,0,0,0,0,AC51,0,0,0,0,0,0,0,0,0,0)';
      PINUSE='POWER';
      NO_LOAD_CHECK='Both';
      NO_IO_CHECK='Both';
      NO_ASSERT_CHECK='TRUE';
      NO_DIR_CHECK='TRUE';
      ALLOW_CONNECT='TRUE';
    'VSS_AC54':
      PIN_NUMBER='(0,0,0,0,0,0,0,0,0,0,0,0,0,0,0,0,0,0,0,0,0,0,0,0,0,0,0,0,0,AC54,0,0,0,0,0,0,0,0,0,0)';
      PINUSE='POWER';
      NO_LOAD_CHECK='Both';
      NO_IO_CHECK='Both';
      NO_ASSERT_CHECK='TRUE';
      NO_DIR_CHECK='TRUE';
      ALLOW_CONNECT='TRUE';
    'VSS_AC56':
      PIN_NUMBER='(0,0,0,0,0,0,0,0,0,0,0,0,0,0,0,0,0,0,0,0,0,0,0,0,0,0,0,0,0,AC56,0,0,0,0,0,0,0,0,0,0)';
      PINUSE='POWER';
      NO_LOAD_CHECK='Both';
      NO_IO_CHECK='Both';
      NO_ASSERT_CHECK='TRUE';
      NO_DIR_CHECK='TRUE';
      ALLOW_CONNECT='TRUE';
    'VSS_AC61':
      PIN_NUMBER='(0,0,0,0,0,0,0,0,0,0,0,0,0,0,0,0,0,0,0,0,0,0,0,0,0,0,0,0,0,AC61,0,0,0,0,0,0,0,0,0,0)';
      PINUSE='POWER';
      NO_LOAD_CHECK='Both';
      NO_IO_CHECK='Both';
      NO_ASSERT_CHECK='TRUE';
      NO_DIR_CHECK='TRUE';
      ALLOW_CONNECT='TRUE';
    'VSS_AC63':
      PIN_NUMBER='(0,0,0,0,0,0,0,0,0,0,0,0,0,0,0,0,0,0,0,0,0,0,0,0,0,0,0,0,0,AC63,0,0,0,0,0,0,0,0,0,0)';
      PINUSE='POWER';
      NO_LOAD_CHECK='Both';
      NO_IO_CHECK='Both';
      NO_ASSERT_CHECK='TRUE';
      NO_DIR_CHECK='TRUE';
      ALLOW_CONNECT='TRUE';
    'VSS_AC68':
      PIN_NUMBER='(0,0,0,0,0,0,0,0,0,0,0,0,0,0,0,0,0,0,0,0,0,0,0,0,0,0,0,0,0,AC68,0,0,0,0,0,0,0,0,0,0)';
      PINUSE='POWER';
      NO_LOAD_CHECK='Both';
      NO_IO_CHECK='Both';
      NO_ASSERT_CHECK='TRUE';
      NO_DIR_CHECK='TRUE';
      ALLOW_CONNECT='TRUE';
    'VSS_AC70':
      PIN_NUMBER='(0,0,0,0,0,0,0,0,0,0,0,0,0,0,0,0,0,0,0,0,0,0,0,0,0,0,0,0,0,AC70,0,0,0,0,0,0,0,0,0,0)';
      PINUSE='POWER';
      NO_LOAD_CHECK='Both';
      NO_IO_CHECK='Both';
      NO_ASSERT_CHECK='TRUE';
      NO_DIR_CHECK='TRUE';
      ALLOW_CONNECT='TRUE';
    'VSS_AC75':
      PIN_NUMBER='(0,0,0,0,0,0,0,0,0,0,0,0,0,0,0,0,0,0,0,0,0,0,0,0,0,0,0,0,0,AC75,0,0,0,0,0,0,0,0,0,0)';
      PINUSE='POWER';
      NO_LOAD_CHECK='Both';
      NO_IO_CHECK='Both';
      NO_ASSERT_CHECK='TRUE';
      NO_DIR_CHECK='TRUE';
      ALLOW_CONNECT='TRUE';
    'VSS_AD3':
      PIN_NUMBER='(0,0,0,0,0,0,0,0,0,0,0,0,0,0,0,0,0,0,0,0,0,0,0,0,0,0,0,0,0,AD3,0,0,0,0,0,0,0,0,0,0)';
      PINUSE='POWER';
      NO_LOAD_CHECK='Both';
      NO_IO_CHECK='Both';
      NO_ASSERT_CHECK='TRUE';
      NO_DIR_CHECK='TRUE';
      ALLOW_CONNECT='TRUE';
    'VSS_AD5':
      PIN_NUMBER='(0,0,0,0,0,0,0,0,0,0,0,0,0,0,0,0,0,0,0,0,0,0,0,0,0,0,0,0,0,AD5,0,0,0,0,0,0,0,0,0,0)';
      PINUSE='POWER';
      NO_LOAD_CHECK='Both';
      NO_IO_CHECK='Both';
      NO_ASSERT_CHECK='TRUE';
      NO_DIR_CHECK='TRUE';
      ALLOW_CONNECT='TRUE';
    'VSS_AD8':
      PIN_NUMBER='(0,0,0,0,0,0,0,0,0,0,0,0,0,0,0,0,0,0,0,0,0,0,0,0,0,0,0,0,0,AD8,0,0,0,0,0,0,0,0,0,0)';
      PINUSE='POWER';
      NO_LOAD_CHECK='Both';
      NO_IO_CHECK='Both';
      NO_ASSERT_CHECK='TRUE';
      NO_DIR_CHECK='TRUE';
      ALLOW_CONNECT='TRUE';
    'VSS_AD10':
      PIN_NUMBER='(0,0,0,0,0,0,0,0,0,0,0,0,0,0,0,0,0,0,0,0,0,0,0,0,0,0,0,0,0,AD10,0,0,0,0,0,0,0,0,0,0)';
      PINUSE='POWER';
      NO_LOAD_CHECK='Both';
      NO_IO_CHECK='Both';
      NO_ASSERT_CHECK='TRUE';
      NO_DIR_CHECK='TRUE';
      ALLOW_CONNECT='TRUE';
    'VSS_AD12':
      PIN_NUMBER='(0,0,0,0,0,0,0,0,0,0,0,0,0,0,0,0,0,0,0,0,0,0,0,0,0,0,0,0,0,AD12,0,0,0,0,0,0,0,0,0,0)';
      PINUSE='POWER';
      NO_LOAD_CHECK='Both';
      NO_IO_CHECK='Both';
      NO_ASSERT_CHECK='TRUE';
      NO_DIR_CHECK='TRUE';
      ALLOW_CONNECT='TRUE';
    'VSS_AD15':
      PIN_NUMBER='(0,0,0,0,0,0,0,0,0,0,0,0,0,0,0,0,0,0,0,0,0,0,0,0,0,0,0,0,0,AD15,0,0,0,0,0,0,0,0,0,0)';
      PINUSE='POWER';
      NO_LOAD_CHECK='Both';
      NO_IO_CHECK='Both';
      NO_ASSERT_CHECK='TRUE';
      NO_DIR_CHECK='TRUE';
      ALLOW_CONNECT='TRUE';
    'VSS_AD17':
      PIN_NUMBER='(0,0,0,0,0,0,0,0,0,0,0,0,0,0,0,0,0,0,0,0,0,0,0,0,0,0,0,0,0,AD17,0,0,0,0,0,0,0,0,0,0)';
      PINUSE='POWER';
      NO_LOAD_CHECK='Both';
      NO_IO_CHECK='Both';
      NO_ASSERT_CHECK='TRUE';
      NO_DIR_CHECK='TRUE';
      ALLOW_CONNECT='TRUE';
    'VSS_AD19':
      PIN_NUMBER='(0,0,0,0,0,0,0,0,0,0,0,0,0,0,0,0,0,0,0,0,0,0,0,0,0,0,0,0,0,AD19,0,0,0,0,0,0,0,0,0,0)';
      PINUSE='POWER';
      NO_LOAD_CHECK='Both';
      NO_IO_CHECK='Both';
      NO_ASSERT_CHECK='TRUE';
      NO_DIR_CHECK='TRUE';
      ALLOW_CONNECT='TRUE';
    'VSS_AD23':
      PIN_NUMBER='(0,0,0,0,0,0,0,0,0,0,0,0,0,0,0,0,0,0,0,0,0,0,0,0,0,0,0,0,0,AD23,0,0,0,0,0,0,0,0,0,0)';
      PINUSE='POWER';
      NO_LOAD_CHECK='Both';
      NO_IO_CHECK='Both';
      NO_ASSERT_CHECK='TRUE';
      NO_DIR_CHECK='TRUE';
      ALLOW_CONNECT='TRUE';
    'VSS_AD24':
      PIN_NUMBER='(0,0,0,0,0,0,0,0,0,0,0,0,0,0,0,0,0,0,0,0,0,0,0,0,0,0,0,0,0,AD24,0,0,0,0,0,0,0,0,0,0)';
      PINUSE='POWER';
      NO_LOAD_CHECK='Both';
      NO_IO_CHECK='Both';
      NO_ASSERT_CHECK='TRUE';
      NO_DIR_CHECK='TRUE';
      ALLOW_CONNECT='TRUE';
    'VSS_AD25':
      PIN_NUMBER='(0,0,0,0,0,0,0,0,0,0,0,0,0,0,0,0,0,0,0,0,0,0,0,0,0,0,0,0,0,AD25,0,0,0,0,0,0,0,0,0,0)';
      PINUSE='POWER';
      NO_LOAD_CHECK='Both';
      NO_IO_CHECK='Both';
      NO_ASSERT_CHECK='TRUE';
      NO_DIR_CHECK='TRUE';
      ALLOW_CONNECT='TRUE';
    'VSS_AD26':
      PIN_NUMBER='(0,0,0,0,0,0,0,0,0,0,0,0,0,0,0,0,0,0,0,0,0,0,0,0,0,0,0,0,0,AD26,0,0,0,0,0,0,0,0,0,0)';
      PINUSE='POWER';
      NO_LOAD_CHECK='Both';
      NO_IO_CHECK='Both';
      NO_ASSERT_CHECK='TRUE';
      NO_DIR_CHECK='TRUE';
      ALLOW_CONNECT='TRUE';
    'VSS_AD27':
      PIN_NUMBER='(0,0,0,0,0,0,0,0,0,0,0,0,0,0,0,0,0,0,0,0,0,0,0,0,0,0,0,0,0,AD27,0,0,0,0,0,0,0,0,0,0)';
      PINUSE='POWER';
      NO_LOAD_CHECK='Both';
      NO_IO_CHECK='Both';
      NO_ASSERT_CHECK='TRUE';
      NO_DIR_CHECK='TRUE';
      ALLOW_CONNECT='TRUE';
    'VSS_AD28':
      PIN_NUMBER='(0,0,0,0,0,0,0,0,0,0,0,0,0,0,0,0,0,0,0,0,0,0,0,0,0,0,0,0,0,AD28,0,0,0,0,0,0,0,0,0,0)';
      PINUSE='POWER';
      NO_LOAD_CHECK='Both';
      NO_IO_CHECK='Both';
      NO_ASSERT_CHECK='TRUE';
      NO_DIR_CHECK='TRUE';
      ALLOW_CONNECT='TRUE';
    'VSS_AD29':
      PIN_NUMBER='(0,0,0,0,0,0,0,0,0,0,0,0,0,0,0,0,0,0,0,0,0,0,0,0,0,0,0,0,0,AD29,0,0,0,0,0,0,0,0,0,0)';
      PINUSE='POWER';
      NO_LOAD_CHECK='Both';
      NO_IO_CHECK='Both';
      NO_ASSERT_CHECK='TRUE';
      NO_DIR_CHECK='TRUE';
      ALLOW_CONNECT='TRUE';
    'VSS_AD30':
      PIN_NUMBER='(0,0,0,0,0,0,0,0,0,0,0,0,0,0,0,0,0,0,0,0,0,0,0,0,0,0,0,0,0,AD30,0,0,0,0,0,0,0,0,0,0)';
      PINUSE='POWER';
      NO_LOAD_CHECK='Both';
      NO_IO_CHECK='Both';
      NO_ASSERT_CHECK='TRUE';
      NO_DIR_CHECK='TRUE';
      ALLOW_CONNECT='TRUE';
    'VSS_AD32':
      PIN_NUMBER='(0,0,0,0,0,0,0,0,0,0,0,0,0,0,0,0,0,0,0,0,0,0,0,0,0,0,0,0,0,AD32,0,0,0,0,0,0,0,0,0,0)';
      PINUSE='POWER';
      NO_LOAD_CHECK='Both';
      NO_IO_CHECK='Both';
      NO_ASSERT_CHECK='TRUE';
      NO_DIR_CHECK='TRUE';
      ALLOW_CONNECT='TRUE';
    'VSS_AD33':
      PIN_NUMBER='(0,0,0,0,0,0,0,0,0,0,0,0,0,0,0,0,0,0,0,0,0,0,0,0,0,0,0,0,0,AD33,0,0,0,0,0,0,0,0,0,0)';
      PINUSE='POWER';
      NO_LOAD_CHECK='Both';
      NO_IO_CHECK='Both';
      NO_ASSERT_CHECK='TRUE';
      NO_DIR_CHECK='TRUE';
      ALLOW_CONNECT='TRUE';
    'VSS_AD34':
      PIN_NUMBER='(0,0,0,0,0,0,0,0,0,0,0,0,0,0,0,0,0,0,0,0,0,0,0,0,0,0,0,0,0,AD34,0,0,0,0,0,0,0,0,0,0)';
      PINUSE='POWER';
      NO_LOAD_CHECK='Both';
      NO_IO_CHECK='Both';
      NO_ASSERT_CHECK='TRUE';
      NO_DIR_CHECK='TRUE';
      ALLOW_CONNECT='TRUE';
    'VSS_AD37':
      PIN_NUMBER='(0,0,0,0,0,0,0,0,0,0,0,0,0,0,0,0,0,0,0,0,0,0,0,0,0,0,0,0,0,AD37,0,0,0,0,0,0,0,0,0,0)';
      PINUSE='POWER';
      NO_LOAD_CHECK='Both';
      NO_IO_CHECK='Both';
      NO_ASSERT_CHECK='TRUE';
      NO_DIR_CHECK='TRUE';
      ALLOW_CONNECT='TRUE';
    'VSS_AD39':
      PIN_NUMBER='(0,0,0,0,0,0,0,0,0,0,0,0,0,0,0,0,0,0,0,0,0,0,0,0,0,0,0,0,0,AD39,0,0,0,0,0,0,0,0,0,0)';
      PINUSE='POWER';
      NO_LOAD_CHECK='Both';
      NO_IO_CHECK='Both';
      NO_ASSERT_CHECK='TRUE';
      NO_DIR_CHECK='TRUE';
      ALLOW_CONNECT='TRUE';
    'VSS_AD42':
      PIN_NUMBER='(0,0,0,0,0,0,0,0,0,0,0,0,0,0,0,0,0,0,0,0,0,0,0,0,0,0,0,0,0,AD42,0,0,0,0,0,0,0,0,0,0)';
      PINUSE='POWER';
      NO_LOAD_CHECK='Both';
      NO_IO_CHECK='Both';
      NO_ASSERT_CHECK='TRUE';
      NO_DIR_CHECK='TRUE';
      ALLOW_CONNECT='TRUE';
    'VSS_AD43':
      PIN_NUMBER='(0,0,0,0,0,0,0,0,0,0,0,0,0,0,0,0,0,0,0,0,0,0,0,0,0,0,0,0,0,AD43,0,0,0,0,0,0,0,0,0,0)';
      PINUSE='POWER';
      NO_LOAD_CHECK='Both';
      NO_IO_CHECK='Both';
      NO_ASSERT_CHECK='TRUE';
      NO_DIR_CHECK='TRUE';
      ALLOW_CONNECT='TRUE';
    'VSS_AD44':
      PIN_NUMBER='(0,0,0,0,0,0,0,0,0,0,0,0,0,0,0,0,0,0,0,0,0,0,0,0,0,0,0,0,0,AD44,0,0,0,0,0,0,0,0,0,0)';
      PINUSE='POWER';
      NO_LOAD_CHECK='Both';
      NO_IO_CHECK='Both';
      NO_ASSERT_CHECK='TRUE';
      NO_DIR_CHECK='TRUE';
      ALLOW_CONNECT='TRUE';
    'VSS_AD45':
      PIN_NUMBER='(0,0,0,0,0,0,0,0,0,0,0,0,0,0,0,0,0,0,0,0,0,0,0,0,0,0,0,0,0,AD45,0,0,0,0,0,0,0,0,0,0)';
      PINUSE='POWER';
      NO_LOAD_CHECK='Both';
      NO_IO_CHECK='Both';
      NO_ASSERT_CHECK='TRUE';
      NO_DIR_CHECK='TRUE';
      ALLOW_CONNECT='TRUE';
    'VSS_AD46':
      PIN_NUMBER='(0,0,0,0,0,0,0,0,0,0,0,0,0,0,0,0,0,0,0,0,0,0,0,0,0,0,0,0,0,AD46,0,0,0,0,0,0,0,0,0,0)';
      PINUSE='POWER';
      NO_LOAD_CHECK='Both';
      NO_IO_CHECK='Both';
      NO_ASSERT_CHECK='TRUE';
      NO_DIR_CHECK='TRUE';
      ALLOW_CONNECT='TRUE';
    'VSS_AD47':
      PIN_NUMBER='(0,0,0,0,0,0,0,0,0,0,0,0,0,0,0,0,0,0,0,0,0,0,0,0,0,0,0,0,0,AD47,0,0,0,0,0,0,0,0,0,0)';
      PINUSE='POWER';
      NO_LOAD_CHECK='Both';
      NO_IO_CHECK='Both';
      NO_ASSERT_CHECK='TRUE';
      NO_DIR_CHECK='TRUE';
      ALLOW_CONNECT='TRUE';
    'VSS_AD48':
      PIN_NUMBER='(0,0,0,0,0,0,0,0,0,0,0,0,0,0,0,0,0,0,0,0,0,0,0,0,0,0,0,0,0,AD48,0,0,0,0,0,0,0,0,0,0)';
      PINUSE='POWER';
      NO_LOAD_CHECK='Both';
      NO_IO_CHECK='Both';
      NO_ASSERT_CHECK='TRUE';
      NO_DIR_CHECK='TRUE';
      ALLOW_CONNECT='TRUE';
    'VSS_T66':
      PIN_NUMBER='(0,0,0,0,0,0,0,0,0,0,0,0,0,0,0,0,0,0,0,0,0,0,0,0,0,0,0,0,0,T66,0,0,0,0,0,0,0,0,0,0)';
      PINUSE='POWER';
      NO_LOAD_CHECK='Both';
      NO_IO_CHECK='Both';
      NO_ASSERT_CHECK='TRUE';
      NO_DIR_CHECK='TRUE';
      ALLOW_CONNECT='TRUE';
    'VSS_T68':
      PIN_NUMBER='(0,0,0,0,0,0,0,0,0,0,0,0,0,0,0,0,0,0,0,0,0,0,0,0,0,0,0,0,0,T68,0,0,0,0,0,0,0,0,0,0)';
      PINUSE='POWER';
      NO_LOAD_CHECK='Both';
      NO_IO_CHECK='Both';
      NO_ASSERT_CHECK='TRUE';
      NO_DIR_CHECK='TRUE';
      ALLOW_CONNECT='TRUE';
    'VSS_T71':
      PIN_NUMBER='(0,0,0,0,0,0,0,0,0,0,0,0,0,0,0,0,0,0,0,0,0,0,0,0,0,0,0,0,0,T71,0,0,0,0,0,0,0,0,0,0)';
      PINUSE='POWER';
      NO_LOAD_CHECK='Both';
      NO_IO_CHECK='Both';
      NO_ASSERT_CHECK='TRUE';
      NO_DIR_CHECK='TRUE';
      ALLOW_CONNECT='TRUE';
    'VSS_T73':
      PIN_NUMBER='(0,0,0,0,0,0,0,0,0,0,0,0,0,0,0,0,0,0,0,0,0,0,0,0,0,0,0,0,0,T73,0,0,0,0,0,0,0,0,0,0)';
      PINUSE='POWER';
      NO_LOAD_CHECK='Both';
      NO_IO_CHECK='Both';
      NO_ASSERT_CHECK='TRUE';
      NO_DIR_CHECK='TRUE';
      ALLOW_CONNECT='TRUE';
    'VSS_U1':
      PIN_NUMBER='(0,0,0,0,0,0,0,0,0,0,0,0,0,0,0,0,0,0,0,0,0,0,0,0,0,0,0,0,0,U1,0,0,0,0,0,0,0,0,0,0)';
      PINUSE='POWER';
      NO_LOAD_CHECK='Both';
      NO_IO_CHECK='Both';
      NO_ASSERT_CHECK='TRUE';
      NO_DIR_CHECK='TRUE';
      ALLOW_CONNECT='TRUE';
    'VSS_U6':
      PIN_NUMBER='(0,0,0,0,0,0,0,0,0,0,0,0,0,0,0,0,0,0,0,0,0,0,0,0,0,0,0,0,0,U6,0,0,0,0,0,0,0,0,0,0)';
      PINUSE='POWER';
      NO_LOAD_CHECK='Both';
      NO_IO_CHECK='Both';
      NO_ASSERT_CHECK='TRUE';
      NO_DIR_CHECK='TRUE';
      ALLOW_CONNECT='TRUE';
    'VSS_U8':
      PIN_NUMBER='(0,0,0,0,0,0,0,0,0,0,0,0,0,0,0,0,0,0,0,0,0,0,0,0,0,0,0,0,0,U8,0,0,0,0,0,0,0,0,0,0)';
      PINUSE='POWER';
      NO_LOAD_CHECK='Both';
      NO_IO_CHECK='Both';
      NO_ASSERT_CHECK='TRUE';
      NO_DIR_CHECK='TRUE';
      ALLOW_CONNECT='TRUE';
    'VSS_U13':
      PIN_NUMBER='(0,0,0,0,0,0,0,0,0,0,0,0,0,0,0,0,0,0,0,0,0,0,0,0,0,0,0,0,0,U13,0,0,0,0,0,0,0,0,0,0)';
      PINUSE='POWER';
      NO_LOAD_CHECK='Both';
      NO_IO_CHECK='Both';
      NO_ASSERT_CHECK='TRUE';
      NO_DIR_CHECK='TRUE';
      ALLOW_CONNECT='TRUE';
    'VSS_U15':
      PIN_NUMBER='(0,0,0,0,0,0,0,0,0,0,0,0,0,0,0,0,0,0,0,0,0,0,0,0,0,0,0,0,0,U15,0,0,0,0,0,0,0,0,0,0)';
      PINUSE='POWER';
      NO_LOAD_CHECK='Both';
      NO_IO_CHECK='Both';
      NO_ASSERT_CHECK='TRUE';
      NO_DIR_CHECK='TRUE';
      ALLOW_CONNECT='TRUE';
    'VSS_U20':
      PIN_NUMBER='(0,0,0,0,0,0,0,0,0,0,0,0,0,0,0,0,0,0,0,0,0,0,0,0,0,0,0,0,0,U20,0,0,0,0,0,0,0,0,0,0)';
      PINUSE='POWER';
      NO_LOAD_CHECK='Both';
      NO_IO_CHECK='Both';
      NO_ASSERT_CHECK='TRUE';
      NO_DIR_CHECK='TRUE';
      ALLOW_CONNECT='TRUE';
    'VSS_U22':
      PIN_NUMBER='(0,0,0,0,0,0,0,0,0,0,0,0,0,0,0,0,0,0,0,0,0,0,0,0,0,0,0,0,0,U22,0,0,0,0,0,0,0,0,0,0)';
      PINUSE='POWER';
      NO_LOAD_CHECK='Both';
      NO_IO_CHECK='Both';
      NO_ASSERT_CHECK='TRUE';
      NO_DIR_CHECK='TRUE';
      ALLOW_CONNECT='TRUE';
    'VSS_U25':
      PIN_NUMBER='(0,0,0,0,0,0,0,0,0,0,0,0,0,0,0,0,0,0,0,0,0,0,0,0,0,0,0,0,0,U25,0,0,0,0,0,0,0,0,0,0)';
      PINUSE='POWER';
      NO_LOAD_CHECK='Both';
      NO_IO_CHECK='Both';
      NO_ASSERT_CHECK='TRUE';
      NO_DIR_CHECK='TRUE';
      ALLOW_CONNECT='TRUE';
    'VSS_U28':
      PIN_NUMBER='(0,0,0,0,0,0,0,0,0,0,0,0,0,0,0,0,0,0,0,0,0,0,0,0,0,0,0,0,0,U28,0,0,0,0,0,0,0,0,0,0)';
      PINUSE='POWER';
      NO_LOAD_CHECK='Both';
      NO_IO_CHECK='Both';
      NO_ASSERT_CHECK='TRUE';
      NO_DIR_CHECK='TRUE';
      ALLOW_CONNECT='TRUE';
    'VSS_U31':
      PIN_NUMBER='(0,0,0,0,0,0,0,0,0,0,0,0,0,0,0,0,0,0,0,0,0,0,0,0,0,0,0,0,0,U31,0,0,0,0,0,0,0,0,0,0)';
      PINUSE='POWER';
      NO_LOAD_CHECK='Both';
      NO_IO_CHECK='Both';
      NO_ASSERT_CHECK='TRUE';
      NO_DIR_CHECK='TRUE';
      ALLOW_CONNECT='TRUE';
    'VSS_U34':
      PIN_NUMBER='(0,0,0,0,0,0,0,0,0,0,0,0,0,0,0,0,0,0,0,0,0,0,0,0,0,0,0,0,0,U34,0,0,0,0,0,0,0,0,0,0)';
      PINUSE='POWER';
      NO_LOAD_CHECK='Both';
      NO_IO_CHECK='Both';
      NO_ASSERT_CHECK='TRUE';
      NO_DIR_CHECK='TRUE';
      ALLOW_CONNECT='TRUE';
    'VSS_U42':
      PIN_NUMBER='(0,0,0,0,0,0,0,0,0,0,0,0,0,0,0,0,0,0,0,0,0,0,0,0,0,0,0,0,0,U42,0,0,0,0,0,0,0,0,0,0)';
      PINUSE='POWER';
      NO_LOAD_CHECK='Both';
      NO_IO_CHECK='Both';
      NO_ASSERT_CHECK='TRUE';
      NO_DIR_CHECK='TRUE';
      ALLOW_CONNECT='TRUE';
    'VSS_U45':
      PIN_NUMBER='(0,0,0,0,0,0,0,0,0,0,0,0,0,0,0,0,0,0,0,0,0,0,0,0,0,0,0,0,0,U45,0,0,0,0,0,0,0,0,0,0)';
      PINUSE='POWER';
      NO_LOAD_CHECK='Both';
      NO_IO_CHECK='Both';
      NO_ASSERT_CHECK='TRUE';
      NO_DIR_CHECK='TRUE';
      ALLOW_CONNECT='TRUE';
    'VSS_U48':
      PIN_NUMBER='(0,0,0,0,0,0,0,0,0,0,0,0,0,0,0,0,0,0,0,0,0,0,0,0,0,0,0,0,0,U48,0,0,0,0,0,0,0,0,0,0)';
      PINUSE='POWER';
      NO_LOAD_CHECK='Both';
      NO_IO_CHECK='Both';
      NO_ASSERT_CHECK='TRUE';
      NO_DIR_CHECK='TRUE';
      ALLOW_CONNECT='TRUE';
    'VSS_U51':
      PIN_NUMBER='(0,0,0,0,0,0,0,0,0,0,0,0,0,0,0,0,0,0,0,0,0,0,0,0,0,0,0,0,0,U51,0,0,0,0,0,0,0,0,0,0)';
      PINUSE='POWER';
      NO_LOAD_CHECK='Both';
      NO_IO_CHECK='Both';
      NO_ASSERT_CHECK='TRUE';
      NO_DIR_CHECK='TRUE';
      ALLOW_CONNECT='TRUE';
    'VSS_U54':
      PIN_NUMBER='(0,0,0,0,0,0,0,0,0,0,0,0,0,0,0,0,0,0,0,0,0,0,0,0,0,0,0,0,0,U54,0,0,0,0,0,0,0,0,0,0)';
      PINUSE='POWER';
      NO_LOAD_CHECK='Both';
      NO_IO_CHECK='Both';
      NO_ASSERT_CHECK='TRUE';
      NO_DIR_CHECK='TRUE';
      ALLOW_CONNECT='TRUE';
    'VSS_U56':
      PIN_NUMBER='(0,0,0,0,0,0,0,0,0,0,0,0,0,0,0,0,0,0,0,0,0,0,0,0,0,0,0,0,0,U56,0,0,0,0,0,0,0,0,0,0)';
      PINUSE='POWER';
      NO_LOAD_CHECK='Both';
      NO_IO_CHECK='Both';
      NO_ASSERT_CHECK='TRUE';
      NO_DIR_CHECK='TRUE';
      ALLOW_CONNECT='TRUE';
    'VSS_U61':
      PIN_NUMBER='(0,0,0,0,0,0,0,0,0,0,0,0,0,0,0,0,0,0,0,0,0,0,0,0,0,0,0,0,0,U61,0,0,0,0,0,0,0,0,0,0)';
      PINUSE='POWER';
      NO_LOAD_CHECK='Both';
      NO_IO_CHECK='Both';
      NO_ASSERT_CHECK='TRUE';
      NO_DIR_CHECK='TRUE';
      ALLOW_CONNECT='TRUE';
    'VSS_U63':
      PIN_NUMBER='(0,0,0,0,0,0,0,0,0,0,0,0,0,0,0,0,0,0,0,0,0,0,0,0,0,0,0,0,0,U63,0,0,0,0,0,0,0,0,0,0)';
      PINUSE='POWER';
      NO_LOAD_CHECK='Both';
      NO_IO_CHECK='Both';
      NO_ASSERT_CHECK='TRUE';
      NO_DIR_CHECK='TRUE';
      ALLOW_CONNECT='TRUE';
    'VSS_U68':
      PIN_NUMBER='(0,0,0,0,0,0,0,0,0,0,0,0,0,0,0,0,0,0,0,0,0,0,0,0,0,0,0,0,0,U68,0,0,0,0,0,0,0,0,0,0)';
      PINUSE='POWER';
      NO_LOAD_CHECK='Both';
      NO_IO_CHECK='Both';
      NO_ASSERT_CHECK='TRUE';
      NO_DIR_CHECK='TRUE';
      ALLOW_CONNECT='TRUE';
    'VSS_U70':
      PIN_NUMBER='(0,0,0,0,0,0,0,0,0,0,0,0,0,0,0,0,0,0,0,0,0,0,0,0,0,0,0,0,0,U70,0,0,0,0,0,0,0,0,0,0)';
      PINUSE='POWER';
      NO_LOAD_CHECK='Both';
      NO_IO_CHECK='Both';
      NO_ASSERT_CHECK='TRUE';
      NO_DIR_CHECK='TRUE';
      ALLOW_CONNECT='TRUE';
    'VSS_U75':
      PIN_NUMBER='(0,0,0,0,0,0,0,0,0,0,0,0,0,0,0,0,0,0,0,0,0,0,0,0,0,0,0,0,0,U75,0,0,0,0,0,0,0,0,0,0)';
      PINUSE='POWER';
      NO_LOAD_CHECK='Both';
      NO_IO_CHECK='Both';
      NO_ASSERT_CHECK='TRUE';
      NO_DIR_CHECK='TRUE';
      ALLOW_CONNECT='TRUE';
    'VSS_V3':
      PIN_NUMBER='(0,0,0,0,0,0,0,0,0,0,0,0,0,0,0,0,0,0,0,0,0,0,0,0,0,0,0,0,0,V3,0,0,0,0,0,0,0,0,0,0)';
      PINUSE='POWER';
      NO_LOAD_CHECK='Both';
      NO_IO_CHECK='Both';
      NO_ASSERT_CHECK='TRUE';
      NO_DIR_CHECK='TRUE';
      ALLOW_CONNECT='TRUE';
    'VSS_V5':
      PIN_NUMBER='(0,0,0,0,0,0,0,0,0,0,0,0,0,0,0,0,0,0,0,0,0,0,0,0,0,0,0,0,0,V5,0,0,0,0,0,0,0,0,0,0)';
      PINUSE='POWER';
      NO_LOAD_CHECK='Both';
      NO_IO_CHECK='Both';
      NO_ASSERT_CHECK='TRUE';
      NO_DIR_CHECK='TRUE';
      ALLOW_CONNECT='TRUE';
    'VSS_V8':
      PIN_NUMBER='(0,0,0,0,0,0,0,0,0,0,0,0,0,0,0,0,0,0,0,0,0,0,0,0,0,0,0,0,0,V8,0,0,0,0,0,0,0,0,0,0)';
      PINUSE='POWER';
      NO_LOAD_CHECK='Both';
      NO_IO_CHECK='Both';
      NO_ASSERT_CHECK='TRUE';
      NO_DIR_CHECK='TRUE';
      ALLOW_CONNECT='TRUE';
    'VSS_V10':
      PIN_NUMBER='(0,0,0,0,0,0,0,0,0,0,0,0,0,0,0,0,0,0,0,0,0,0,0,0,0,0,0,0,0,V10,0,0,0,0,0,0,0,0,0,0)';
      PINUSE='POWER';
      NO_LOAD_CHECK='Both';
      NO_IO_CHECK='Both';
      NO_ASSERT_CHECK='TRUE';
      NO_DIR_CHECK='TRUE';
      ALLOW_CONNECT='TRUE';
    'VSS_V12':
      PIN_NUMBER='(0,0,0,0,0,0,0,0,0,0,0,0,0,0,0,0,0,0,0,0,0,0,0,0,0,0,0,0,0,V12,0,0,0,0,0,0,0,0,0,0)';
      PINUSE='POWER';
      NO_LOAD_CHECK='Both';
      NO_IO_CHECK='Both';
      NO_ASSERT_CHECK='TRUE';
      NO_DIR_CHECK='TRUE';
      ALLOW_CONNECT='TRUE';
    'VSS_V15':
      PIN_NUMBER='(0,0,0,0,0,0,0,0,0,0,0,0,0,0,0,0,0,0,0,0,0,0,0,0,0,0,0,0,0,V15,0,0,0,0,0,0,0,0,0,0)';
      PINUSE='POWER';
      NO_LOAD_CHECK='Both';
      NO_IO_CHECK='Both';
      NO_ASSERT_CHECK='TRUE';
      NO_DIR_CHECK='TRUE';
      ALLOW_CONNECT='TRUE';
    'VSS_V17':
      PIN_NUMBER='(0,0,0,0,0,0,0,0,0,0,0,0,0,0,0,0,0,0,0,0,0,0,0,0,0,0,0,0,0,V17,0,0,0,0,0,0,0,0,0,0)';
      PINUSE='POWER';
      NO_LOAD_CHECK='Both';
      NO_IO_CHECK='Both';
      NO_ASSERT_CHECK='TRUE';
      NO_DIR_CHECK='TRUE';
      ALLOW_CONNECT='TRUE';
    'VSS_V19':
      PIN_NUMBER='(0,0,0,0,0,0,0,0,0,0,0,0,0,0,0,0,0,0,0,0,0,0,0,0,0,0,0,0,0,V19,0,0,0,0,0,0,0,0,0,0)';
      PINUSE='POWER';
      NO_LOAD_CHECK='Both';
      NO_IO_CHECK='Both';
      NO_ASSERT_CHECK='TRUE';
      NO_DIR_CHECK='TRUE';
      ALLOW_CONNECT='TRUE';
    'VSS_V23':
      PIN_NUMBER='(0,0,0,0,0,0,0,0,0,0,0,0,0,0,0,0,0,0,0,0,0,0,0,0,0,0,0,0,0,V23,0,0,0,0,0,0,0,0,0,0)';
      PINUSE='POWER';
      NO_LOAD_CHECK='Both';
      NO_IO_CHECK='Both';
      NO_ASSERT_CHECK='TRUE';
      NO_DIR_CHECK='TRUE';
      ALLOW_CONNECT='TRUE';
    'VSS_V24':
      PIN_NUMBER='(0,0,0,0,0,0,0,0,0,0,0,0,0,0,0,0,0,0,0,0,0,0,0,0,0,0,0,0,0,V24,0,0,0,0,0,0,0,0,0,0)';
      PINUSE='POWER';
      NO_LOAD_CHECK='Both';
      NO_IO_CHECK='Both';
      NO_ASSERT_CHECK='TRUE';
      NO_DIR_CHECK='TRUE';
      ALLOW_CONNECT='TRUE';
    'VSS_V25':
      PIN_NUMBER='(0,0,0,0,0,0,0,0,0,0,0,0,0,0,0,0,0,0,0,0,0,0,0,0,0,0,0,0,0,V25,0,0,0,0,0,0,0,0,0,0)';
      PINUSE='POWER';
      NO_LOAD_CHECK='Both';
      NO_IO_CHECK='Both';
      NO_ASSERT_CHECK='TRUE';
      NO_DIR_CHECK='TRUE';
      ALLOW_CONNECT='TRUE';
    'VSS_V26':
      PIN_NUMBER='(0,0,0,0,0,0,0,0,0,0,0,0,0,0,0,0,0,0,0,0,0,0,0,0,0,0,0,0,0,V26,0,0,0,0,0,0,0,0,0,0)';
      PINUSE='POWER';
      NO_LOAD_CHECK='Both';
      NO_IO_CHECK='Both';
      NO_ASSERT_CHECK='TRUE';
      NO_DIR_CHECK='TRUE';
      ALLOW_CONNECT='TRUE';
    'VSS_V28':
      PIN_NUMBER='(0,0,0,0,0,0,0,0,0,0,0,0,0,0,0,0,0,0,0,0,0,0,0,0,0,0,0,0,0,V28,0,0,0,0,0,0,0,0,0,0)';
      PINUSE='POWER';
      NO_LOAD_CHECK='Both';
      NO_IO_CHECK='Both';
      NO_ASSERT_CHECK='TRUE';
      NO_DIR_CHECK='TRUE';
      ALLOW_CONNECT='TRUE';
    'VSS_V29':
      PIN_NUMBER='(0,0,0,0,0,0,0,0,0,0,0,0,0,0,0,0,0,0,0,0,0,0,0,0,0,0,0,0,0,V29,0,0,0,0,0,0,0,0,0,0)';
      PINUSE='POWER';
      NO_LOAD_CHECK='Both';
      NO_IO_CHECK='Both';
      NO_ASSERT_CHECK='TRUE';
      NO_DIR_CHECK='TRUE';
      ALLOW_CONNECT='TRUE';
    'VSS_V30':
      PIN_NUMBER='(0,0,0,0,0,0,0,0,0,0,0,0,0,0,0,0,0,0,0,0,0,0,0,0,0,0,0,0,0,V30,0,0,0,0,0,0,0,0,0,0)';
      PINUSE='POWER';
      NO_LOAD_CHECK='Both';
      NO_IO_CHECK='Both';
      NO_ASSERT_CHECK='TRUE';
      NO_DIR_CHECK='TRUE';
      ALLOW_CONNECT='TRUE';
    'VSS_V31':
      PIN_NUMBER='(0,0,0,0,0,0,0,0,0,0,0,0,0,0,0,0,0,0,0,0,0,0,0,0,0,0,0,0,0,V31,0,0,0,0,0,0,0,0,0,0)';
      PINUSE='POWER';
      NO_LOAD_CHECK='Both';
      NO_IO_CHECK='Both';
      NO_ASSERT_CHECK='TRUE';
      NO_DIR_CHECK='TRUE';
      ALLOW_CONNECT='TRUE';
    'VSS_V32':
      PIN_NUMBER='(0,0,0,0,0,0,0,0,0,0,0,0,0,0,0,0,0,0,0,0,0,0,0,0,0,0,0,0,0,V32,0,0,0,0,0,0,0,0,0,0)';
      PINUSE='POWER';
      NO_LOAD_CHECK='Both';
      NO_IO_CHECK='Both';
      NO_ASSERT_CHECK='TRUE';
      NO_DIR_CHECK='TRUE';
      ALLOW_CONNECT='TRUE';
    'VSS_V33':
      PIN_NUMBER='(0,0,0,0,0,0,0,0,0,0,0,0,0,0,0,0,0,0,0,0,0,0,0,0,0,0,0,0,0,V33,0,0,0,0,0,0,0,0,0,0)';
      PINUSE='POWER';
      NO_LOAD_CHECK='Both';
      NO_IO_CHECK='Both';
      NO_ASSERT_CHECK='TRUE';
      NO_DIR_CHECK='TRUE';
      ALLOW_CONNECT='TRUE';
    'VSS_V34':
      PIN_NUMBER='(0,0,0,0,0,0,0,0,0,0,0,0,0,0,0,0,0,0,0,0,0,0,0,0,0,0,0,0,0,V34,0,0,0,0,0,0,0,0,0,0)';
      PINUSE='POWER';
      NO_LOAD_CHECK='Both';
      NO_IO_CHECK='Both';
      NO_ASSERT_CHECK='TRUE';
      NO_DIR_CHECK='TRUE';
      ALLOW_CONNECT='TRUE';
    'VSS_V37':
      PIN_NUMBER='(0,0,0,0,0,0,0,0,0,0,0,0,0,0,0,0,0,0,0,0,0,0,0,0,0,0,0,0,0,V37,0,0,0,0,0,0,0,0,0,0)';
      PINUSE='POWER';
      NO_LOAD_CHECK='Both';
      NO_IO_CHECK='Both';
      NO_ASSERT_CHECK='TRUE';
      NO_DIR_CHECK='TRUE';
      ALLOW_CONNECT='TRUE';
    'VSS_V39':
      PIN_NUMBER='(0,0,0,0,0,0,0,0,0,0,0,0,0,0,0,0,0,0,0,0,0,0,0,0,0,0,0,0,0,V39,0,0,0,0,0,0,0,0,0,0)';
      PINUSE='POWER';
      NO_LOAD_CHECK='Both';
      NO_IO_CHECK='Both';
      NO_ASSERT_CHECK='TRUE';
      NO_DIR_CHECK='TRUE';
      ALLOW_CONNECT='TRUE';
    'VSS_V42':
      PIN_NUMBER='(0,0,0,0,0,0,0,0,0,0,0,0,0,0,0,0,0,0,0,0,0,0,0,0,0,0,0,0,0,V42,0,0,0,0,0,0,0,0,0,0)';
      PINUSE='POWER';
      NO_LOAD_CHECK='Both';
      NO_IO_CHECK='Both';
      NO_ASSERT_CHECK='TRUE';
      NO_DIR_CHECK='TRUE';
      ALLOW_CONNECT='TRUE';
    'VSS_V43':
      PIN_NUMBER='(0,0,0,0,0,0,0,0,0,0,0,0,0,0,0,0,0,0,0,0,0,0,0,0,0,0,0,0,0,V43,0,0,0,0,0,0,0,0,0,0)';
      PINUSE='POWER';
      NO_LOAD_CHECK='Both';
      NO_IO_CHECK='Both';
      NO_ASSERT_CHECK='TRUE';
      NO_DIR_CHECK='TRUE';
      ALLOW_CONNECT='TRUE';
    'VSS_V44':
      PIN_NUMBER='(0,0,0,0,0,0,0,0,0,0,0,0,0,0,0,0,0,0,0,0,0,0,0,0,0,0,0,0,0,V44,0,0,0,0,0,0,0,0,0,0)';
      PINUSE='POWER';
      NO_LOAD_CHECK='Both';
      NO_IO_CHECK='Both';
      NO_ASSERT_CHECK='TRUE';
      NO_DIR_CHECK='TRUE';
      ALLOW_CONNECT='TRUE';
    'VSS_V45':
      PIN_NUMBER='(0,0,0,0,0,0,0,0,0,0,0,0,0,0,0,0,0,0,0,0,0,0,0,0,0,0,0,0,0,V45,0,0,0,0,0,0,0,0,0,0)';
      PINUSE='POWER';
      NO_LOAD_CHECK='Both';
      NO_IO_CHECK='Both';
      NO_ASSERT_CHECK='TRUE';
      NO_DIR_CHECK='TRUE';
      ALLOW_CONNECT='TRUE';
    'VSS_V46':
      PIN_NUMBER='(0,0,0,0,0,0,0,0,0,0,0,0,0,0,0,0,0,0,0,0,0,0,0,0,0,0,0,0,0,V46,0,0,0,0,0,0,0,0,0,0)';
      PINUSE='POWER';
      NO_LOAD_CHECK='Both';
      NO_IO_CHECK='Both';
      NO_ASSERT_CHECK='TRUE';
      NO_DIR_CHECK='TRUE';
      ALLOW_CONNECT='TRUE';
    'VSS_V47':
      PIN_NUMBER='(0,0,0,0,0,0,0,0,0,0,0,0,0,0,0,0,0,0,0,0,0,0,0,0,0,0,0,0,0,V47,0,0,0,0,0,0,0,0,0,0)';
      PINUSE='POWER';
      NO_LOAD_CHECK='Both';
      NO_IO_CHECK='Both';
      NO_ASSERT_CHECK='TRUE';
      NO_DIR_CHECK='TRUE';
      ALLOW_CONNECT='TRUE';
    'VSS_V48':
      PIN_NUMBER='(0,0,0,0,0,0,0,0,0,0,0,0,0,0,0,0,0,0,0,0,0,0,0,0,0,0,0,0,0,V48,0,0,0,0,0,0,0,0,0,0)';
      PINUSE='POWER';
      NO_LOAD_CHECK='Both';
      NO_IO_CHECK='Both';
      NO_ASSERT_CHECK='TRUE';
      NO_DIR_CHECK='TRUE';
      ALLOW_CONNECT='TRUE';
    'VSS_V49':
      PIN_NUMBER='(0,0,0,0,0,0,0,0,0,0,0,0,0,0,0,0,0,0,0,0,0,0,0,0,0,0,0,0,0,V49,0,0,0,0,0,0,0,0,0,0)';
      PINUSE='POWER';
      NO_LOAD_CHECK='Both';
      NO_IO_CHECK='Both';
      NO_ASSERT_CHECK='TRUE';
      NO_DIR_CHECK='TRUE';
      ALLOW_CONNECT='TRUE';
    'VSS_V50':
      PIN_NUMBER='(0,0,0,0,0,0,0,0,0,0,0,0,0,0,0,0,0,0,0,0,0,0,0,0,0,0,0,0,0,V50,0,0,0,0,0,0,0,0,0,0)';
      PINUSE='POWER';
      NO_LOAD_CHECK='Both';
      NO_IO_CHECK='Both';
      NO_ASSERT_CHECK='TRUE';
      NO_DIR_CHECK='TRUE';
      ALLOW_CONNECT='TRUE';
    'VSS_V51':
      PIN_NUMBER='(0,0,0,0,0,0,0,0,0,0,0,0,0,0,0,0,0,0,0,0,0,0,0,0,0,0,0,0,0,V51,0,0,0,0,0,0,0,0,0,0)';
      PINUSE='POWER';
      NO_LOAD_CHECK='Both';
      NO_IO_CHECK='Both';
      NO_ASSERT_CHECK='TRUE';
      NO_DIR_CHECK='TRUE';
      ALLOW_CONNECT='TRUE';
    'VSS_V52':
      PIN_NUMBER='(0,0,0,0,0,0,0,0,0,0,0,0,0,0,0,0,0,0,0,0,0,0,0,0,0,0,0,0,0,V52,0,0,0,0,0,0,0,0,0,0)';
      PINUSE='POWER';
      NO_LOAD_CHECK='Both';
      NO_IO_CHECK='Both';
      NO_ASSERT_CHECK='TRUE';
      NO_DIR_CHECK='TRUE';
      ALLOW_CONNECT='TRUE';
    'VSS_V53':
      PIN_NUMBER='(0,0,0,0,0,0,0,0,0,0,0,0,0,0,0,0,0,0,0,0,0,0,0,0,0,0,0,0,0,V53,0,0,0,0,0,0,0,0,0,0)';
      PINUSE='POWER';
      NO_LOAD_CHECK='Both';
      NO_IO_CHECK='Both';
      NO_ASSERT_CHECK='TRUE';
      NO_DIR_CHECK='TRUE';
      ALLOW_CONNECT='TRUE';
    'VSS_V57':
      PIN_NUMBER='(0,0,0,0,0,0,0,0,0,0,0,0,0,0,0,0,0,0,0,0,0,0,0,0,0,0,0,0,0,V57,0,0,0,0,0,0,0,0,0,0)';
      PINUSE='POWER';
      NO_LOAD_CHECK='Both';
      NO_IO_CHECK='Both';
      NO_ASSERT_CHECK='TRUE';
      NO_DIR_CHECK='TRUE';
      ALLOW_CONNECT='TRUE';
    'VSS_V59':
      PIN_NUMBER='(0,0,0,0,0,0,0,0,0,0,0,0,0,0,0,0,0,0,0,0,0,0,0,0,0,0,0,0,0,V59,0,0,0,0,0,0,0,0,0,0)';
      PINUSE='POWER';
      NO_LOAD_CHECK='Both';
      NO_IO_CHECK='Both';
      NO_ASSERT_CHECK='TRUE';
      NO_DIR_CHECK='TRUE';
      ALLOW_CONNECT='TRUE';
    'VSS_V61':
      PIN_NUMBER='(0,0,0,0,0,0,0,0,0,0,0,0,0,0,0,0,0,0,0,0,0,0,0,0,0,0,0,0,0,V61,0,0,0,0,0,0,0,0,0,0)';
      PINUSE='POWER';
      NO_LOAD_CHECK='Both';
      NO_IO_CHECK='Both';
      NO_ASSERT_CHECK='TRUE';
      NO_DIR_CHECK='TRUE';
      ALLOW_CONNECT='TRUE';
    'VSS_V64':
      PIN_NUMBER='(0,0,0,0,0,0,0,0,0,0,0,0,0,0,0,0,0,0,0,0,0,0,0,0,0,0,0,0,0,V64,0,0,0,0,0,0,0,0,0,0)';
      PINUSE='POWER';
      NO_LOAD_CHECK='Both';
      NO_IO_CHECK='Both';
      NO_ASSERT_CHECK='TRUE';
      NO_DIR_CHECK='TRUE';
      ALLOW_CONNECT='TRUE';
    'VSS_V66':
      PIN_NUMBER='(0,0,0,0,0,0,0,0,0,0,0,0,0,0,0,0,0,0,0,0,0,0,0,0,0,0,0,0,0,V66,0,0,0,0,0,0,0,0,0,0)';
      PINUSE='POWER';
      NO_LOAD_CHECK='Both';
      NO_IO_CHECK='Both';
      NO_ASSERT_CHECK='TRUE';
      NO_DIR_CHECK='TRUE';
      ALLOW_CONNECT='TRUE';
    'VSS_V71':
      PIN_NUMBER='(0,0,0,0,0,0,0,0,0,0,0,0,0,0,0,0,0,0,0,0,0,0,0,0,0,0,0,0,0,V71,0,0,0,0,0,0,0,0,0,0)';
      PINUSE='POWER';
      NO_LOAD_CHECK='Both';
      NO_IO_CHECK='Both';
      NO_ASSERT_CHECK='TRUE';
      NO_DIR_CHECK='TRUE';
      ALLOW_CONNECT='TRUE';
    'VSS_V73':
      PIN_NUMBER='(0,0,0,0,0,0,0,0,0,0,0,0,0,0,0,0,0,0,0,0,0,0,0,0,0,0,0,0,0,V73,0,0,0,0,0,0,0,0,0,0)';
      PINUSE='POWER';
      NO_LOAD_CHECK='Both';
      NO_IO_CHECK='Both';
      NO_ASSERT_CHECK='TRUE';
      NO_DIR_CHECK='TRUE';
      ALLOW_CONNECT='TRUE';
    'VSS_W1':
      PIN_NUMBER='(0,0,0,0,0,0,0,0,0,0,0,0,0,0,0,0,0,0,0,0,0,0,0,0,0,0,0,0,0,W1,0,0,0,0,0,0,0,0,0,0)';
      PINUSE='POWER';
      NO_LOAD_CHECK='Both';
      NO_IO_CHECK='Both';
      NO_ASSERT_CHECK='TRUE';
      NO_DIR_CHECK='TRUE';
      ALLOW_CONNECT='TRUE';
    'VSS_W4':
      PIN_NUMBER='(0,0,0,0,0,0,0,0,0,0,0,0,0,0,0,0,0,0,0,0,0,0,0,0,0,0,0,0,0,W4,0,0,0,0,0,0,0,0,0,0)';
      PINUSE='POWER';
      NO_LOAD_CHECK='Both';
      NO_IO_CHECK='Both';
      NO_ASSERT_CHECK='TRUE';
      NO_DIR_CHECK='TRUE';
      ALLOW_CONNECT='TRUE';
    'VSS_W6':
      PIN_NUMBER='(0,0,0,0,0,0,0,0,0,0,0,0,0,0,0,0,0,0,0,0,0,0,0,0,0,0,0,0,0,W6,0,0,0,0,0,0,0,0,0,0)';
      PINUSE='POWER';
      NO_LOAD_CHECK='Both';
      NO_IO_CHECK='Both';
      NO_ASSERT_CHECK='TRUE';
      NO_DIR_CHECK='TRUE';
      ALLOW_CONNECT='TRUE';
    'VSS_W8':
      PIN_NUMBER='(0,0,0,0,0,0,0,0,0,0,0,0,0,0,0,0,0,0,0,0,0,0,0,0,0,0,0,0,0,W8,0,0,0,0,0,0,0,0,0,0)';
      PINUSE='POWER';
      NO_LOAD_CHECK='Both';
      NO_IO_CHECK='Both';
      NO_ASSERT_CHECK='TRUE';
      NO_DIR_CHECK='TRUE';
      ALLOW_CONNECT='TRUE';
    'VSS_W11':
      PIN_NUMBER='(0,0,0,0,0,0,0,0,0,0,0,0,0,0,0,0,0,0,0,0,0,0,0,0,0,0,0,0,0,W11,0,0,0,0,0,0,0,0,0,0)';
      PINUSE='POWER';
      NO_LOAD_CHECK='Both';
      NO_IO_CHECK='Both';
      NO_ASSERT_CHECK='TRUE';
      NO_DIR_CHECK='TRUE';
      ALLOW_CONNECT='TRUE';
    'VSS_W13':
      PIN_NUMBER='(0,0,0,0,0,0,0,0,0,0,0,0,0,0,0,0,0,0,0,0,0,0,0,0,0,0,0,0,0,W13,0,0,0,0,0,0,0,0,0,0)';
      PINUSE='POWER';
      NO_LOAD_CHECK='Both';
      NO_IO_CHECK='Both';
      NO_ASSERT_CHECK='TRUE';
      NO_DIR_CHECK='TRUE';
      ALLOW_CONNECT='TRUE';
    'VSS_W15':
      PIN_NUMBER='(0,0,0,0,0,0,0,0,0,0,0,0,0,0,0,0,0,0,0,0,0,0,0,0,0,0,0,0,0,W15,0,0,0,0,0,0,0,0,0,0)';
      PINUSE='POWER';
      NO_LOAD_CHECK='Both';
      NO_IO_CHECK='Both';
      NO_ASSERT_CHECK='TRUE';
      NO_DIR_CHECK='TRUE';
      ALLOW_CONNECT='TRUE';
    'VSS_W18':
      PIN_NUMBER='(0,0,0,0,0,0,0,0,0,0,0,0,0,0,0,0,0,0,0,0,0,0,0,0,0,0,0,0,0,W18,0,0,0,0,0,0,0,0,0,0)';
      PINUSE='POWER';
      NO_LOAD_CHECK='Both';
      NO_IO_CHECK='Both';
      NO_ASSERT_CHECK='TRUE';
      NO_DIR_CHECK='TRUE';
      ALLOW_CONNECT='TRUE';
    'VSS_W20':
      PIN_NUMBER='(0,0,0,0,0,0,0,0,0,0,0,0,0,0,0,0,0,0,0,0,0,0,0,0,0,0,0,0,0,W20,0,0,0,0,0,0,0,0,0,0)';
      PINUSE='POWER';
      NO_LOAD_CHECK='Both';
      NO_IO_CHECK='Both';
      NO_ASSERT_CHECK='TRUE';
      NO_DIR_CHECK='TRUE';
      ALLOW_CONNECT='TRUE';
    'VSS_W22':
      PIN_NUMBER='(0,0,0,0,0,0,0,0,0,0,0,0,0,0,0,0,0,0,0,0,0,0,0,0,0,0,0,0,0,W22,0,0,0,0,0,0,0,0,0,0)';
      PINUSE='POWER';
      NO_LOAD_CHECK='Both';
      NO_IO_CHECK='Both';
      NO_ASSERT_CHECK='TRUE';
      NO_DIR_CHECK='TRUE';
      ALLOW_CONNECT='TRUE';
    'VSS_W25':
      PIN_NUMBER='(0,0,0,0,0,0,0,0,0,0,0,0,0,0,0,0,0,0,0,0,0,0,0,0,0,0,0,0,0,W25,0,0,0,0,0,0,0,0,0,0)';
      PINUSE='POWER';
      NO_LOAD_CHECK='Both';
      NO_IO_CHECK='Both';
      NO_ASSERT_CHECK='TRUE';
      NO_DIR_CHECK='TRUE';
      ALLOW_CONNECT='TRUE';
    'VSS_W28':
      PIN_NUMBER='(0,0,0,0,0,0,0,0,0,0,0,0,0,0,0,0,0,0,0,0,0,0,0,0,0,0,0,0,0,W28,0,0,0,0,0,0,0,0,0,0)';
      PINUSE='POWER';
      NO_LOAD_CHECK='Both';
      NO_IO_CHECK='Both';
      NO_ASSERT_CHECK='TRUE';
      NO_DIR_CHECK='TRUE';
      ALLOW_CONNECT='TRUE';
    'VSS_W34':
      PIN_NUMBER='(0,0,0,0,0,0,0,0,0,0,0,0,0,0,0,0,0,0,0,0,0,0,0,0,0,0,0,0,0,W34,0,0,0,0,0,0,0,0,0,0)';
      PINUSE='POWER';
      NO_LOAD_CHECK='Both';
      NO_IO_CHECK='Both';
      NO_ASSERT_CHECK='TRUE';
      NO_DIR_CHECK='TRUE';
      ALLOW_CONNECT='TRUE';
    'VSS_W35':
      PIN_NUMBER='(0,0,0,0,0,0,0,0,0,0,0,0,0,0,0,0,0,0,0,0,0,0,0,0,0,0,0,0,0,W35,0,0,0,0,0,0,0,0,0,0)';
      PINUSE='POWER';
      NO_LOAD_CHECK='Both';
      NO_IO_CHECK='Both';
      NO_ASSERT_CHECK='TRUE';
      NO_DIR_CHECK='TRUE';
      ALLOW_CONNECT='TRUE';
    'VSS_W36':
      PIN_NUMBER='(0,0,0,0,0,0,0,0,0,0,0,0,0,0,0,0,0,0,0,0,0,0,0,0,0,0,0,0,0,W36,0,0,0,0,0,0,0,0,0,0)';
      PINUSE='POWER';
      NO_LOAD_CHECK='Both';
      NO_IO_CHECK='Both';
      NO_ASSERT_CHECK='TRUE';
      NO_DIR_CHECK='TRUE';
      ALLOW_CONNECT='TRUE';
    'VSS_W40':
      PIN_NUMBER='(0,0,0,0,0,0,0,0,0,0,0,0,0,0,0,0,0,0,0,0,0,0,0,0,0,0,0,0,0,W40,0,0,0,0,0,0,0,0,0,0)';
      PINUSE='POWER';
      NO_LOAD_CHECK='Both';
      NO_IO_CHECK='Both';
      NO_ASSERT_CHECK='TRUE';
      NO_DIR_CHECK='TRUE';
      ALLOW_CONNECT='TRUE';
    'VSS_W41':
      PIN_NUMBER='(0,0,0,0,0,0,0,0,0,0,0,0,0,0,0,0,0,0,0,0,0,0,0,0,0,0,0,0,0,W41,0,0,0,0,0,0,0,0,0,0)';
      PINUSE='POWER';
      NO_LOAD_CHECK='Both';
      NO_IO_CHECK='Both';
      NO_ASSERT_CHECK='TRUE';
      NO_DIR_CHECK='TRUE';
      ALLOW_CONNECT='TRUE';
    'VSS_W42':
      PIN_NUMBER='(0,0,0,0,0,0,0,0,0,0,0,0,0,0,0,0,0,0,0,0,0,0,0,0,0,0,0,0,0,W42,0,0,0,0,0,0,0,0,0,0)';
      PINUSE='POWER';
      NO_LOAD_CHECK='Both';
      NO_IO_CHECK='Both';
      NO_ASSERT_CHECK='TRUE';
      NO_DIR_CHECK='TRUE';
      ALLOW_CONNECT='TRUE';
    'VSS_W45':
      PIN_NUMBER='(0,0,0,0,0,0,0,0,0,0,0,0,0,0,0,0,0,0,0,0,0,0,0,0,0,0,0,0,0,W45,0,0,0,0,0,0,0,0,0,0)';
      PINUSE='POWER';
      NO_LOAD_CHECK='Both';
      NO_IO_CHECK='Both';
      NO_ASSERT_CHECK='TRUE';
      NO_DIR_CHECK='TRUE';
      ALLOW_CONNECT='TRUE';
    'VSS_W48':
      PIN_NUMBER='(0,0,0,0,0,0,0,0,0,0,0,0,0,0,0,0,0,0,0,0,0,0,0,0,0,0,0,0,0,W48,0,0,0,0,0,0,0,0,0,0)';
      PINUSE='POWER';
      NO_LOAD_CHECK='Both';
      NO_IO_CHECK='Both';
      NO_ASSERT_CHECK='TRUE';
      NO_DIR_CHECK='TRUE';
      ALLOW_CONNECT='TRUE';
    'VSS_W51':
      PIN_NUMBER='(0,0,0,0,0,0,0,0,0,0,0,0,0,0,0,0,0,0,0,0,0,0,0,0,0,0,0,0,0,W51,0,0,0,0,0,0,0,0,0,0)';
      PINUSE='POWER';
      NO_LOAD_CHECK='Both';
      NO_IO_CHECK='Both';
      NO_ASSERT_CHECK='TRUE';
      NO_DIR_CHECK='TRUE';
      ALLOW_CONNECT='TRUE';
    'VSS_W54':
      PIN_NUMBER='(0,0,0,0,0,0,0,0,0,0,0,0,0,0,0,0,0,0,0,0,0,0,0,0,0,0,0,0,0,W54,0,0,0,0,0,0,0,0,0,0)';
      PINUSE='POWER';
      NO_LOAD_CHECK='Both';
      NO_IO_CHECK='Both';
      NO_ASSERT_CHECK='TRUE';
      NO_DIR_CHECK='TRUE';
      ALLOW_CONNECT='TRUE';
    'VSS_W56':
      PIN_NUMBER='(0,0,0,0,0,0,0,0,0,0,0,0,0,0,0,0,0,0,0,0,0,0,0,0,0,0,0,0,0,W56,0,0,0,0,0,0,0,0,0,0)';
      PINUSE='POWER';
      NO_LOAD_CHECK='Both';
      NO_IO_CHECK='Both';
      NO_ASSERT_CHECK='TRUE';
      NO_DIR_CHECK='TRUE';
      ALLOW_CONNECT='TRUE';
    'VSS_W58':
      PIN_NUMBER='(0,0,0,0,0,0,0,0,0,0,0,0,0,0,0,0,0,0,0,0,0,0,0,0,0,0,0,0,0,W58,0,0,0,0,0,0,0,0,0,0)';
      PINUSE='POWER';
      NO_LOAD_CHECK='Both';
      NO_IO_CHECK='Both';
      NO_ASSERT_CHECK='TRUE';
      NO_DIR_CHECK='TRUE';
      ALLOW_CONNECT='TRUE';
    'VSS_W61':
      PIN_NUMBER='(0,0,0,0,0,0,0,0,0,0,0,0,0,0,0,0,0,0,0,0,0,0,0,0,0,0,0,0,0,W61,0,0,0,0,0,0,0,0,0,0)';
      PINUSE='POWER';
      NO_LOAD_CHECK='Both';
      NO_IO_CHECK='Both';
      NO_ASSERT_CHECK='TRUE';
      NO_DIR_CHECK='TRUE';
      ALLOW_CONNECT='TRUE';
    'VSS_W63':
      PIN_NUMBER='(0,0,0,0,0,0,0,0,0,0,0,0,0,0,0,0,0,0,0,0,0,0,0,0,0,0,0,0,0,W63,0,0,0,0,0,0,0,0,0,0)';
      PINUSE='POWER';
      NO_LOAD_CHECK='Both';
      NO_IO_CHECK='Both';
      NO_ASSERT_CHECK='TRUE';
      NO_DIR_CHECK='TRUE';
      ALLOW_CONNECT='TRUE';
    'VSS_W65':
      PIN_NUMBER='(0,0,0,0,0,0,0,0,0,0,0,0,0,0,0,0,0,0,0,0,0,0,0,0,0,0,0,0,0,W65,0,0,0,0,0,0,0,0,0,0)';
      PINUSE='POWER';
      NO_LOAD_CHECK='Both';
      NO_IO_CHECK='Both';
      NO_ASSERT_CHECK='TRUE';
      NO_DIR_CHECK='TRUE';
      ALLOW_CONNECT='TRUE';
    'VSS_W68':
      PIN_NUMBER='(0,0,0,0,0,0,0,0,0,0,0,0,0,0,0,0,0,0,0,0,0,0,0,0,0,0,0,0,0,W68,0,0,0,0,0,0,0,0,0,0)';
      PINUSE='POWER';
      NO_LOAD_CHECK='Both';
      NO_IO_CHECK='Both';
      NO_ASSERT_CHECK='TRUE';
      NO_DIR_CHECK='TRUE';
      ALLOW_CONNECT='TRUE';
    'VSS_W70':
      PIN_NUMBER='(0,0,0,0,0,0,0,0,0,0,0,0,0,0,0,0,0,0,0,0,0,0,0,0,0,0,0,0,0,W70,0,0,0,0,0,0,0,0,0,0)';
      PINUSE='POWER';
      NO_LOAD_CHECK='Both';
      NO_IO_CHECK='Both';
      NO_ASSERT_CHECK='TRUE';
      NO_DIR_CHECK='TRUE';
      ALLOW_CONNECT='TRUE';
    'VSS_W72':
      PIN_NUMBER='(0,0,0,0,0,0,0,0,0,0,0,0,0,0,0,0,0,0,0,0,0,0,0,0,0,0,0,0,0,W72,0,0,0,0,0,0,0,0,0,0)';
      PINUSE='POWER';
      NO_LOAD_CHECK='Both';
      NO_IO_CHECK='Both';
      NO_ASSERT_CHECK='TRUE';
      NO_DIR_CHECK='TRUE';
      ALLOW_CONNECT='TRUE';
    'VSS_W75':
      PIN_NUMBER='(0,0,0,0,0,0,0,0,0,0,0,0,0,0,0,0,0,0,0,0,0,0,0,0,0,0,0,0,0,W75,0,0,0,0,0,0,0,0,0,0)';
      PINUSE='POWER';
      NO_LOAD_CHECK='Both';
      NO_IO_CHECK='Both';
      NO_ASSERT_CHECK='TRUE';
      NO_DIR_CHECK='TRUE';
      ALLOW_CONNECT='TRUE';
    'VSS_Y3':
      PIN_NUMBER='(0,0,0,0,0,0,0,0,0,0,0,0,0,0,0,0,0,0,0,0,0,0,0,0,0,0,0,0,0,Y3,0,0,0,0,0,0,0,0,0,0)';
      PINUSE='POWER';
      NO_LOAD_CHECK='Both';
      NO_IO_CHECK='Both';
      NO_ASSERT_CHECK='TRUE';
      NO_DIR_CHECK='TRUE';
      ALLOW_CONNECT='TRUE';
    'VSS_Y8':
      PIN_NUMBER='(0,0,0,0,0,0,0,0,0,0,0,0,0,0,0,0,0,0,0,0,0,0,0,0,0,0,0,0,0,Y8,0,0,0,0,0,0,0,0,0,0)';
      PINUSE='POWER';
      NO_LOAD_CHECK='Both';
      NO_IO_CHECK='Both';
      NO_ASSERT_CHECK='TRUE';
      NO_DIR_CHECK='TRUE';
      ALLOW_CONNECT='TRUE';
    'VSS_Y10':
      PIN_NUMBER='(0,0,0,0,0,0,0,0,0,0,0,0,0,0,0,0,0,0,0,0,0,0,0,0,0,0,0,0,0,Y10,0,0,0,0,0,0,0,0,0,0)';
      PINUSE='POWER';
      NO_LOAD_CHECK='Both';
      NO_IO_CHECK='Both';
      NO_ASSERT_CHECK='TRUE';
      NO_DIR_CHECK='TRUE';
      ALLOW_CONNECT='TRUE';
    'VSS_Y15':
      PIN_NUMBER='(0,0,0,0,0,0,0,0,0,0,0,0,0,0,0,0,0,0,0,0,0,0,0,0,0,0,0,0,0,Y15,0,0,0,0,0,0,0,0,0,0)';
      PINUSE='POWER';
      NO_LOAD_CHECK='Both';
      NO_IO_CHECK='Both';
      NO_ASSERT_CHECK='TRUE';
      NO_DIR_CHECK='TRUE';
      ALLOW_CONNECT='TRUE';
    'VSS_Y17':
      PIN_NUMBER='(0,0,0,0,0,0,0,0,0,0,0,0,0,0,0,0,0,0,0,0,0,0,0,0,0,0,0,0,0,Y17,0,0,0,0,0,0,0,0,0,0)';
      PINUSE='POWER';
      NO_LOAD_CHECK='Both';
      NO_IO_CHECK='Both';
      NO_ASSERT_CHECK='TRUE';
      NO_DIR_CHECK='TRUE';
      ALLOW_CONNECT='TRUE';
    'VSS_Y22':
      PIN_NUMBER='(0,0,0,0,0,0,0,0,0,0,0,0,0,0,0,0,0,0,0,0,0,0,0,0,0,0,0,0,0,Y22,0,0,0,0,0,0,0,0,0,0)';
      PINUSE='POWER';
      NO_LOAD_CHECK='Both';
      NO_IO_CHECK='Both';
      NO_ASSERT_CHECK='TRUE';
      NO_DIR_CHECK='TRUE';
      ALLOW_CONNECT='TRUE';
    'VSS_Y23':
      PIN_NUMBER='(0,0,0,0,0,0,0,0,0,0,0,0,0,0,0,0,0,0,0,0,0,0,0,0,0,0,0,0,0,Y23,0,0,0,0,0,0,0,0,0,0)';
      PINUSE='POWER';
      NO_LOAD_CHECK='Both';
      NO_IO_CHECK='Both';
      NO_ASSERT_CHECK='TRUE';
      NO_DIR_CHECK='TRUE';
      ALLOW_CONNECT='TRUE';
    'VSS_Y24':
      PIN_NUMBER='(0,0,0,0,0,0,0,0,0,0,0,0,0,0,0,0,0,0,0,0,0,0,0,0,0,0,0,0,0,Y24,0,0,0,0,0,0,0,0,0,0)';
      PINUSE='POWER';
      NO_LOAD_CHECK='Both';
      NO_IO_CHECK='Both';
      NO_ASSERT_CHECK='TRUE';
      NO_DIR_CHECK='TRUE';
      ALLOW_CONNECT='TRUE';
    'VSS_Y25':
      PIN_NUMBER='(0,0,0,0,0,0,0,0,0,0,0,0,0,0,0,0,0,0,0,0,0,0,0,0,0,0,0,0,0,Y25,0,0,0,0,0,0,0,0,0,0)';
      PINUSE='POWER';
      NO_LOAD_CHECK='Both';
      NO_IO_CHECK='Both';
      NO_ASSERT_CHECK='TRUE';
      NO_DIR_CHECK='TRUE';
      ALLOW_CONNECT='TRUE';
    'VSS_Y26':
      PIN_NUMBER='(0,0,0,0,0,0,0,0,0,0,0,0,0,0,0,0,0,0,0,0,0,0,0,0,0,0,0,0,0,Y26,0,0,0,0,0,0,0,0,0,0)';
      PINUSE='POWER';
      NO_LOAD_CHECK='Both';
      NO_IO_CHECK='Both';
      NO_ASSERT_CHECK='TRUE';
      NO_DIR_CHECK='TRUE';
      ALLOW_CONNECT='TRUE';
    'VSS_Y27':
      PIN_NUMBER='(0,0,0,0,0,0,0,0,0,0,0,0,0,0,0,0,0,0,0,0,0,0,0,0,0,0,0,0,0,Y27,0,0,0,0,0,0,0,0,0,0)';
      PINUSE='POWER';
      NO_LOAD_CHECK='Both';
      NO_IO_CHECK='Both';
      NO_ASSERT_CHECK='TRUE';
      NO_DIR_CHECK='TRUE';
      ALLOW_CONNECT='TRUE';
    'VSS_Y28':
      PIN_NUMBER='(0,0,0,0,0,0,0,0,0,0,0,0,0,0,0,0,0,0,0,0,0,0,0,0,0,0,0,0,0,Y28,0,0,0,0,0,0,0,0,0,0)';
      PINUSE='POWER';
      NO_LOAD_CHECK='Both';
      NO_IO_CHECK='Both';
      NO_ASSERT_CHECK='TRUE';
      NO_DIR_CHECK='TRUE';
      ALLOW_CONNECT='TRUE';
    'VSS_Y31':
      PIN_NUMBER='(0,0,0,0,0,0,0,0,0,0,0,0,0,0,0,0,0,0,0,0,0,0,0,0,0,0,0,0,0,Y31,0,0,0,0,0,0,0,0,0,0)';
      PINUSE='POWER';
      NO_LOAD_CHECK='Both';
      NO_IO_CHECK='Both';
      NO_ASSERT_CHECK='TRUE';
      NO_DIR_CHECK='TRUE';
      ALLOW_CONNECT='TRUE';
    'VSS_Y32':
      PIN_NUMBER='(0,0,0,0,0,0,0,0,0,0,0,0,0,0,0,0,0,0,0,0,0,0,0,0,0,0,0,0,0,Y32,0,0,0,0,0,0,0,0,0,0)';
      PINUSE='POWER';
      NO_LOAD_CHECK='Both';
      NO_IO_CHECK='Both';
      NO_ASSERT_CHECK='TRUE';
      NO_DIR_CHECK='TRUE';
      ALLOW_CONNECT='TRUE';
    'VSS_Y33':
      PIN_NUMBER='(0,0,0,0,0,0,0,0,0,0,0,0,0,0,0,0,0,0,0,0,0,0,0,0,0,0,0,0,0,Y33,0,0,0,0,0,0,0,0,0,0)';
      PINUSE='POWER';
      NO_LOAD_CHECK='Both';
      NO_IO_CHECK='Both';
      NO_ASSERT_CHECK='TRUE';
      NO_DIR_CHECK='TRUE';
      ALLOW_CONNECT='TRUE';
    'VSS_Y34':
      PIN_NUMBER='(0,0,0,0,0,0,0,0,0,0,0,0,0,0,0,0,0,0,0,0,0,0,0,0,0,0,0,0,0,Y34,0,0,0,0,0,0,0,0,0,0)';
      PINUSE='POWER';
      NO_LOAD_CHECK='Both';
      NO_IO_CHECK='Both';
      NO_ASSERT_CHECK='TRUE';
      NO_DIR_CHECK='TRUE';
      ALLOW_CONNECT='TRUE';
    'VSS_Y37':
      PIN_NUMBER='(0,0,0,0,0,0,0,0,0,0,0,0,0,0,0,0,0,0,0,0,0,0,0,0,0,0,0,0,0,Y37,0,0,0,0,0,0,0,0,0,0)';
      PINUSE='POWER';
      NO_LOAD_CHECK='Both';
      NO_IO_CHECK='Both';
      NO_ASSERT_CHECK='TRUE';
      NO_DIR_CHECK='TRUE';
      ALLOW_CONNECT='TRUE';
    'VSS_Y39':
      PIN_NUMBER='(0,0,0,0,0,0,0,0,0,0,0,0,0,0,0,0,0,0,0,0,0,0,0,0,0,0,0,0,0,Y39,0,0,0,0,0,0,0,0,0,0)';
      PINUSE='POWER';
      NO_LOAD_CHECK='Both';
      NO_IO_CHECK='Both';
      NO_ASSERT_CHECK='TRUE';
      NO_DIR_CHECK='TRUE';
      ALLOW_CONNECT='TRUE';
    'VSS_Y42':
      PIN_NUMBER='(0,0,0,0,0,0,0,0,0,0,0,0,0,0,0,0,0,0,0,0,0,0,0,0,0,0,0,0,0,Y42,0,0,0,0,0,0,0,0,0,0)';
      PINUSE='POWER';
      NO_LOAD_CHECK='Both';
      NO_IO_CHECK='Both';
      NO_ASSERT_CHECK='TRUE';
      NO_DIR_CHECK='TRUE';
      ALLOW_CONNECT='TRUE';
    'VSS_Y43':
      PIN_NUMBER='(0,0,0,0,0,0,0,0,0,0,0,0,0,0,0,0,0,0,0,0,0,0,0,0,0,0,0,0,0,Y43,0,0,0,0,0,0,0,0,0,0)';
      PINUSE='POWER';
      NO_LOAD_CHECK='Both';
      NO_IO_CHECK='Both';
      NO_ASSERT_CHECK='TRUE';
      NO_DIR_CHECK='TRUE';
      ALLOW_CONNECT='TRUE';
    'VSS_Y44':
      PIN_NUMBER='(0,0,0,0,0,0,0,0,0,0,0,0,0,0,0,0,0,0,0,0,0,0,0,0,0,0,0,0,0,Y44,0,0,0,0,0,0,0,0,0,0)';
      PINUSE='POWER';
      NO_LOAD_CHECK='Both';
      NO_IO_CHECK='Both';
      NO_ASSERT_CHECK='TRUE';
      NO_DIR_CHECK='TRUE';
      ALLOW_CONNECT='TRUE';
    'VSS_Y45':
      PIN_NUMBER='(0,0,0,0,0,0,0,0,0,0,0,0,0,0,0,0,0,0,0,0,0,0,0,0,0,0,0,0,0,Y45,0,0,0,0,0,0,0,0,0,0)';
      PINUSE='POWER';
      NO_LOAD_CHECK='Both';
      NO_IO_CHECK='Both';
      NO_ASSERT_CHECK='TRUE';
      NO_DIR_CHECK='TRUE';
      ALLOW_CONNECT='TRUE';
    'VSS_Y48':
      PIN_NUMBER='(0,0,0,0,0,0,0,0,0,0,0,0,0,0,0,0,0,0,0,0,0,0,0,0,0,0,0,0,0,Y48,0,0,0,0,0,0,0,0,0,0)';
      PINUSE='POWER';
      NO_LOAD_CHECK='Both';
      NO_IO_CHECK='Both';
      NO_ASSERT_CHECK='TRUE';
      NO_DIR_CHECK='TRUE';
      ALLOW_CONNECT='TRUE';
    'VSS_Y49':
      PIN_NUMBER='(0,0,0,0,0,0,0,0,0,0,0,0,0,0,0,0,0,0,0,0,0,0,0,0,0,0,0,0,0,Y49,0,0,0,0,0,0,0,0,0,0)';
      PINUSE='POWER';
      NO_LOAD_CHECK='Both';
      NO_IO_CHECK='Both';
      NO_ASSERT_CHECK='TRUE';
      NO_DIR_CHECK='TRUE';
      ALLOW_CONNECT='TRUE';
    'VSS_Y50':
      PIN_NUMBER='(0,0,0,0,0,0,0,0,0,0,0,0,0,0,0,0,0,0,0,0,0,0,0,0,0,0,0,0,0,Y50,0,0,0,0,0,0,0,0,0,0)';
      PINUSE='POWER';
      NO_LOAD_CHECK='Both';
      NO_IO_CHECK='Both';
      NO_ASSERT_CHECK='TRUE';
      NO_DIR_CHECK='TRUE';
      ALLOW_CONNECT='TRUE';
    'VSS_Y51':
      PIN_NUMBER='(0,0,0,0,0,0,0,0,0,0,0,0,0,0,0,0,0,0,0,0,0,0,0,0,0,0,0,0,0,Y51,0,0,0,0,0,0,0,0,0,0)';
      PINUSE='POWER';
      NO_LOAD_CHECK='Both';
      NO_IO_CHECK='Both';
      NO_ASSERT_CHECK='TRUE';
      NO_DIR_CHECK='TRUE';
      ALLOW_CONNECT='TRUE';
    'VSS_Y52':
      PIN_NUMBER='(0,0,0,0,0,0,0,0,0,0,0,0,0,0,0,0,0,0,0,0,0,0,0,0,0,0,0,0,0,Y52,0,0,0,0,0,0,0,0,0,0)';
      PINUSE='POWER';
      NO_LOAD_CHECK='Both';
      NO_IO_CHECK='Both';
      NO_ASSERT_CHECK='TRUE';
      NO_DIR_CHECK='TRUE';
      ALLOW_CONNECT='TRUE';
    'VSS_Y53':
      PIN_NUMBER='(0,0,0,0,0,0,0,0,0,0,0,0,0,0,0,0,0,0,0,0,0,0,0,0,0,0,0,0,0,Y53,0,0,0,0,0,0,0,0,0,0)';
      PINUSE='POWER';
      NO_LOAD_CHECK='Both';
      NO_IO_CHECK='Both';
      NO_ASSERT_CHECK='TRUE';
      NO_DIR_CHECK='TRUE';
      ALLOW_CONNECT='TRUE';
    'VSS_Y54':
      PIN_NUMBER='(0,0,0,0,0,0,0,0,0,0,0,0,0,0,0,0,0,0,0,0,0,0,0,0,0,0,0,0,0,Y54,0,0,0,0,0,0,0,0,0,0)';
      PINUSE='POWER';
      NO_LOAD_CHECK='Both';
      NO_IO_CHECK='Both';
      NO_ASSERT_CHECK='TRUE';
      NO_DIR_CHECK='TRUE';
      ALLOW_CONNECT='TRUE';
    'VSS_Y59':
      PIN_NUMBER='(0,0,0,0,0,0,0,0,0,0,0,0,0,0,0,0,0,0,0,0,0,0,0,0,0,0,0,0,0,Y59,0,0,0,0,0,0,0,0,0,0)';
      PINUSE='POWER';
      NO_LOAD_CHECK='Both';
      NO_IO_CHECK='Both';
      NO_ASSERT_CHECK='TRUE';
      NO_DIR_CHECK='TRUE';
      ALLOW_CONNECT='TRUE';
    'VSS_Y61':
      PIN_NUMBER='(0,0,0,0,0,0,0,0,0,0,0,0,0,0,0,0,0,0,0,0,0,0,0,0,0,0,0,0,0,Y61,0,0,0,0,0,0,0,0,0,0)';
      PINUSE='POWER';
      NO_LOAD_CHECK='Both';
      NO_IO_CHECK='Both';
      NO_ASSERT_CHECK='TRUE';
      NO_DIR_CHECK='TRUE';
      ALLOW_CONNECT='TRUE';
    'VSS_Y66':
      PIN_NUMBER='(0,0,0,0,0,0,0,0,0,0,0,0,0,0,0,0,0,0,0,0,0,0,0,0,0,0,0,0,0,Y66,0,0,0,0,0,0,0,0,0,0)';
      PINUSE='POWER';
      NO_LOAD_CHECK='Both';
      NO_IO_CHECK='Both';
      NO_ASSERT_CHECK='TRUE';
      NO_DIR_CHECK='TRUE';
      ALLOW_CONNECT='TRUE';
    'VSS_Y68':
      PIN_NUMBER='(0,0,0,0,0,0,0,0,0,0,0,0,0,0,0,0,0,0,0,0,0,0,0,0,0,0,0,0,0,Y68,0,0,0,0,0,0,0,0,0,0)';
      PINUSE='POWER';
      NO_LOAD_CHECK='Both';
      NO_IO_CHECK='Both';
      NO_ASSERT_CHECK='TRUE';
      NO_DIR_CHECK='TRUE';
      ALLOW_CONNECT='TRUE';
    'VSS_Y73':
      PIN_NUMBER='(0,0,0,0,0,0,0,0,0,0,0,0,0,0,0,0,0,0,0,0,0,0,0,0,0,0,0,0,0,Y73,0,0,0,0,0,0,0,0,0,0)';
      PINUSE='POWER';
      NO_LOAD_CHECK='Both';
      NO_IO_CHECK='Both';
      NO_ASSERT_CHECK='TRUE';
      NO_DIR_CHECK='TRUE';
      ALLOW_CONNECT='TRUE';
    'VSS_AA1':
      PIN_NUMBER='(0,0,0,0,0,0,0,0,0,0,0,0,0,0,0,0,0,0,0,0,0,0,0,0,0,0,0,0,0,AA1,0,0,0,0,0,0,0,0,0,0)';
      PINUSE='POWER';
      NO_LOAD_CHECK='Both';
      NO_IO_CHECK='Both';
      NO_ASSERT_CHECK='TRUE';
      NO_DIR_CHECK='TRUE';
      ALLOW_CONNECT='TRUE';
    'VSS_AA4':
      PIN_NUMBER='(0,0,0,0,0,0,0,0,0,0,0,0,0,0,0,0,0,0,0,0,0,0,0,0,0,0,0,0,0,AA4,0,0,0,0,0,0,0,0,0,0)';
      PINUSE='POWER';
      NO_LOAD_CHECK='Both';
      NO_IO_CHECK='Both';
      NO_ASSERT_CHECK='TRUE';
      NO_DIR_CHECK='TRUE';
      ALLOW_CONNECT='TRUE';
    'VSS_AA6':
      PIN_NUMBER='(0,0,0,0,0,0,0,0,0,0,0,0,0,0,0,0,0,0,0,0,0,0,0,0,0,0,0,0,0,AA6,0,0,0,0,0,0,0,0,0,0)';
      PINUSE='POWER';
      NO_LOAD_CHECK='Both';
      NO_IO_CHECK='Both';
      NO_ASSERT_CHECK='TRUE';
      NO_DIR_CHECK='TRUE';
      ALLOW_CONNECT='TRUE';
    'VSS_AA8':
      PIN_NUMBER='(0,0,0,0,0,0,0,0,0,0,0,0,0,0,0,0,0,0,0,0,0,0,0,0,0,0,0,0,0,AA8,0,0,0,0,0,0,0,0,0,0)';
      PINUSE='POWER';
      NO_LOAD_CHECK='Both';
      NO_IO_CHECK='Both';
      NO_ASSERT_CHECK='TRUE';
      NO_DIR_CHECK='TRUE';
      ALLOW_CONNECT='TRUE';
    'VSS_AA11':
      PIN_NUMBER='(0,0,0,0,0,0,0,0,0,0,0,0,0,0,0,0,0,0,0,0,0,0,0,0,0,0,0,0,0,AA11,0,0,0,0,0,0,0,0,0,0)';
      PINUSE='POWER';
      NO_LOAD_CHECK='Both';
      NO_IO_CHECK='Both';
      NO_ASSERT_CHECK='TRUE';
      NO_DIR_CHECK='TRUE';
      ALLOW_CONNECT='TRUE';
    'VSS_AA13':
      PIN_NUMBER='(0,0,0,0,0,0,0,0,0,0,0,0,0,0,0,0,0,0,0,0,0,0,0,0,0,0,0,0,0,AA13,0,0,0,0,0,0,0,0,0,0)';
      PINUSE='POWER';
      NO_LOAD_CHECK='Both';
      NO_IO_CHECK='Both';
      NO_ASSERT_CHECK='TRUE';
      NO_DIR_CHECK='TRUE';
      ALLOW_CONNECT='TRUE';
    'VSS_AA15':
      PIN_NUMBER='(0,0,0,0,0,0,0,0,0,0,0,0,0,0,0,0,0,0,0,0,0,0,0,0,0,0,0,0,0,AA15,0,0,0,0,0,0,0,0,0,0)';
      PINUSE='POWER';
      NO_LOAD_CHECK='Both';
      NO_IO_CHECK='Both';
      NO_ASSERT_CHECK='TRUE';
      NO_DIR_CHECK='TRUE';
      ALLOW_CONNECT='TRUE';
    'VSS_AA18':
      PIN_NUMBER='(0,0,0,0,0,0,0,0,0,0,0,0,0,0,0,0,0,0,0,0,0,0,0,0,0,0,0,0,0,AA18,0,0,0,0,0,0,0,0,0,0)';
      PINUSE='POWER';
      NO_LOAD_CHECK='Both';
      NO_IO_CHECK='Both';
      NO_ASSERT_CHECK='TRUE';
      NO_DIR_CHECK='TRUE';
      ALLOW_CONNECT='TRUE';
    'VSS_AA20':
      PIN_NUMBER='(0,0,0,0,0,0,0,0,0,0,0,0,0,0,0,0,0,0,0,0,0,0,0,0,0,0,0,0,0,AA20,0,0,0,0,0,0,0,0,0,0)';
      PINUSE='POWER';
      NO_LOAD_CHECK='Both';
      NO_IO_CHECK='Both';
      NO_ASSERT_CHECK='TRUE';
      NO_DIR_CHECK='TRUE';
      ALLOW_CONNECT='TRUE';
    'VSS_AA31':
      PIN_NUMBER='(0,0,0,0,0,0,0,0,0,0,0,0,0,0,0,0,0,0,0,0,0,0,0,0,0,0,0,0,0,AA31,0,0,0,0,0,0,0,0,0,0)';
      PINUSE='POWER';
      NO_LOAD_CHECK='Both';
      NO_IO_CHECK='Both';
      NO_ASSERT_CHECK='TRUE';
      NO_DIR_CHECK='TRUE';
      ALLOW_CONNECT='TRUE';
    'VSS_AA34':
      PIN_NUMBER='(0,0,0,0,0,0,0,0,0,0,0,0,0,0,0,0,0,0,0,0,0,0,0,0,0,0,0,0,0,AA34,0,0,0,0,0,0,0,0,0,0)';
      PINUSE='POWER';
      NO_LOAD_CHECK='Both';
      NO_IO_CHECK='Both';
      NO_ASSERT_CHECK='TRUE';
      NO_DIR_CHECK='TRUE';
      ALLOW_CONNECT='TRUE';
    'VSS_AA35':
      PIN_NUMBER='(0,0,0,0,0,0,0,0,0,0,0,0,0,0,0,0,0,0,0,0,0,0,0,0,0,0,0,0,0,AA35,0,0,0,0,0,0,0,0,0,0)';
      PINUSE='POWER';
      NO_LOAD_CHECK='Both';
      NO_IO_CHECK='Both';
      NO_ASSERT_CHECK='TRUE';
      NO_DIR_CHECK='TRUE';
      ALLOW_CONNECT='TRUE';
    'VSS_AA36':
      PIN_NUMBER='(0,0,0,0,0,0,0,0,0,0,0,0,0,0,0,0,0,0,0,0,0,0,0,0,0,0,0,0,0,AA36,0,0,0,0,0,0,0,0,0,0)';
      PINUSE='POWER';
      NO_LOAD_CHECK='Both';
      NO_IO_CHECK='Both';
      NO_ASSERT_CHECK='TRUE';
      NO_DIR_CHECK='TRUE';
      ALLOW_CONNECT='TRUE';
    'VSS_AA40':
      PIN_NUMBER='(0,0,0,0,0,0,0,0,0,0,0,0,0,0,0,0,0,0,0,0,0,0,0,0,0,0,0,0,0,AA40,0,0,0,0,0,0,0,0,0,0)';
      PINUSE='POWER';
      NO_LOAD_CHECK='Both';
      NO_IO_CHECK='Both';
      NO_ASSERT_CHECK='TRUE';
      NO_DIR_CHECK='TRUE';
      ALLOW_CONNECT='TRUE';
    'VSS_AA41':
      PIN_NUMBER='(0,0,0,0,0,0,0,0,0,0,0,0,0,0,0,0,0,0,0,0,0,0,0,0,0,0,0,0,0,AA41,0,0,0,0,0,0,0,0,0,0)';
      PINUSE='POWER';
      NO_LOAD_CHECK='Both';
      NO_IO_CHECK='Both';
      NO_ASSERT_CHECK='TRUE';
      NO_DIR_CHECK='TRUE';
      ALLOW_CONNECT='TRUE';
    'VSS_AA45':
      PIN_NUMBER='(0,0,0,0,0,0,0,0,0,0,0,0,0,0,0,0,0,0,0,0,0,0,0,0,0,0,0,0,0,AA45,0,0,0,0,0,0,0,0,0,0)';
      PINUSE='POWER';
      NO_LOAD_CHECK='Both';
      NO_IO_CHECK='Both';
      NO_ASSERT_CHECK='TRUE';
      NO_DIR_CHECK='TRUE';
      ALLOW_CONNECT='TRUE';
    'VSS_AA56':
      PIN_NUMBER='(0,0,0,0,0,0,0,0,0,0,0,0,0,0,0,0,0,0,0,0,0,0,0,0,0,0,0,0,0,AA56,0,0,0,0,0,0,0,0,0,0)';
      PINUSE='POWER';
      NO_LOAD_CHECK='Both';
      NO_IO_CHECK='Both';
      NO_ASSERT_CHECK='TRUE';
      NO_DIR_CHECK='TRUE';
      ALLOW_CONNECT='TRUE';
    'VSS_AA58':
      PIN_NUMBER='(0,0,0,0,0,0,0,0,0,0,0,0,0,0,0,0,0,0,0,0,0,0,0,0,0,0,0,0,0,AA58,0,0,0,0,0,0,0,0,0,0)';
      PINUSE='POWER';
      NO_LOAD_CHECK='Both';
      NO_IO_CHECK='Both';
      NO_ASSERT_CHECK='TRUE';
      NO_DIR_CHECK='TRUE';
      ALLOW_CONNECT='TRUE';
    'VSS_AA61':
      PIN_NUMBER='(0,0,0,0,0,0,0,0,0,0,0,0,0,0,0,0,0,0,0,0,0,0,0,0,0,0,0,0,0,AA61,0,0,0,0,0,0,0,0,0,0)';
      PINUSE='POWER';
      NO_LOAD_CHECK='Both';
      NO_IO_CHECK='Both';
      NO_ASSERT_CHECK='TRUE';
      NO_DIR_CHECK='TRUE';
      ALLOW_CONNECT='TRUE';
    'VSS_AA63':
      PIN_NUMBER='(0,0,0,0,0,0,0,0,0,0,0,0,0,0,0,0,0,0,0,0,0,0,0,0,0,0,0,0,0,AA63,0,0,0,0,0,0,0,0,0,0)';
      PINUSE='POWER';
      NO_LOAD_CHECK='Both';
      NO_IO_CHECK='Both';
      NO_ASSERT_CHECK='TRUE';
      NO_DIR_CHECK='TRUE';
      ALLOW_CONNECT='TRUE';
    'VSS_AA65':
      PIN_NUMBER='(0,0,0,0,0,0,0,0,0,0,0,0,0,0,0,0,0,0,0,0,0,0,0,0,0,0,0,0,0,AA65,0,0,0,0,0,0,0,0,0,0)';
      PINUSE='POWER';
      NO_LOAD_CHECK='Both';
      NO_IO_CHECK='Both';
      NO_ASSERT_CHECK='TRUE';
      NO_DIR_CHECK='TRUE';
      ALLOW_CONNECT='TRUE';
    'VSS_AA68':
      PIN_NUMBER='(0,0,0,0,0,0,0,0,0,0,0,0,0,0,0,0,0,0,0,0,0,0,0,0,0,0,0,0,0,AA68,0,0,0,0,0,0,0,0,0,0)';
      PINUSE='POWER';
      NO_LOAD_CHECK='Both';
      NO_IO_CHECK='Both';
      NO_ASSERT_CHECK='TRUE';
      NO_DIR_CHECK='TRUE';
      ALLOW_CONNECT='TRUE';
    'VSS_AA70':
      PIN_NUMBER='(0,0,0,0,0,0,0,0,0,0,0,0,0,0,0,0,0,0,0,0,0,0,0,0,0,0,0,0,0,AA70,0,0,0,0,0,0,0,0,0,0)';
      PINUSE='POWER';
      NO_LOAD_CHECK='Both';
      NO_IO_CHECK='Both';
      NO_ASSERT_CHECK='TRUE';
      NO_DIR_CHECK='TRUE';
      ALLOW_CONNECT='TRUE';
    'VSS_AA75':
      PIN_NUMBER='(0,0,0,0,0,0,0,0,0,0,0,0,0,0,0,0,0,0,0,0,0,0,0,0,0,0,0,0,0,AA75,0,0,0,0,0,0,0,0,0,0)';
      PINUSE='POWER';
      NO_LOAD_CHECK='Both';
      NO_IO_CHECK='Both';
      NO_ASSERT_CHECK='TRUE';
      NO_DIR_CHECK='TRUE';
      ALLOW_CONNECT='TRUE';
    'VSS_AB3':
      PIN_NUMBER='(0,0,0,0,0,0,0,0,0,0,0,0,0,0,0,0,0,0,0,0,0,0,0,0,0,0,0,0,0,AB3,0,0,0,0,0,0,0,0,0,0)';
      PINUSE='POWER';
      NO_LOAD_CHECK='Both';
      NO_IO_CHECK='Both';
      NO_ASSERT_CHECK='TRUE';
      NO_DIR_CHECK='TRUE';
      ALLOW_CONNECT='TRUE';
    'VSS_AB5':
      PIN_NUMBER='(0,0,0,0,0,0,0,0,0,0,0,0,0,0,0,0,0,0,0,0,0,0,0,0,0,0,0,0,0,AB5,0,0,0,0,0,0,0,0,0,0)';
      PINUSE='POWER';
      NO_LOAD_CHECK='Both';
      NO_IO_CHECK='Both';
      NO_ASSERT_CHECK='TRUE';
      NO_DIR_CHECK='TRUE';
      ALLOW_CONNECT='TRUE';
    'VSS_AB8':
      PIN_NUMBER='(0,0,0,0,0,0,0,0,0,0,0,0,0,0,0,0,0,0,0,0,0,0,0,0,0,0,0,0,0,AB8,0,0,0,0,0,0,0,0,0,0)';
      PINUSE='POWER';
      NO_LOAD_CHECK='Both';
      NO_IO_CHECK='Both';
      NO_ASSERT_CHECK='TRUE';
      NO_DIR_CHECK='TRUE';
      ALLOW_CONNECT='TRUE';
    'VSS_AB10':
      PIN_NUMBER='(0,0,0,0,0,0,0,0,0,0,0,0,0,0,0,0,0,0,0,0,0,0,0,0,0,0,0,0,0,AB10,0,0,0,0,0,0,0,0,0,0)';
      PINUSE='POWER';
      NO_LOAD_CHECK='Both';
      NO_IO_CHECK='Both';
      NO_ASSERT_CHECK='TRUE';
      NO_DIR_CHECK='TRUE';
      ALLOW_CONNECT='TRUE';
    'VSS_AB12':
      PIN_NUMBER='(0,0,0,0,0,0,0,0,0,0,0,0,0,0,0,0,0,0,0,0,0,0,0,0,0,0,0,0,0,AB12,0,0,0,0,0,0,0,0,0,0)';
      PINUSE='POWER';
      NO_LOAD_CHECK='Both';
      NO_IO_CHECK='Both';
      NO_ASSERT_CHECK='TRUE';
      NO_DIR_CHECK='TRUE';
      ALLOW_CONNECT='TRUE';
    'VSS_AB15':
      PIN_NUMBER='(0,0,0,0,0,0,0,0,0,0,0,0,0,0,0,0,0,0,0,0,0,0,0,0,0,0,0,0,0,AB15,0,0,0,0,0,0,0,0,0,0)';
      PINUSE='POWER';
      NO_LOAD_CHECK='Both';
      NO_IO_CHECK='Both';
      NO_ASSERT_CHECK='TRUE';
      NO_DIR_CHECK='TRUE';
      ALLOW_CONNECT='TRUE';
    'VSS_AB17':
      PIN_NUMBER='(0,0,0,0,0,0,0,0,0,0,0,0,0,0,0,0,0,0,0,0,0,0,0,0,0,0,0,0,0,AB17,0,0,0,0,0,0,0,0,0,0)';
      PINUSE='POWER';
      NO_LOAD_CHECK='Both';
      NO_IO_CHECK='Both';
      NO_ASSERT_CHECK='TRUE';
      NO_DIR_CHECK='TRUE';
      ALLOW_CONNECT='TRUE';
    'VSS_AB19':
      PIN_NUMBER='(0,0,0,0,0,0,0,0,0,0,0,0,0,0,0,0,0,0,0,0,0,0,0,0,0,0,0,0,0,AB19,0,0,0,0,0,0,0,0,0,0)';
      PINUSE='POWER';
      NO_LOAD_CHECK='Both';
      NO_IO_CHECK='Both';
      NO_ASSERT_CHECK='TRUE';
      NO_DIR_CHECK='TRUE';
      ALLOW_CONNECT='TRUE';
    'VSS_AB22':
      PIN_NUMBER='(0,0,0,0,0,0,0,0,0,0,0,0,0,0,0,0,0,0,0,0,0,0,0,0,0,0,0,0,0,AB22,0,0,0,0,0,0,0,0,0,0)';
      PINUSE='POWER';
      NO_LOAD_CHECK='Both';
      NO_IO_CHECK='Both';
      NO_ASSERT_CHECK='TRUE';
      NO_DIR_CHECK='TRUE';
      ALLOW_CONNECT='TRUE';
    'VSS_AB25':
      PIN_NUMBER='(0,0,0,0,0,0,0,0,0,0,0,0,0,0,0,0,0,0,0,0,0,0,0,0,0,0,0,0,0,AB25,0,0,0,0,0,0,0,0,0,0)';
      PINUSE='POWER';
      NO_LOAD_CHECK='Both';
      NO_IO_CHECK='Both';
      NO_ASSERT_CHECK='TRUE';
      NO_DIR_CHECK='TRUE';
      ALLOW_CONNECT='TRUE';
    'VSS_AB28':
      PIN_NUMBER='(0,0,0,0,0,0,0,0,0,0,0,0,0,0,0,0,0,0,0,0,0,0,0,0,0,0,0,0,0,AB28,0,0,0,0,0,0,0,0,0,0)';
      PINUSE='POWER';
      NO_LOAD_CHECK='Both';
      NO_IO_CHECK='Both';
      NO_ASSERT_CHECK='TRUE';
      NO_DIR_CHECK='TRUE';
      ALLOW_CONNECT='TRUE';
    'VSS_AB31':
      PIN_NUMBER='(0,0,0,0,0,0,0,0,0,0,0,0,0,0,0,0,0,0,0,0,0,0,0,0,0,0,0,0,0,AB31,0,0,0,0,0,0,0,0,0,0)';
      PINUSE='POWER';
      NO_LOAD_CHECK='Both';
      NO_IO_CHECK='Both';
      NO_ASSERT_CHECK='TRUE';
      NO_DIR_CHECK='TRUE';
      ALLOW_CONNECT='TRUE';
    'VSS_AB34':
      PIN_NUMBER='(0,0,0,0,0,0,0,0,0,0,0,0,0,0,0,0,0,0,0,0,0,0,0,0,0,0,0,0,0,AB34,0,0,0,0,0,0,0,0,0,0)';
      PINUSE='POWER';
      NO_LOAD_CHECK='Both';
      NO_IO_CHECK='Both';
      NO_ASSERT_CHECK='TRUE';
      NO_DIR_CHECK='TRUE';
      ALLOW_CONNECT='TRUE';
    'VSS_AB37':
      PIN_NUMBER='(0,0,0,0,0,0,0,0,0,0,0,0,0,0,0,0,0,0,0,0,0,0,0,0,0,0,0,0,0,AB37,0,0,0,0,0,0,0,0,0,0)';
      PINUSE='POWER';
      NO_LOAD_CHECK='Both';
      NO_IO_CHECK='Both';
      NO_ASSERT_CHECK='TRUE';
      NO_DIR_CHECK='TRUE';
      ALLOW_CONNECT='TRUE';
    'VSS_AB39':
      PIN_NUMBER='(0,0,0,0,0,0,0,0,0,0,0,0,0,0,0,0,0,0,0,0,0,0,0,0,0,0,0,0,0,AB39,0,0,0,0,0,0,0,0,0,0)';
      PINUSE='POWER';
      NO_LOAD_CHECK='Both';
      NO_IO_CHECK='Both';
      NO_ASSERT_CHECK='TRUE';
      NO_DIR_CHECK='TRUE';
      ALLOW_CONNECT='TRUE';
    'VSS_AB42':
      PIN_NUMBER='(0,0,0,0,0,0,0,0,0,0,0,0,0,0,0,0,0,0,0,0,0,0,0,0,0,0,0,0,0,AB42,0,0,0,0,0,0,0,0,0,0)';
      PINUSE='POWER';
      NO_LOAD_CHECK='Both';
      NO_IO_CHECK='Both';
      NO_ASSERT_CHECK='TRUE';
      NO_DIR_CHECK='TRUE';
      ALLOW_CONNECT='TRUE';
    'VSS_AB45':
      PIN_NUMBER='(0,0,0,0,0,0,0,0,0,0,0,0,0,0,0,0,0,0,0,0,0,0,0,0,0,0,0,0,0,AB45,0,0,0,0,0,0,0,0,0,0)';
      PINUSE='POWER';
      NO_LOAD_CHECK='Both';
      NO_IO_CHECK='Both';
      NO_ASSERT_CHECK='TRUE';
      NO_DIR_CHECK='TRUE';
      ALLOW_CONNECT='TRUE';
    'VSS_AB48':
      PIN_NUMBER='(0,0,0,0,0,0,0,0,0,0,0,0,0,0,0,0,0,0,0,0,0,0,0,0,0,0,0,0,0,AB48,0,0,0,0,0,0,0,0,0,0)';
      PINUSE='POWER';
      NO_LOAD_CHECK='Both';
      NO_IO_CHECK='Both';
      NO_ASSERT_CHECK='TRUE';
      NO_DIR_CHECK='TRUE';
      ALLOW_CONNECT='TRUE';
    'VSS_AB51':
      PIN_NUMBER='(0,0,0,0,0,0,0,0,0,0,0,0,0,0,0,0,0,0,0,0,0,0,0,0,0,0,0,0,0,AB51,0,0,0,0,0,0,0,0,0,0)';
      PINUSE='POWER';
      NO_LOAD_CHECK='Both';
      NO_IO_CHECK='Both';
      NO_ASSERT_CHECK='TRUE';
      NO_DIR_CHECK='TRUE';
      ALLOW_CONNECT='TRUE';
    'VSS_AB54':
      PIN_NUMBER='(0,0,0,0,0,0,0,0,0,0,0,0,0,0,0,0,0,0,0,0,0,0,0,0,0,0,0,0,0,AB54,0,0,0,0,0,0,0,0,0,0)';
      PINUSE='POWER';
      NO_LOAD_CHECK='Both';
      NO_IO_CHECK='Both';
      NO_ASSERT_CHECK='TRUE';
      NO_DIR_CHECK='TRUE';
      ALLOW_CONNECT='TRUE';
    'VSS_AB57':
      PIN_NUMBER='(0,0,0,0,0,0,0,0,0,0,0,0,0,0,0,0,0,0,0,0,0,0,0,0,0,0,0,0,0,AB57,0,0,0,0,0,0,0,0,0,0)';
      PINUSE='POWER';
      NO_LOAD_CHECK='Both';
      NO_IO_CHECK='Both';
      NO_ASSERT_CHECK='TRUE';
      NO_DIR_CHECK='TRUE';
      ALLOW_CONNECT='TRUE';
    'VSS_AB59':
      PIN_NUMBER='(0,0,0,0,0,0,0,0,0,0,0,0,0,0,0,0,0,0,0,0,0,0,0,0,0,0,0,0,0,AB59,0,0,0,0,0,0,0,0,0,0)';
      PINUSE='POWER';
      NO_LOAD_CHECK='Both';
      NO_IO_CHECK='Both';
      NO_ASSERT_CHECK='TRUE';
      NO_DIR_CHECK='TRUE';
      ALLOW_CONNECT='TRUE';
    'VSS_AB61':
      PIN_NUMBER='(0,0,0,0,0,0,0,0,0,0,0,0,0,0,0,0,0,0,0,0,0,0,0,0,0,0,0,0,0,AB61,0,0,0,0,0,0,0,0,0,0)';
      PINUSE='POWER';
      NO_LOAD_CHECK='Both';
      NO_IO_CHECK='Both';
      NO_ASSERT_CHECK='TRUE';
      NO_DIR_CHECK='TRUE';
      ALLOW_CONNECT='TRUE';
    'VSS_AB64':
      PIN_NUMBER='(0,0,0,0,0,0,0,0,0,0,0,0,0,0,0,0,0,0,0,0,0,0,0,0,0,0,0,0,0,AB64,0,0,0,0,0,0,0,0,0,0)';
      PINUSE='POWER';
      NO_LOAD_CHECK='Both';
      NO_IO_CHECK='Both';
      NO_ASSERT_CHECK='TRUE';
      NO_DIR_CHECK='TRUE';
      ALLOW_CONNECT='TRUE';
    'VSS_AB66':
      PIN_NUMBER='(0,0,0,0,0,0,0,0,0,0,0,0,0,0,0,0,0,0,0,0,0,0,0,0,0,0,0,0,0,AB66,0,0,0,0,0,0,0,0,0,0)';
      PINUSE='POWER';
      NO_LOAD_CHECK='Both';
      NO_IO_CHECK='Both';
      NO_ASSERT_CHECK='TRUE';
      NO_DIR_CHECK='TRUE';
      ALLOW_CONNECT='TRUE';
    'VSS_AK10':
      PIN_NUMBER='(0,0,0,0,0,0,0,0,0,0,0,0,0,0,0,0,0,0,0,0,0,0,0,0,0,0,0,0,0,0,AK10,0,0,0,0,0,0,0,0,0)';
      PINUSE='POWER';
      NO_LOAD_CHECK='Both';
      NO_IO_CHECK='Both';
      NO_ASSERT_CHECK='TRUE';
      NO_DIR_CHECK='TRUE';
      ALLOW_CONNECT='TRUE';
    'VSS_AK12':
      PIN_NUMBER='(0,0,0,0,0,0,0,0,0,0,0,0,0,0,0,0,0,0,0,0,0,0,0,0,0,0,0,0,0,0,AK12,0,0,0,0,0,0,0,0,0)';
      PINUSE='POWER';
      NO_LOAD_CHECK='Both';
      NO_IO_CHECK='Both';
      NO_ASSERT_CHECK='TRUE';
      NO_DIR_CHECK='TRUE';
      ALLOW_CONNECT='TRUE';
    'VSS_AK15':
      PIN_NUMBER='(0,0,0,0,0,0,0,0,0,0,0,0,0,0,0,0,0,0,0,0,0,0,0,0,0,0,0,0,0,0,AK15,0,0,0,0,0,0,0,0,0)';
      PINUSE='POWER';
      NO_LOAD_CHECK='Both';
      NO_IO_CHECK='Both';
      NO_ASSERT_CHECK='TRUE';
      NO_DIR_CHECK='TRUE';
      ALLOW_CONNECT='TRUE';
    'VSS_AK17':
      PIN_NUMBER='(0,0,0,0,0,0,0,0,0,0,0,0,0,0,0,0,0,0,0,0,0,0,0,0,0,0,0,0,0,0,AK17,0,0,0,0,0,0,0,0,0)';
      PINUSE='POWER';
      NO_LOAD_CHECK='Both';
      NO_IO_CHECK='Both';
      NO_ASSERT_CHECK='TRUE';
      NO_DIR_CHECK='TRUE';
      ALLOW_CONNECT='TRUE';
    'VSS_AK19':
      PIN_NUMBER='(0,0,0,0,0,0,0,0,0,0,0,0,0,0,0,0,0,0,0,0,0,0,0,0,0,0,0,0,0,0,AK19,0,0,0,0,0,0,0,0,0)';
      PINUSE='POWER';
      NO_LOAD_CHECK='Both';
      NO_IO_CHECK='Both';
      NO_ASSERT_CHECK='TRUE';
      NO_DIR_CHECK='TRUE';
      ALLOW_CONNECT='TRUE';
    'VSS_AK22':
      PIN_NUMBER='(0,0,0,0,0,0,0,0,0,0,0,0,0,0,0,0,0,0,0,0,0,0,0,0,0,0,0,0,0,0,AK22,0,0,0,0,0,0,0,0,0)';
      PINUSE='POWER';
      NO_LOAD_CHECK='Both';
      NO_IO_CHECK='Both';
      NO_ASSERT_CHECK='TRUE';
      NO_DIR_CHECK='TRUE';
      ALLOW_CONNECT='TRUE';
    'VSS_AK25':
      PIN_NUMBER='(0,0,0,0,0,0,0,0,0,0,0,0,0,0,0,0,0,0,0,0,0,0,0,0,0,0,0,0,0,0,AK25,0,0,0,0,0,0,0,0,0)';
      PINUSE='POWER';
      NO_LOAD_CHECK='Both';
      NO_IO_CHECK='Both';
      NO_ASSERT_CHECK='TRUE';
      NO_DIR_CHECK='TRUE';
      ALLOW_CONNECT='TRUE';
    'VSS_AK28':
      PIN_NUMBER='(0,0,0,0,0,0,0,0,0,0,0,0,0,0,0,0,0,0,0,0,0,0,0,0,0,0,0,0,0,0,AK28,0,0,0,0,0,0,0,0,0)';
      PINUSE='POWER';
      NO_LOAD_CHECK='Both';
      NO_IO_CHECK='Both';
      NO_ASSERT_CHECK='TRUE';
      NO_DIR_CHECK='TRUE';
      ALLOW_CONNECT='TRUE';
    'VSS_AK31':
      PIN_NUMBER='(0,0,0,0,0,0,0,0,0,0,0,0,0,0,0,0,0,0,0,0,0,0,0,0,0,0,0,0,0,0,AK31,0,0,0,0,0,0,0,0,0)';
      PINUSE='POWER';
      NO_LOAD_CHECK='Both';
      NO_IO_CHECK='Both';
      NO_ASSERT_CHECK='TRUE';
      NO_DIR_CHECK='TRUE';
      ALLOW_CONNECT='TRUE';
    'VSS_AK34':
      PIN_NUMBER='(0,0,0,0,0,0,0,0,0,0,0,0,0,0,0,0,0,0,0,0,0,0,0,0,0,0,0,0,0,0,AK34,0,0,0,0,0,0,0,0,0)';
      PINUSE='POWER';
      NO_LOAD_CHECK='Both';
      NO_IO_CHECK='Both';
      NO_ASSERT_CHECK='TRUE';
      NO_DIR_CHECK='TRUE';
      ALLOW_CONNECT='TRUE';
    'VSS_AK37':
      PIN_NUMBER='(0,0,0,0,0,0,0,0,0,0,0,0,0,0,0,0,0,0,0,0,0,0,0,0,0,0,0,0,0,0,AK37,0,0,0,0,0,0,0,0,0)';
      PINUSE='POWER';
      NO_LOAD_CHECK='Both';
      NO_IO_CHECK='Both';
      NO_ASSERT_CHECK='TRUE';
      NO_DIR_CHECK='TRUE';
      ALLOW_CONNECT='TRUE';
    'VSS_AK39':
      PIN_NUMBER='(0,0,0,0,0,0,0,0,0,0,0,0,0,0,0,0,0,0,0,0,0,0,0,0,0,0,0,0,0,0,AK39,0,0,0,0,0,0,0,0,0)';
      PINUSE='POWER';
      NO_LOAD_CHECK='Both';
      NO_IO_CHECK='Both';
      NO_ASSERT_CHECK='TRUE';
      NO_DIR_CHECK='TRUE';
      ALLOW_CONNECT='TRUE';
    'VSS_AK42':
      PIN_NUMBER='(0,0,0,0,0,0,0,0,0,0,0,0,0,0,0,0,0,0,0,0,0,0,0,0,0,0,0,0,0,0,AK42,0,0,0,0,0,0,0,0,0)';
      PINUSE='POWER';
      NO_LOAD_CHECK='Both';
      NO_IO_CHECK='Both';
      NO_ASSERT_CHECK='TRUE';
      NO_DIR_CHECK='TRUE';
      ALLOW_CONNECT='TRUE';
    'VSS_AK45':
      PIN_NUMBER='(0,0,0,0,0,0,0,0,0,0,0,0,0,0,0,0,0,0,0,0,0,0,0,0,0,0,0,0,0,0,AK45,0,0,0,0,0,0,0,0,0)';
      PINUSE='POWER';
      NO_LOAD_CHECK='Both';
      NO_IO_CHECK='Both';
      NO_ASSERT_CHECK='TRUE';
      NO_DIR_CHECK='TRUE';
      ALLOW_CONNECT='TRUE';
    'VSS_AK48':
      PIN_NUMBER='(0,0,0,0,0,0,0,0,0,0,0,0,0,0,0,0,0,0,0,0,0,0,0,0,0,0,0,0,0,0,AK48,0,0,0,0,0,0,0,0,0)';
      PINUSE='POWER';
      NO_LOAD_CHECK='Both';
      NO_IO_CHECK='Both';
      NO_ASSERT_CHECK='TRUE';
      NO_DIR_CHECK='TRUE';
      ALLOW_CONNECT='TRUE';
    'VSS_AK51':
      PIN_NUMBER='(0,0,0,0,0,0,0,0,0,0,0,0,0,0,0,0,0,0,0,0,0,0,0,0,0,0,0,0,0,0,AK51,0,0,0,0,0,0,0,0,0)';
      PINUSE='POWER';
      NO_LOAD_CHECK='Both';
      NO_IO_CHECK='Both';
      NO_ASSERT_CHECK='TRUE';
      NO_DIR_CHECK='TRUE';
      ALLOW_CONNECT='TRUE';
    'VSS_AK54':
      PIN_NUMBER='(0,0,0,0,0,0,0,0,0,0,0,0,0,0,0,0,0,0,0,0,0,0,0,0,0,0,0,0,0,0,AK54,0,0,0,0,0,0,0,0,0)';
      PINUSE='POWER';
      NO_LOAD_CHECK='Both';
      NO_IO_CHECK='Both';
      NO_ASSERT_CHECK='TRUE';
      NO_DIR_CHECK='TRUE';
      ALLOW_CONNECT='TRUE';
    'VSS_AK57':
      PIN_NUMBER='(0,0,0,0,0,0,0,0,0,0,0,0,0,0,0,0,0,0,0,0,0,0,0,0,0,0,0,0,0,0,AK57,0,0,0,0,0,0,0,0,0)';
      PINUSE='POWER';
      NO_LOAD_CHECK='Both';
      NO_IO_CHECK='Both';
      NO_ASSERT_CHECK='TRUE';
      NO_DIR_CHECK='TRUE';
      ALLOW_CONNECT='TRUE';
    'VSS_AK59':
      PIN_NUMBER='(0,0,0,0,0,0,0,0,0,0,0,0,0,0,0,0,0,0,0,0,0,0,0,0,0,0,0,0,0,0,AK59,0,0,0,0,0,0,0,0,0)';
      PINUSE='POWER';
      NO_LOAD_CHECK='Both';
      NO_IO_CHECK='Both';
      NO_ASSERT_CHECK='TRUE';
      NO_DIR_CHECK='TRUE';
      ALLOW_CONNECT='TRUE';
    'VSS_AK61':
      PIN_NUMBER='(0,0,0,0,0,0,0,0,0,0,0,0,0,0,0,0,0,0,0,0,0,0,0,0,0,0,0,0,0,0,AK61,0,0,0,0,0,0,0,0,0)';
      PINUSE='POWER';
      NO_LOAD_CHECK='Both';
      NO_IO_CHECK='Both';
      NO_ASSERT_CHECK='TRUE';
      NO_DIR_CHECK='TRUE';
      ALLOW_CONNECT='TRUE';
    'VSS_AK64':
      PIN_NUMBER='(0,0,0,0,0,0,0,0,0,0,0,0,0,0,0,0,0,0,0,0,0,0,0,0,0,0,0,0,0,0,AK64,0,0,0,0,0,0,0,0,0)';
      PINUSE='POWER';
      NO_LOAD_CHECK='Both';
      NO_IO_CHECK='Both';
      NO_ASSERT_CHECK='TRUE';
      NO_DIR_CHECK='TRUE';
      ALLOW_CONNECT='TRUE';
    'VSS_AK66':
      PIN_NUMBER='(0,0,0,0,0,0,0,0,0,0,0,0,0,0,0,0,0,0,0,0,0,0,0,0,0,0,0,0,0,0,AK66,0,0,0,0,0,0,0,0,0)';
      PINUSE='POWER';
      NO_LOAD_CHECK='Both';
      NO_IO_CHECK='Both';
      NO_ASSERT_CHECK='TRUE';
      NO_DIR_CHECK='TRUE';
      ALLOW_CONNECT='TRUE';
    'VSS_AK68':
      PIN_NUMBER='(0,0,0,0,0,0,0,0,0,0,0,0,0,0,0,0,0,0,0,0,0,0,0,0,0,0,0,0,0,0,AK68,0,0,0,0,0,0,0,0,0)';
      PINUSE='POWER';
      NO_LOAD_CHECK='Both';
      NO_IO_CHECK='Both';
      NO_ASSERT_CHECK='TRUE';
      NO_DIR_CHECK='TRUE';
      ALLOW_CONNECT='TRUE';
    'VSS_AK71':
      PIN_NUMBER='(0,0,0,0,0,0,0,0,0,0,0,0,0,0,0,0,0,0,0,0,0,0,0,0,0,0,0,0,0,0,AK71,0,0,0,0,0,0,0,0,0)';
      PINUSE='POWER';
      NO_LOAD_CHECK='Both';
      NO_IO_CHECK='Both';
      NO_ASSERT_CHECK='TRUE';
      NO_DIR_CHECK='TRUE';
      ALLOW_CONNECT='TRUE';
    'VSS_AK73':
      PIN_NUMBER='(0,0,0,0,0,0,0,0,0,0,0,0,0,0,0,0,0,0,0,0,0,0,0,0,0,0,0,0,0,0,AK73,0,0,0,0,0,0,0,0,0)';
      PINUSE='POWER';
      NO_LOAD_CHECK='Both';
      NO_IO_CHECK='Both';
      NO_ASSERT_CHECK='TRUE';
      NO_DIR_CHECK='TRUE';
      ALLOW_CONNECT='TRUE';
    'VSS_AL1':
      PIN_NUMBER='(0,0,0,0,0,0,0,0,0,0,0,0,0,0,0,0,0,0,0,0,0,0,0,0,0,0,0,0,0,0,AL1,0,0,0,0,0,0,0,0,0)';
      PINUSE='POWER';
      NO_LOAD_CHECK='Both';
      NO_IO_CHECK='Both';
      NO_ASSERT_CHECK='TRUE';
      NO_DIR_CHECK='TRUE';
      ALLOW_CONNECT='TRUE';
    'VSS_AL4':
      PIN_NUMBER='(0,0,0,0,0,0,0,0,0,0,0,0,0,0,0,0,0,0,0,0,0,0,0,0,0,0,0,0,0,0,AL4,0,0,0,0,0,0,0,0,0)';
      PINUSE='POWER';
      NO_LOAD_CHECK='Both';
      NO_IO_CHECK='Both';
      NO_ASSERT_CHECK='TRUE';
      NO_DIR_CHECK='TRUE';
      ALLOW_CONNECT='TRUE';
    'VSS_AL6':
      PIN_NUMBER='(0,0,0,0,0,0,0,0,0,0,0,0,0,0,0,0,0,0,0,0,0,0,0,0,0,0,0,0,0,0,AL6,0,0,0,0,0,0,0,0,0)';
      PINUSE='POWER';
      NO_LOAD_CHECK='Both';
      NO_IO_CHECK='Both';
      NO_ASSERT_CHECK='TRUE';
      NO_DIR_CHECK='TRUE';
      ALLOW_CONNECT='TRUE';
    'VSS_AL8':
      PIN_NUMBER='(0,0,0,0,0,0,0,0,0,0,0,0,0,0,0,0,0,0,0,0,0,0,0,0,0,0,0,0,0,0,AL8,0,0,0,0,0,0,0,0,0)';
      PINUSE='POWER';
      NO_LOAD_CHECK='Both';
      NO_IO_CHECK='Both';
      NO_ASSERT_CHECK='TRUE';
      NO_DIR_CHECK='TRUE';
      ALLOW_CONNECT='TRUE';
    'VSS_AL11':
      PIN_NUMBER='(0,0,0,0,0,0,0,0,0,0,0,0,0,0,0,0,0,0,0,0,0,0,0,0,0,0,0,0,0,0,AL11,0,0,0,0,0,0,0,0,0)';
      PINUSE='POWER';
      NO_LOAD_CHECK='Both';
      NO_IO_CHECK='Both';
      NO_ASSERT_CHECK='TRUE';
      NO_DIR_CHECK='TRUE';
      ALLOW_CONNECT='TRUE';
    'VSS_AL13':
      PIN_NUMBER='(0,0,0,0,0,0,0,0,0,0,0,0,0,0,0,0,0,0,0,0,0,0,0,0,0,0,0,0,0,0,AL13,0,0,0,0,0,0,0,0,0)';
      PINUSE='POWER';
      NO_LOAD_CHECK='Both';
      NO_IO_CHECK='Both';
      NO_ASSERT_CHECK='TRUE';
      NO_DIR_CHECK='TRUE';
      ALLOW_CONNECT='TRUE';
    'VSS_AL15':
      PIN_NUMBER='(0,0,0,0,0,0,0,0,0,0,0,0,0,0,0,0,0,0,0,0,0,0,0,0,0,0,0,0,0,0,AL15,0,0,0,0,0,0,0,0,0)';
      PINUSE='POWER';
      NO_LOAD_CHECK='Both';
      NO_IO_CHECK='Both';
      NO_ASSERT_CHECK='TRUE';
      NO_DIR_CHECK='TRUE';
      ALLOW_CONNECT='TRUE';
    'VSS_AL18':
      PIN_NUMBER='(0,0,0,0,0,0,0,0,0,0,0,0,0,0,0,0,0,0,0,0,0,0,0,0,0,0,0,0,0,0,AL18,0,0,0,0,0,0,0,0,0)';
      PINUSE='POWER';
      NO_LOAD_CHECK='Both';
      NO_IO_CHECK='Both';
      NO_ASSERT_CHECK='TRUE';
      NO_DIR_CHECK='TRUE';
      ALLOW_CONNECT='TRUE';
    'VSS_AL20':
      PIN_NUMBER='(0,0,0,0,0,0,0,0,0,0,0,0,0,0,0,0,0,0,0,0,0,0,0,0,0,0,0,0,0,0,AL20,0,0,0,0,0,0,0,0,0)';
      PINUSE='POWER';
      NO_LOAD_CHECK='Both';
      NO_IO_CHECK='Both';
      NO_ASSERT_CHECK='TRUE';
      NO_DIR_CHECK='TRUE';
      ALLOW_CONNECT='TRUE';
    'VSS_AL22':
      PIN_NUMBER='(0,0,0,0,0,0,0,0,0,0,0,0,0,0,0,0,0,0,0,0,0,0,0,0,0,0,0,0,0,0,AL22,0,0,0,0,0,0,0,0,0)';
      PINUSE='POWER';
      NO_LOAD_CHECK='Both';
      NO_IO_CHECK='Both';
      NO_ASSERT_CHECK='TRUE';
      NO_DIR_CHECK='TRUE';
      ALLOW_CONNECT='TRUE';
    'VSS_AL25':
      PIN_NUMBER='(0,0,0,0,0,0,0,0,0,0,0,0,0,0,0,0,0,0,0,0,0,0,0,0,0,0,0,0,0,0,AL25,0,0,0,0,0,0,0,0,0)';
      PINUSE='POWER';
      NO_LOAD_CHECK='Both';
      NO_IO_CHECK='Both';
      NO_ASSERT_CHECK='TRUE';
      NO_DIR_CHECK='TRUE';
      ALLOW_CONNECT='TRUE';
    'VSS_AL28':
      PIN_NUMBER='(0,0,0,0,0,0,0,0,0,0,0,0,0,0,0,0,0,0,0,0,0,0,0,0,0,0,0,0,0,0,AL28,0,0,0,0,0,0,0,0,0)';
      PINUSE='POWER';
      NO_LOAD_CHECK='Both';
      NO_IO_CHECK='Both';
      NO_ASSERT_CHECK='TRUE';
      NO_DIR_CHECK='TRUE';
      ALLOW_CONNECT='TRUE';
    'VSS_AL31':
      PIN_NUMBER='(0,0,0,0,0,0,0,0,0,0,0,0,0,0,0,0,0,0,0,0,0,0,0,0,0,0,0,0,0,0,AL31,0,0,0,0,0,0,0,0,0)';
      PINUSE='POWER';
      NO_LOAD_CHECK='Both';
      NO_IO_CHECK='Both';
      NO_ASSERT_CHECK='TRUE';
      NO_DIR_CHECK='TRUE';
      ALLOW_CONNECT='TRUE';
    'VSS_AL34':
      PIN_NUMBER='(0,0,0,0,0,0,0,0,0,0,0,0,0,0,0,0,0,0,0,0,0,0,0,0,0,0,0,0,0,0,AL34,0,0,0,0,0,0,0,0,0)';
      PINUSE='POWER';
      NO_LOAD_CHECK='Both';
      NO_IO_CHECK='Both';
      NO_ASSERT_CHECK='TRUE';
      NO_DIR_CHECK='TRUE';
      ALLOW_CONNECT='TRUE';
    'VSS_AL42':
      PIN_NUMBER='(0,0,0,0,0,0,0,0,0,0,0,0,0,0,0,0,0,0,0,0,0,0,0,0,0,0,0,0,0,0,AL42,0,0,0,0,0,0,0,0,0)';
      PINUSE='POWER';
      NO_LOAD_CHECK='Both';
      NO_IO_CHECK='Both';
      NO_ASSERT_CHECK='TRUE';
      NO_DIR_CHECK='TRUE';
      ALLOW_CONNECT='TRUE';
    'VSS_AL45':
      PIN_NUMBER='(0,0,0,0,0,0,0,0,0,0,0,0,0,0,0,0,0,0,0,0,0,0,0,0,0,0,0,0,0,0,AL45,0,0,0,0,0,0,0,0,0)';
      PINUSE='POWER';
      NO_LOAD_CHECK='Both';
      NO_IO_CHECK='Both';
      NO_ASSERT_CHECK='TRUE';
      NO_DIR_CHECK='TRUE';
      ALLOW_CONNECT='TRUE';
    'VSS_AL48':
      PIN_NUMBER='(0,0,0,0,0,0,0,0,0,0,0,0,0,0,0,0,0,0,0,0,0,0,0,0,0,0,0,0,0,0,AL48,0,0,0,0,0,0,0,0,0)';
      PINUSE='POWER';
      NO_LOAD_CHECK='Both';
      NO_IO_CHECK='Both';
      NO_ASSERT_CHECK='TRUE';
      NO_DIR_CHECK='TRUE';
      ALLOW_CONNECT='TRUE';
    'VSS_AL51':
      PIN_NUMBER='(0,0,0,0,0,0,0,0,0,0,0,0,0,0,0,0,0,0,0,0,0,0,0,0,0,0,0,0,0,0,AL51,0,0,0,0,0,0,0,0,0)';
      PINUSE='POWER';
      NO_LOAD_CHECK='Both';
      NO_IO_CHECK='Both';
      NO_ASSERT_CHECK='TRUE';
      NO_DIR_CHECK='TRUE';
      ALLOW_CONNECT='TRUE';
    'VSS_AL54':
      PIN_NUMBER='(0,0,0,0,0,0,0,0,0,0,0,0,0,0,0,0,0,0,0,0,0,0,0,0,0,0,0,0,0,0,AL54,0,0,0,0,0,0,0,0,0)';
      PINUSE='POWER';
      NO_LOAD_CHECK='Both';
      NO_IO_CHECK='Both';
      NO_ASSERT_CHECK='TRUE';
      NO_DIR_CHECK='TRUE';
      ALLOW_CONNECT='TRUE';
    'VSS_AL56':
      PIN_NUMBER='(0,0,0,0,0,0,0,0,0,0,0,0,0,0,0,0,0,0,0,0,0,0,0,0,0,0,0,0,0,0,AL56,0,0,0,0,0,0,0,0,0)';
      PINUSE='POWER';
      NO_LOAD_CHECK='Both';
      NO_IO_CHECK='Both';
      NO_ASSERT_CHECK='TRUE';
      NO_DIR_CHECK='TRUE';
      ALLOW_CONNECT='TRUE';
    'VSS_AL58':
      PIN_NUMBER='(0,0,0,0,0,0,0,0,0,0,0,0,0,0,0,0,0,0,0,0,0,0,0,0,0,0,0,0,0,0,AL58,0,0,0,0,0,0,0,0,0)';
      PINUSE='POWER';
      NO_LOAD_CHECK='Both';
      NO_IO_CHECK='Both';
      NO_ASSERT_CHECK='TRUE';
      NO_DIR_CHECK='TRUE';
      ALLOW_CONNECT='TRUE';
    'VSS_AL61':
      PIN_NUMBER='(0,0,0,0,0,0,0,0,0,0,0,0,0,0,0,0,0,0,0,0,0,0,0,0,0,0,0,0,0,0,AL61,0,0,0,0,0,0,0,0,0)';
      PINUSE='POWER';
      NO_LOAD_CHECK='Both';
      NO_IO_CHECK='Both';
      NO_ASSERT_CHECK='TRUE';
      NO_DIR_CHECK='TRUE';
      ALLOW_CONNECT='TRUE';
    'VSS_AL63':
      PIN_NUMBER='(0,0,0,0,0,0,0,0,0,0,0,0,0,0,0,0,0,0,0,0,0,0,0,0,0,0,0,0,0,0,AL63,0,0,0,0,0,0,0,0,0)';
      PINUSE='POWER';
      NO_LOAD_CHECK='Both';
      NO_IO_CHECK='Both';
      NO_ASSERT_CHECK='TRUE';
      NO_DIR_CHECK='TRUE';
      ALLOW_CONNECT='TRUE';
    'VSS_AL65':
      PIN_NUMBER='(0,0,0,0,0,0,0,0,0,0,0,0,0,0,0,0,0,0,0,0,0,0,0,0,0,0,0,0,0,0,AL65,0,0,0,0,0,0,0,0,0)';
      PINUSE='POWER';
      NO_LOAD_CHECK='Both';
      NO_IO_CHECK='Both';
      NO_ASSERT_CHECK='TRUE';
      NO_DIR_CHECK='TRUE';
      ALLOW_CONNECT='TRUE';
    'VSS_AL68':
      PIN_NUMBER='(0,0,0,0,0,0,0,0,0,0,0,0,0,0,0,0,0,0,0,0,0,0,0,0,0,0,0,0,0,0,AL68,0,0,0,0,0,0,0,0,0)';
      PINUSE='POWER';
      NO_LOAD_CHECK='Both';
      NO_IO_CHECK='Both';
      NO_ASSERT_CHECK='TRUE';
      NO_DIR_CHECK='TRUE';
      ALLOW_CONNECT='TRUE';
    'VSS_AL70':
      PIN_NUMBER='(0,0,0,0,0,0,0,0,0,0,0,0,0,0,0,0,0,0,0,0,0,0,0,0,0,0,0,0,0,0,AL70,0,0,0,0,0,0,0,0,0)';
      PINUSE='POWER';
      NO_LOAD_CHECK='Both';
      NO_IO_CHECK='Both';
      NO_ASSERT_CHECK='TRUE';
      NO_DIR_CHECK='TRUE';
      ALLOW_CONNECT='TRUE';
    'VSS_AL72':
      PIN_NUMBER='(0,0,0,0,0,0,0,0,0,0,0,0,0,0,0,0,0,0,0,0,0,0,0,0,0,0,0,0,0,0,AL72,0,0,0,0,0,0,0,0,0)';
      PINUSE='POWER';
      NO_LOAD_CHECK='Both';
      NO_IO_CHECK='Both';
      NO_ASSERT_CHECK='TRUE';
      NO_DIR_CHECK='TRUE';
      ALLOW_CONNECT='TRUE';
    'VSS_AL75':
      PIN_NUMBER='(0,0,0,0,0,0,0,0,0,0,0,0,0,0,0,0,0,0,0,0,0,0,0,0,0,0,0,0,0,0,AL75,0,0,0,0,0,0,0,0,0)';
      PINUSE='POWER';
      NO_LOAD_CHECK='Both';
      NO_IO_CHECK='Both';
      NO_ASSERT_CHECK='TRUE';
      NO_DIR_CHECK='TRUE';
      ALLOW_CONNECT='TRUE';
    'VSS_AM3':
      PIN_NUMBER='(0,0,0,0,0,0,0,0,0,0,0,0,0,0,0,0,0,0,0,0,0,0,0,0,0,0,0,0,0,0,AM3,0,0,0,0,0,0,0,0,0)';
      PINUSE='POWER';
      NO_LOAD_CHECK='Both';
      NO_IO_CHECK='Both';
      NO_ASSERT_CHECK='TRUE';
      NO_DIR_CHECK='TRUE';
      ALLOW_CONNECT='TRUE';
    'VSS_AM8':
      PIN_NUMBER='(0,0,0,0,0,0,0,0,0,0,0,0,0,0,0,0,0,0,0,0,0,0,0,0,0,0,0,0,0,0,AM8,0,0,0,0,0,0,0,0,0)';
      PINUSE='POWER';
      NO_LOAD_CHECK='Both';
      NO_IO_CHECK='Both';
      NO_ASSERT_CHECK='TRUE';
      NO_DIR_CHECK='TRUE';
      ALLOW_CONNECT='TRUE';
    'VSS_AM10':
      PIN_NUMBER='(0,0,0,0,0,0,0,0,0,0,0,0,0,0,0,0,0,0,0,0,0,0,0,0,0,0,0,0,0,0,AM10,0,0,0,0,0,0,0,0,0)';
      PINUSE='POWER';
      NO_LOAD_CHECK='Both';
      NO_IO_CHECK='Both';
      NO_ASSERT_CHECK='TRUE';
      NO_DIR_CHECK='TRUE';
      ALLOW_CONNECT='TRUE';
    'VSS_AM15':
      PIN_NUMBER='(0,0,0,0,0,0,0,0,0,0,0,0,0,0,0,0,0,0,0,0,0,0,0,0,0,0,0,0,0,0,AM15,0,0,0,0,0,0,0,0,0)';
      PINUSE='POWER';
      NO_LOAD_CHECK='Both';
      NO_IO_CHECK='Both';
      NO_ASSERT_CHECK='TRUE';
      NO_DIR_CHECK='TRUE';
      ALLOW_CONNECT='TRUE';
    'VSS_AM17':
      PIN_NUMBER='(0,0,0,0,0,0,0,0,0,0,0,0,0,0,0,0,0,0,0,0,0,0,0,0,0,0,0,0,0,0,AM17,0,0,0,0,0,0,0,0,0)';
      PINUSE='POWER';
      NO_LOAD_CHECK='Both';
      NO_IO_CHECK='Both';
      NO_ASSERT_CHECK='TRUE';
      NO_DIR_CHECK='TRUE';
      ALLOW_CONNECT='TRUE';
    'VSS_AM23':
      PIN_NUMBER='(0,0,0,0,0,0,0,0,0,0,0,0,0,0,0,0,0,0,0,0,0,0,0,0,0,0,0,0,0,0,AM23,0,0,0,0,0,0,0,0,0)';
      PINUSE='POWER';
      NO_LOAD_CHECK='Both';
      NO_IO_CHECK='Both';
      NO_ASSERT_CHECK='TRUE';
      NO_DIR_CHECK='TRUE';
      ALLOW_CONNECT='TRUE';
    'VSS_AM24':
      PIN_NUMBER='(0,0,0,0,0,0,0,0,0,0,0,0,0,0,0,0,0,0,0,0,0,0,0,0,0,0,0,0,0,0,AM24,0,0,0,0,0,0,0,0,0)';
      PINUSE='POWER';
      NO_LOAD_CHECK='Both';
      NO_IO_CHECK='Both';
      NO_ASSERT_CHECK='TRUE';
      NO_DIR_CHECK='TRUE';
      ALLOW_CONNECT='TRUE';
    'VSS_AM25':
      PIN_NUMBER='(0,0,0,0,0,0,0,0,0,0,0,0,0,0,0,0,0,0,0,0,0,0,0,0,0,0,0,0,0,0,AM25,0,0,0,0,0,0,0,0,0)';
      PINUSE='POWER';
      NO_LOAD_CHECK='Both';
      NO_IO_CHECK='Both';
      NO_ASSERT_CHECK='TRUE';
      NO_DIR_CHECK='TRUE';
      ALLOW_CONNECT='TRUE';
    'VSS_AM26':
      PIN_NUMBER='(0,0,0,0,0,0,0,0,0,0,0,0,0,0,0,0,0,0,0,0,0,0,0,0,0,0,0,0,0,0,AM26,0,0,0,0,0,0,0,0,0)';
      PINUSE='POWER';
      NO_LOAD_CHECK='Both';
      NO_IO_CHECK='Both';
      NO_ASSERT_CHECK='TRUE';
      NO_DIR_CHECK='TRUE';
      ALLOW_CONNECT='TRUE';
    'VSS_AM27':
      PIN_NUMBER='(0,0,0,0,0,0,0,0,0,0,0,0,0,0,0,0,0,0,0,0,0,0,0,0,0,0,0,0,0,0,AM27,0,0,0,0,0,0,0,0,0)';
      PINUSE='POWER';
      NO_LOAD_CHECK='Both';
      NO_IO_CHECK='Both';
      NO_ASSERT_CHECK='TRUE';
      NO_DIR_CHECK='TRUE';
      ALLOW_CONNECT='TRUE';
    'VSS_AM28':
      PIN_NUMBER='(0,0,0,0,0,0,0,0,0,0,0,0,0,0,0,0,0,0,0,0,0,0,0,0,0,0,0,0,0,0,AM28,0,0,0,0,0,0,0,0,0)';
      PINUSE='POWER';
      NO_LOAD_CHECK='Both';
      NO_IO_CHECK='Both';
      NO_ASSERT_CHECK='TRUE';
      NO_DIR_CHECK='TRUE';
      ALLOW_CONNECT='TRUE';
    'VSS_AM29':
      PIN_NUMBER='(0,0,0,0,0,0,0,0,0,0,0,0,0,0,0,0,0,0,0,0,0,0,0,0,0,0,0,0,0,0,AM29,0,0,0,0,0,0,0,0,0)';
      PINUSE='POWER';
      NO_LOAD_CHECK='Both';
      NO_IO_CHECK='Both';
      NO_ASSERT_CHECK='TRUE';
      NO_DIR_CHECK='TRUE';
      ALLOW_CONNECT='TRUE';
    'VSS_AM30':
      PIN_NUMBER='(0,0,0,0,0,0,0,0,0,0,0,0,0,0,0,0,0,0,0,0,0,0,0,0,0,0,0,0,0,0,AM30,0,0,0,0,0,0,0,0,0)';
      PINUSE='POWER';
      NO_LOAD_CHECK='Both';
      NO_IO_CHECK='Both';
      NO_ASSERT_CHECK='TRUE';
      NO_DIR_CHECK='TRUE';
      ALLOW_CONNECT='TRUE';
    'VSS_AM31':
      PIN_NUMBER='(0,0,0,0,0,0,0,0,0,0,0,0,0,0,0,0,0,0,0,0,0,0,0,0,0,0,0,0,0,0,AM31,0,0,0,0,0,0,0,0,0)';
      PINUSE='POWER';
      NO_LOAD_CHECK='Both';
      NO_IO_CHECK='Both';
      NO_ASSERT_CHECK='TRUE';
      NO_DIR_CHECK='TRUE';
      ALLOW_CONNECT='TRUE';
    'VSS_AM32':
      PIN_NUMBER='(0,0,0,0,0,0,0,0,0,0,0,0,0,0,0,0,0,0,0,0,0,0,0,0,0,0,0,0,0,0,AM32,0,0,0,0,0,0,0,0,0)';
      PINUSE='POWER';
      NO_LOAD_CHECK='Both';
      NO_IO_CHECK='Both';
      NO_ASSERT_CHECK='TRUE';
      NO_DIR_CHECK='TRUE';
      ALLOW_CONNECT='TRUE';
    'VSS_AM33':
      PIN_NUMBER='(0,0,0,0,0,0,0,0,0,0,0,0,0,0,0,0,0,0,0,0,0,0,0,0,0,0,0,0,0,0,AM33,0,0,0,0,0,0,0,0,0)';
      PINUSE='POWER';
      NO_LOAD_CHECK='Both';
      NO_IO_CHECK='Both';
      NO_ASSERT_CHECK='TRUE';
      NO_DIR_CHECK='TRUE';
      ALLOW_CONNECT='TRUE';
    'VSS_AM34':
      PIN_NUMBER='(0,0,0,0,0,0,0,0,0,0,0,0,0,0,0,0,0,0,0,0,0,0,0,0,0,0,0,0,0,0,AM34,0,0,0,0,0,0,0,0,0)';
      PINUSE='POWER';
      NO_LOAD_CHECK='Both';
      NO_IO_CHECK='Both';
      NO_ASSERT_CHECK='TRUE';
      NO_DIR_CHECK='TRUE';
      ALLOW_CONNECT='TRUE';
    'VSS_AM39':
      PIN_NUMBER='(0,0,0,0,0,0,0,0,0,0,0,0,0,0,0,0,0,0,0,0,0,0,0,0,0,0,0,0,0,0,AM39,0,0,0,0,0,0,0,0,0)';
      PINUSE='POWER';
      NO_LOAD_CHECK='Both';
      NO_IO_CHECK='Both';
      NO_ASSERT_CHECK='TRUE';
      NO_DIR_CHECK='TRUE';
      ALLOW_CONNECT='TRUE';
    'VSS_AD49':
      PIN_NUMBER='(0,0,0,0,0,0,0,0,0,0,0,0,0,0,0,0,0,0,0,0,0,0,0,0,0,0,0,0,0,0,AD49,0,0,0,0,0,0,0,0,0)';
      PINUSE='POWER';
      NO_LOAD_CHECK='Both';
      NO_IO_CHECK='Both';
      NO_ASSERT_CHECK='TRUE';
      NO_DIR_CHECK='TRUE';
      ALLOW_CONNECT='TRUE';
    'VSS_AD50':
      PIN_NUMBER='(0,0,0,0,0,0,0,0,0,0,0,0,0,0,0,0,0,0,0,0,0,0,0,0,0,0,0,0,0,0,AD50,0,0,0,0,0,0,0,0,0)';
      PINUSE='POWER';
      NO_LOAD_CHECK='Both';
      NO_IO_CHECK='Both';
      NO_ASSERT_CHECK='TRUE';
      NO_DIR_CHECK='TRUE';
      ALLOW_CONNECT='TRUE';
    'VSS_AD51':
      PIN_NUMBER='(0,0,0,0,0,0,0,0,0,0,0,0,0,0,0,0,0,0,0,0,0,0,0,0,0,0,0,0,0,0,AD51,0,0,0,0,0,0,0,0,0)';
      PINUSE='POWER';
      NO_LOAD_CHECK='Both';
      NO_IO_CHECK='Both';
      NO_ASSERT_CHECK='TRUE';
      NO_DIR_CHECK='TRUE';
      ALLOW_CONNECT='TRUE';
    'VSS_AD52':
      PIN_NUMBER='(0,0,0,0,0,0,0,0,0,0,0,0,0,0,0,0,0,0,0,0,0,0,0,0,0,0,0,0,0,0,AD52,0,0,0,0,0,0,0,0,0)';
      PINUSE='POWER';
      NO_LOAD_CHECK='Both';
      NO_IO_CHECK='Both';
      NO_ASSERT_CHECK='TRUE';
      NO_DIR_CHECK='TRUE';
      ALLOW_CONNECT='TRUE';
    'VSS_AD53':
      PIN_NUMBER='(0,0,0,0,0,0,0,0,0,0,0,0,0,0,0,0,0,0,0,0,0,0,0,0,0,0,0,0,0,0,AD53,0,0,0,0,0,0,0,0,0)';
      PINUSE='POWER';
      NO_LOAD_CHECK='Both';
      NO_IO_CHECK='Both';
      NO_ASSERT_CHECK='TRUE';
      NO_DIR_CHECK='TRUE';
      ALLOW_CONNECT='TRUE';
    'VSS_AD57':
      PIN_NUMBER='(0,0,0,0,0,0,0,0,0,0,0,0,0,0,0,0,0,0,0,0,0,0,0,0,0,0,0,0,0,0,AD57,0,0,0,0,0,0,0,0,0)';
      PINUSE='POWER';
      NO_LOAD_CHECK='Both';
      NO_IO_CHECK='Both';
      NO_ASSERT_CHECK='TRUE';
      NO_DIR_CHECK='TRUE';
      ALLOW_CONNECT='TRUE';
    'VSS_AD59':
      PIN_NUMBER='(0,0,0,0,0,0,0,0,0,0,0,0,0,0,0,0,0,0,0,0,0,0,0,0,0,0,0,0,0,0,AD59,0,0,0,0,0,0,0,0,0)';
      PINUSE='POWER';
      NO_LOAD_CHECK='Both';
      NO_IO_CHECK='Both';
      NO_ASSERT_CHECK='TRUE';
      NO_DIR_CHECK='TRUE';
      ALLOW_CONNECT='TRUE';
    'VSS_AD61':
      PIN_NUMBER='(0,0,0,0,0,0,0,0,0,0,0,0,0,0,0,0,0,0,0,0,0,0,0,0,0,0,0,0,0,0,AD61,0,0,0,0,0,0,0,0,0)';
      PINUSE='POWER';
      NO_LOAD_CHECK='Both';
      NO_IO_CHECK='Both';
      NO_ASSERT_CHECK='TRUE';
      NO_DIR_CHECK='TRUE';
      ALLOW_CONNECT='TRUE';
    'VSS_AD64':
      PIN_NUMBER='(0,0,0,0,0,0,0,0,0,0,0,0,0,0,0,0,0,0,0,0,0,0,0,0,0,0,0,0,0,0,AD64,0,0,0,0,0,0,0,0,0)';
      PINUSE='POWER';
      NO_LOAD_CHECK='Both';
      NO_IO_CHECK='Both';
      NO_ASSERT_CHECK='TRUE';
      NO_DIR_CHECK='TRUE';
      ALLOW_CONNECT='TRUE';
    'VSS_AD66':
      PIN_NUMBER='(0,0,0,0,0,0,0,0,0,0,0,0,0,0,0,0,0,0,0,0,0,0,0,0,0,0,0,0,0,0,AD66,0,0,0,0,0,0,0,0,0)';
      PINUSE='POWER';
      NO_LOAD_CHECK='Both';
      NO_IO_CHECK='Both';
      NO_ASSERT_CHECK='TRUE';
      NO_DIR_CHECK='TRUE';
      ALLOW_CONNECT='TRUE';
    'VSS_AD68':
      PIN_NUMBER='(0,0,0,0,0,0,0,0,0,0,0,0,0,0,0,0,0,0,0,0,0,0,0,0,0,0,0,0,0,0,AD68,0,0,0,0,0,0,0,0,0)';
      PINUSE='POWER';
      NO_LOAD_CHECK='Both';
      NO_IO_CHECK='Both';
      NO_ASSERT_CHECK='TRUE';
      NO_DIR_CHECK='TRUE';
      ALLOW_CONNECT='TRUE';
    'VSS_AD71':
      PIN_NUMBER='(0,0,0,0,0,0,0,0,0,0,0,0,0,0,0,0,0,0,0,0,0,0,0,0,0,0,0,0,0,0,AD71,0,0,0,0,0,0,0,0,0)';
      PINUSE='POWER';
      NO_LOAD_CHECK='Both';
      NO_IO_CHECK='Both';
      NO_ASSERT_CHECK='TRUE';
      NO_DIR_CHECK='TRUE';
      ALLOW_CONNECT='TRUE';
    'VSS_AD73':
      PIN_NUMBER='(0,0,0,0,0,0,0,0,0,0,0,0,0,0,0,0,0,0,0,0,0,0,0,0,0,0,0,0,0,0,AD73,0,0,0,0,0,0,0,0,0)';
      PINUSE='POWER';
      NO_LOAD_CHECK='Both';
      NO_IO_CHECK='Both';
      NO_ASSERT_CHECK='TRUE';
      NO_DIR_CHECK='TRUE';
      ALLOW_CONNECT='TRUE';
    'VSS_AE1':
      PIN_NUMBER='(0,0,0,0,0,0,0,0,0,0,0,0,0,0,0,0,0,0,0,0,0,0,0,0,0,0,0,0,0,0,AE1,0,0,0,0,0,0,0,0,0)';
      PINUSE='POWER';
      NO_LOAD_CHECK='Both';
      NO_IO_CHECK='Both';
      NO_ASSERT_CHECK='TRUE';
      NO_DIR_CHECK='TRUE';
      ALLOW_CONNECT='TRUE';
    'VSS_AE6':
      PIN_NUMBER='(0,0,0,0,0,0,0,0,0,0,0,0,0,0,0,0,0,0,0,0,0,0,0,0,0,0,0,0,0,0,AE6,0,0,0,0,0,0,0,0,0)';
      PINUSE='POWER';
      NO_LOAD_CHECK='Both';
      NO_IO_CHECK='Both';
      NO_ASSERT_CHECK='TRUE';
      NO_DIR_CHECK='TRUE';
      ALLOW_CONNECT='TRUE';
    'VSS_AE8':
      PIN_NUMBER='(0,0,0,0,0,0,0,0,0,0,0,0,0,0,0,0,0,0,0,0,0,0,0,0,0,0,0,0,0,0,AE8,0,0,0,0,0,0,0,0,0)';
      PINUSE='POWER';
      NO_LOAD_CHECK='Both';
      NO_IO_CHECK='Both';
      NO_ASSERT_CHECK='TRUE';
      NO_DIR_CHECK='TRUE';
      ALLOW_CONNECT='TRUE';
    'VSS_AE11':
      PIN_NUMBER='(0,0,0,0,0,0,0,0,0,0,0,0,0,0,0,0,0,0,0,0,0,0,0,0,0,0,0,0,0,0,AE11,0,0,0,0,0,0,0,0,0)';
      PINUSE='POWER';
      NO_LOAD_CHECK='Both';
      NO_IO_CHECK='Both';
      NO_ASSERT_CHECK='TRUE';
      NO_DIR_CHECK='TRUE';
      ALLOW_CONNECT='TRUE';
    'VSS_AE13':
      PIN_NUMBER='(0,0,0,0,0,0,0,0,0,0,0,0,0,0,0,0,0,0,0,0,0,0,0,0,0,0,0,0,0,0,AE13,0,0,0,0,0,0,0,0,0)';
      PINUSE='POWER';
      NO_LOAD_CHECK='Both';
      NO_IO_CHECK='Both';
      NO_ASSERT_CHECK='TRUE';
      NO_DIR_CHECK='TRUE';
      ALLOW_CONNECT='TRUE';
    'VSS_AE15':
      PIN_NUMBER='(0,0,0,0,0,0,0,0,0,0,0,0,0,0,0,0,0,0,0,0,0,0,0,0,0,0,0,0,0,0,AE15,0,0,0,0,0,0,0,0,0)';
      PINUSE='POWER';
      NO_LOAD_CHECK='Both';
      NO_IO_CHECK='Both';
      NO_ASSERT_CHECK='TRUE';
      NO_DIR_CHECK='TRUE';
      ALLOW_CONNECT='TRUE';
    'VSS_AE18':
      PIN_NUMBER='(0,0,0,0,0,0,0,0,0,0,0,0,0,0,0,0,0,0,0,0,0,0,0,0,0,0,0,0,0,0,AE18,0,0,0,0,0,0,0,0,0)';
      PINUSE='POWER';
      NO_LOAD_CHECK='Both';
      NO_IO_CHECK='Both';
      NO_ASSERT_CHECK='TRUE';
      NO_DIR_CHECK='TRUE';
      ALLOW_CONNECT='TRUE';
    'VSS_AE20':
      PIN_NUMBER='(0,0,0,0,0,0,0,0,0,0,0,0,0,0,0,0,0,0,0,0,0,0,0,0,0,0,0,0,0,0,AE20,0,0,0,0,0,0,0,0,0)';
      PINUSE='POWER';
      NO_LOAD_CHECK='Both';
      NO_IO_CHECK='Both';
      NO_ASSERT_CHECK='TRUE';
      NO_DIR_CHECK='TRUE';
      ALLOW_CONNECT='TRUE';
    'VSS_AE22':
      PIN_NUMBER='(0,0,0,0,0,0,0,0,0,0,0,0,0,0,0,0,0,0,0,0,0,0,0,0,0,0,0,0,0,0,AE22,0,0,0,0,0,0,0,0,0)';
      PINUSE='POWER';
      NO_LOAD_CHECK='Both';
      NO_IO_CHECK='Both';
      NO_ASSERT_CHECK='TRUE';
      NO_DIR_CHECK='TRUE';
      ALLOW_CONNECT='TRUE';
    'VSS_AE25':
      PIN_NUMBER='(0,0,0,0,0,0,0,0,0,0,0,0,0,0,0,0,0,0,0,0,0,0,0,0,0,0,0,0,0,0,AE25,0,0,0,0,0,0,0,0,0)';
      PINUSE='POWER';
      NO_LOAD_CHECK='Both';
      NO_IO_CHECK='Both';
      NO_ASSERT_CHECK='TRUE';
      NO_DIR_CHECK='TRUE';
      ALLOW_CONNECT='TRUE';
    'VSS_AE28':
      PIN_NUMBER='(0,0,0,0,0,0,0,0,0,0,0,0,0,0,0,0,0,0,0,0,0,0,0,0,0,0,0,0,0,0,AE28,0,0,0,0,0,0,0,0,0)';
      PINUSE='POWER';
      NO_LOAD_CHECK='Both';
      NO_IO_CHECK='Both';
      NO_ASSERT_CHECK='TRUE';
      NO_DIR_CHECK='TRUE';
      ALLOW_CONNECT='TRUE';
    'VSS_AE31':
      PIN_NUMBER='(0,0,0,0,0,0,0,0,0,0,0,0,0,0,0,0,0,0,0,0,0,0,0,0,0,0,0,0,0,0,AE31,0,0,0,0,0,0,0,0,0)';
      PINUSE='POWER';
      NO_LOAD_CHECK='Both';
      NO_IO_CHECK='Both';
      NO_ASSERT_CHECK='TRUE';
      NO_DIR_CHECK='TRUE';
      ALLOW_CONNECT='TRUE';
    'VSS_AE34':
      PIN_NUMBER='(0,0,0,0,0,0,0,0,0,0,0,0,0,0,0,0,0,0,0,0,0,0,0,0,0,0,0,0,0,0,AE34,0,0,0,0,0,0,0,0,0)';
      PINUSE='POWER';
      NO_LOAD_CHECK='Both';
      NO_IO_CHECK='Both';
      NO_ASSERT_CHECK='TRUE';
      NO_DIR_CHECK='TRUE';
      ALLOW_CONNECT='TRUE';
    'VSS_AE35':
      PIN_NUMBER='(0,0,0,0,0,0,0,0,0,0,0,0,0,0,0,0,0,0,0,0,0,0,0,0,0,0,0,0,0,0,AE35,0,0,0,0,0,0,0,0,0)';
      PINUSE='POWER';
      NO_LOAD_CHECK='Both';
      NO_IO_CHECK='Both';
      NO_ASSERT_CHECK='TRUE';
      NO_DIR_CHECK='TRUE';
      ALLOW_CONNECT='TRUE';
    'VSS_AE36':
      PIN_NUMBER='(0,0,0,0,0,0,0,0,0,0,0,0,0,0,0,0,0,0,0,0,0,0,0,0,0,0,0,0,0,0,AE36,0,0,0,0,0,0,0,0,0)';
      PINUSE='POWER';
      NO_LOAD_CHECK='Both';
      NO_IO_CHECK='Both';
      NO_ASSERT_CHECK='TRUE';
      NO_DIR_CHECK='TRUE';
      ALLOW_CONNECT='TRUE';
    'VSS_AE40':
      PIN_NUMBER='(0,0,0,0,0,0,0,0,0,0,0,0,0,0,0,0,0,0,0,0,0,0,0,0,0,0,0,0,0,0,AE40,0,0,0,0,0,0,0,0,0)';
      PINUSE='POWER';
      NO_LOAD_CHECK='Both';
      NO_IO_CHECK='Both';
      NO_ASSERT_CHECK='TRUE';
      NO_DIR_CHECK='TRUE';
      ALLOW_CONNECT='TRUE';
    'VSS_AE41':
      PIN_NUMBER='(0,0,0,0,0,0,0,0,0,0,0,0,0,0,0,0,0,0,0,0,0,0,0,0,0,0,0,0,0,0,AE41,0,0,0,0,0,0,0,0,0)';
      PINUSE='POWER';
      NO_LOAD_CHECK='Both';
      NO_IO_CHECK='Both';
      NO_ASSERT_CHECK='TRUE';
      NO_DIR_CHECK='TRUE';
      ALLOW_CONNECT='TRUE';
    'VSS_AE42':
      PIN_NUMBER='(0,0,0,0,0,0,0,0,0,0,0,0,0,0,0,0,0,0,0,0,0,0,0,0,0,0,0,0,0,0,AE42,0,0,0,0,0,0,0,0,0)';
      PINUSE='POWER';
      NO_LOAD_CHECK='Both';
      NO_IO_CHECK='Both';
      NO_ASSERT_CHECK='TRUE';
      NO_DIR_CHECK='TRUE';
      ALLOW_CONNECT='TRUE';
    'VSS_AE45':
      PIN_NUMBER='(0,0,0,0,0,0,0,0,0,0,0,0,0,0,0,0,0,0,0,0,0,0,0,0,0,0,0,0,0,0,AE45,0,0,0,0,0,0,0,0,0)';
      PINUSE='POWER';
      NO_LOAD_CHECK='Both';
      NO_IO_CHECK='Both';
      NO_ASSERT_CHECK='TRUE';
      NO_DIR_CHECK='TRUE';
      ALLOW_CONNECT='TRUE';
    'VSS_AE48':
      PIN_NUMBER='(0,0,0,0,0,0,0,0,0,0,0,0,0,0,0,0,0,0,0,0,0,0,0,0,0,0,0,0,0,0,AE48,0,0,0,0,0,0,0,0,0)';
      PINUSE='POWER';
      NO_LOAD_CHECK='Both';
      NO_IO_CHECK='Both';
      NO_ASSERT_CHECK='TRUE';
      NO_DIR_CHECK='TRUE';
      ALLOW_CONNECT='TRUE';
    'VSS_AE51':
      PIN_NUMBER='(0,0,0,0,0,0,0,0,0,0,0,0,0,0,0,0,0,0,0,0,0,0,0,0,0,0,0,0,0,0,AE51,0,0,0,0,0,0,0,0,0)';
      PINUSE='POWER';
      NO_LOAD_CHECK='Both';
      NO_IO_CHECK='Both';
      NO_ASSERT_CHECK='TRUE';
      NO_DIR_CHECK='TRUE';
      ALLOW_CONNECT='TRUE';
    'VSS_AE54':
      PIN_NUMBER='(0,0,0,0,0,0,0,0,0,0,0,0,0,0,0,0,0,0,0,0,0,0,0,0,0,0,0,0,0,0,AE54,0,0,0,0,0,0,0,0,0)';
      PINUSE='POWER';
      NO_LOAD_CHECK='Both';
      NO_IO_CHECK='Both';
      NO_ASSERT_CHECK='TRUE';
      NO_DIR_CHECK='TRUE';
      ALLOW_CONNECT='TRUE';
    'VSS_AE56':
      PIN_NUMBER='(0,0,0,0,0,0,0,0,0,0,0,0,0,0,0,0,0,0,0,0,0,0,0,0,0,0,0,0,0,0,AE56,0,0,0,0,0,0,0,0,0)';
      PINUSE='POWER';
      NO_LOAD_CHECK='Both';
      NO_IO_CHECK='Both';
      NO_ASSERT_CHECK='TRUE';
      NO_DIR_CHECK='TRUE';
      ALLOW_CONNECT='TRUE';
    'VSS_AE58':
      PIN_NUMBER='(0,0,0,0,0,0,0,0,0,0,0,0,0,0,0,0,0,0,0,0,0,0,0,0,0,0,0,0,0,0,AE58,0,0,0,0,0,0,0,0,0)';
      PINUSE='POWER';
      NO_LOAD_CHECK='Both';
      NO_IO_CHECK='Both';
      NO_ASSERT_CHECK='TRUE';
      NO_DIR_CHECK='TRUE';
      ALLOW_CONNECT='TRUE';
    'VSS_AE61':
      PIN_NUMBER='(0,0,0,0,0,0,0,0,0,0,0,0,0,0,0,0,0,0,0,0,0,0,0,0,0,0,0,0,0,0,AE61,0,0,0,0,0,0,0,0,0)';
      PINUSE='POWER';
      NO_LOAD_CHECK='Both';
      NO_IO_CHECK='Both';
      NO_ASSERT_CHECK='TRUE';
      NO_DIR_CHECK='TRUE';
      ALLOW_CONNECT='TRUE';
    'VSS_AE63':
      PIN_NUMBER='(0,0,0,0,0,0,0,0,0,0,0,0,0,0,0,0,0,0,0,0,0,0,0,0,0,0,0,0,0,0,AE63,0,0,0,0,0,0,0,0,0)';
      PINUSE='POWER';
      NO_LOAD_CHECK='Both';
      NO_IO_CHECK='Both';
      NO_ASSERT_CHECK='TRUE';
      NO_DIR_CHECK='TRUE';
      ALLOW_CONNECT='TRUE';
    'VSS_AE65':
      PIN_NUMBER='(0,0,0,0,0,0,0,0,0,0,0,0,0,0,0,0,0,0,0,0,0,0,0,0,0,0,0,0,0,0,AE65,0,0,0,0,0,0,0,0,0)';
      PINUSE='POWER';
      NO_LOAD_CHECK='Both';
      NO_IO_CHECK='Both';
      NO_ASSERT_CHECK='TRUE';
      NO_DIR_CHECK='TRUE';
      ALLOW_CONNECT='TRUE';
    'VSS_AE68':
      PIN_NUMBER='(0,0,0,0,0,0,0,0,0,0,0,0,0,0,0,0,0,0,0,0,0,0,0,0,0,0,0,0,0,0,AE68,0,0,0,0,0,0,0,0,0)';
      PINUSE='POWER';
      NO_LOAD_CHECK='Both';
      NO_IO_CHECK='Both';
      NO_ASSERT_CHECK='TRUE';
      NO_DIR_CHECK='TRUE';
      ALLOW_CONNECT='TRUE';
    'VSS_AE70':
      PIN_NUMBER='(0,0,0,0,0,0,0,0,0,0,0,0,0,0,0,0,0,0,0,0,0,0,0,0,0,0,0,0,0,0,AE70,0,0,0,0,0,0,0,0,0)';
      PINUSE='POWER';
      NO_LOAD_CHECK='Both';
      NO_IO_CHECK='Both';
      NO_ASSERT_CHECK='TRUE';
      NO_DIR_CHECK='TRUE';
      ALLOW_CONNECT='TRUE';
    'VSS_AE72':
      PIN_NUMBER='(0,0,0,0,0,0,0,0,0,0,0,0,0,0,0,0,0,0,0,0,0,0,0,0,0,0,0,0,0,0,AE72,0,0,0,0,0,0,0,0,0)';
      PINUSE='POWER';
      NO_LOAD_CHECK='Both';
      NO_IO_CHECK='Both';
      NO_ASSERT_CHECK='TRUE';
      NO_DIR_CHECK='TRUE';
      ALLOW_CONNECT='TRUE';
    'VSS_AE75':
      PIN_NUMBER='(0,0,0,0,0,0,0,0,0,0,0,0,0,0,0,0,0,0,0,0,0,0,0,0,0,0,0,0,0,0,AE75,0,0,0,0,0,0,0,0,0)';
      PINUSE='POWER';
      NO_LOAD_CHECK='Both';
      NO_IO_CHECK='Both';
      NO_ASSERT_CHECK='TRUE';
      NO_DIR_CHECK='TRUE';
      ALLOW_CONNECT='TRUE';
    'VSS_AF3':
      PIN_NUMBER='(0,0,0,0,0,0,0,0,0,0,0,0,0,0,0,0,0,0,0,0,0,0,0,0,0,0,0,0,0,0,AF3,0,0,0,0,0,0,0,0,0)';
      PINUSE='POWER';
      NO_LOAD_CHECK='Both';
      NO_IO_CHECK='Both';
      NO_ASSERT_CHECK='TRUE';
      NO_DIR_CHECK='TRUE';
      ALLOW_CONNECT='TRUE';
    'VSS_AF8':
      PIN_NUMBER='(0,0,0,0,0,0,0,0,0,0,0,0,0,0,0,0,0,0,0,0,0,0,0,0,0,0,0,0,0,0,AF8,0,0,0,0,0,0,0,0,0)';
      PINUSE='POWER';
      NO_LOAD_CHECK='Both';
      NO_IO_CHECK='Both';
      NO_ASSERT_CHECK='TRUE';
      NO_DIR_CHECK='TRUE';
      ALLOW_CONNECT='TRUE';
    'VSS_AF10':
      PIN_NUMBER='(0,0,0,0,0,0,0,0,0,0,0,0,0,0,0,0,0,0,0,0,0,0,0,0,0,0,0,0,0,0,AF10,0,0,0,0,0,0,0,0,0)';
      PINUSE='POWER';
      NO_LOAD_CHECK='Both';
      NO_IO_CHECK='Both';
      NO_ASSERT_CHECK='TRUE';
      NO_DIR_CHECK='TRUE';
      ALLOW_CONNECT='TRUE';
    'VSS_AF15':
      PIN_NUMBER='(0,0,0,0,0,0,0,0,0,0,0,0,0,0,0,0,0,0,0,0,0,0,0,0,0,0,0,0,0,0,AF15,0,0,0,0,0,0,0,0,0)';
      PINUSE='POWER';
      NO_LOAD_CHECK='Both';
      NO_IO_CHECK='Both';
      NO_ASSERT_CHECK='TRUE';
      NO_DIR_CHECK='TRUE';
      ALLOW_CONNECT='TRUE';
    'VSS_AF17':
      PIN_NUMBER='(0,0,0,0,0,0,0,0,0,0,0,0,0,0,0,0,0,0,0,0,0,0,0,0,0,0,0,0,0,0,AF17,0,0,0,0,0,0,0,0,0)';
      PINUSE='POWER';
      NO_LOAD_CHECK='Both';
      NO_IO_CHECK='Both';
      NO_ASSERT_CHECK='TRUE';
      NO_DIR_CHECK='TRUE';
      ALLOW_CONNECT='TRUE';
    'VSS_AF22':
      PIN_NUMBER='(0,0,0,0,0,0,0,0,0,0,0,0,0,0,0,0,0,0,0,0,0,0,0,0,0,0,0,0,0,0,AF22,0,0,0,0,0,0,0,0,0)';
      PINUSE='POWER';
      NO_LOAD_CHECK='Both';
      NO_IO_CHECK='Both';
      NO_ASSERT_CHECK='TRUE';
      NO_DIR_CHECK='TRUE';
      ALLOW_CONNECT='TRUE';
    'VSS_AF25':
      PIN_NUMBER='(0,0,0,0,0,0,0,0,0,0,0,0,0,0,0,0,0,0,0,0,0,0,0,0,0,0,0,0,0,0,AF25,0,0,0,0,0,0,0,0,0)';
      PINUSE='POWER';
      NO_LOAD_CHECK='Both';
      NO_IO_CHECK='Both';
      NO_ASSERT_CHECK='TRUE';
      NO_DIR_CHECK='TRUE';
      ALLOW_CONNECT='TRUE';
    'VSS_AF28':
      PIN_NUMBER='(0,0,0,0,0,0,0,0,0,0,0,0,0,0,0,0,0,0,0,0,0,0,0,0,0,0,0,0,0,0,AF28,0,0,0,0,0,0,0,0,0)';
      PINUSE='POWER';
      NO_LOAD_CHECK='Both';
      NO_IO_CHECK='Both';
      NO_ASSERT_CHECK='TRUE';
      NO_DIR_CHECK='TRUE';
      ALLOW_CONNECT='TRUE';
    'VSS_AF31':
      PIN_NUMBER='(0,0,0,0,0,0,0,0,0,0,0,0,0,0,0,0,0,0,0,0,0,0,0,0,0,0,0,0,0,0,AF31,0,0,0,0,0,0,0,0,0)';
      PINUSE='POWER';
      NO_LOAD_CHECK='Both';
      NO_IO_CHECK='Both';
      NO_ASSERT_CHECK='TRUE';
      NO_DIR_CHECK='TRUE';
      ALLOW_CONNECT='TRUE';
    'VSS_AF34':
      PIN_NUMBER='(0,0,0,0,0,0,0,0,0,0,0,0,0,0,0,0,0,0,0,0,0,0,0,0,0,0,0,0,0,0,AF34,0,0,0,0,0,0,0,0,0)';
      PINUSE='POWER';
      NO_LOAD_CHECK='Both';
      NO_IO_CHECK='Both';
      NO_ASSERT_CHECK='TRUE';
      NO_DIR_CHECK='TRUE';
      ALLOW_CONNECT='TRUE';
    'VSS_AF37':
      PIN_NUMBER='(0,0,0,0,0,0,0,0,0,0,0,0,0,0,0,0,0,0,0,0,0,0,0,0,0,0,0,0,0,0,AF37,0,0,0,0,0,0,0,0,0)';
      PINUSE='POWER';
      NO_LOAD_CHECK='Both';
      NO_IO_CHECK='Both';
      NO_ASSERT_CHECK='TRUE';
      NO_DIR_CHECK='TRUE';
      ALLOW_CONNECT='TRUE';
    'VSS_AF39':
      PIN_NUMBER='(0,0,0,0,0,0,0,0,0,0,0,0,0,0,0,0,0,0,0,0,0,0,0,0,0,0,0,0,0,0,AF39,0,0,0,0,0,0,0,0,0)';
      PINUSE='POWER';
      NO_LOAD_CHECK='Both';
      NO_IO_CHECK='Both';
      NO_ASSERT_CHECK='TRUE';
      NO_DIR_CHECK='TRUE';
      ALLOW_CONNECT='TRUE';
    'VSS_AF42':
      PIN_NUMBER='(0,0,0,0,0,0,0,0,0,0,0,0,0,0,0,0,0,0,0,0,0,0,0,0,0,0,0,0,0,0,AF42,0,0,0,0,0,0,0,0,0)';
      PINUSE='POWER';
      NO_LOAD_CHECK='Both';
      NO_IO_CHECK='Both';
      NO_ASSERT_CHECK='TRUE';
      NO_DIR_CHECK='TRUE';
      ALLOW_CONNECT='TRUE';
    'VSS_AF45':
      PIN_NUMBER='(0,0,0,0,0,0,0,0,0,0,0,0,0,0,0,0,0,0,0,0,0,0,0,0,0,0,0,0,0,0,AF45,0,0,0,0,0,0,0,0,0)';
      PINUSE='POWER';
      NO_LOAD_CHECK='Both';
      NO_IO_CHECK='Both';
      NO_ASSERT_CHECK='TRUE';
      NO_DIR_CHECK='TRUE';
      ALLOW_CONNECT='TRUE';
    'VSS_AF48':
      PIN_NUMBER='(0,0,0,0,0,0,0,0,0,0,0,0,0,0,0,0,0,0,0,0,0,0,0,0,0,0,0,0,0,0,AF48,0,0,0,0,0,0,0,0,0)';
      PINUSE='POWER';
      NO_LOAD_CHECK='Both';
      NO_IO_CHECK='Both';
      NO_ASSERT_CHECK='TRUE';
      NO_DIR_CHECK='TRUE';
      ALLOW_CONNECT='TRUE';
    'VSS_AF51':
      PIN_NUMBER='(0,0,0,0,0,0,0,0,0,0,0,0,0,0,0,0,0,0,0,0,0,0,0,0,0,0,0,0,0,0,AF51,0,0,0,0,0,0,0,0,0)';
      PINUSE='POWER';
      NO_LOAD_CHECK='Both';
      NO_IO_CHECK='Both';
      NO_ASSERT_CHECK='TRUE';
      NO_DIR_CHECK='TRUE';
      ALLOW_CONNECT='TRUE';
    'VSS_AF54':
      PIN_NUMBER='(0,0,0,0,0,0,0,0,0,0,0,0,0,0,0,0,0,0,0,0,0,0,0,0,0,0,0,0,0,0,AF54,0,0,0,0,0,0,0,0,0)';
      PINUSE='POWER';
      NO_LOAD_CHECK='Both';
      NO_IO_CHECK='Both';
      NO_ASSERT_CHECK='TRUE';
      NO_DIR_CHECK='TRUE';
      ALLOW_CONNECT='TRUE';
    'VSS_AF59':
      PIN_NUMBER='(0,0,0,0,0,0,0,0,0,0,0,0,0,0,0,0,0,0,0,0,0,0,0,0,0,0,0,0,0,0,AF59,0,0,0,0,0,0,0,0,0)';
      PINUSE='POWER';
      NO_LOAD_CHECK='Both';
      NO_IO_CHECK='Both';
      NO_ASSERT_CHECK='TRUE';
      NO_DIR_CHECK='TRUE';
      ALLOW_CONNECT='TRUE';
    'VSS_AF61':
      PIN_NUMBER='(0,0,0,0,0,0,0,0,0,0,0,0,0,0,0,0,0,0,0,0,0,0,0,0,0,0,0,0,0,0,AF61,0,0,0,0,0,0,0,0,0)';
      PINUSE='POWER';
      NO_LOAD_CHECK='Both';
      NO_IO_CHECK='Both';
      NO_ASSERT_CHECK='TRUE';
      NO_DIR_CHECK='TRUE';
      ALLOW_CONNECT='TRUE';
    'VSS_AF66':
      PIN_NUMBER='(0,0,0,0,0,0,0,0,0,0,0,0,0,0,0,0,0,0,0,0,0,0,0,0,0,0,0,0,0,0,AF66,0,0,0,0,0,0,0,0,0)';
      PINUSE='POWER';
      NO_LOAD_CHECK='Both';
      NO_IO_CHECK='Both';
      NO_ASSERT_CHECK='TRUE';
      NO_DIR_CHECK='TRUE';
      ALLOW_CONNECT='TRUE';
    'VSS_AF68':
      PIN_NUMBER='(0,0,0,0,0,0,0,0,0,0,0,0,0,0,0,0,0,0,0,0,0,0,0,0,0,0,0,0,0,0,AF68,0,0,0,0,0,0,0,0,0)';
      PINUSE='POWER';
      NO_LOAD_CHECK='Both';
      NO_IO_CHECK='Both';
      NO_ASSERT_CHECK='TRUE';
      NO_DIR_CHECK='TRUE';
      ALLOW_CONNECT='TRUE';
    'VSS_AF73':
      PIN_NUMBER='(0,0,0,0,0,0,0,0,0,0,0,0,0,0,0,0,0,0,0,0,0,0,0,0,0,0,0,0,0,0,AF73,0,0,0,0,0,0,0,0,0)';
      PINUSE='POWER';
      NO_LOAD_CHECK='Both';
      NO_IO_CHECK='Both';
      NO_ASSERT_CHECK='TRUE';
      NO_DIR_CHECK='TRUE';
      ALLOW_CONNECT='TRUE';
    'VSS_AG1':
      PIN_NUMBER='(0,0,0,0,0,0,0,0,0,0,0,0,0,0,0,0,0,0,0,0,0,0,0,0,0,0,0,0,0,0,AG1,0,0,0,0,0,0,0,0,0)';
      PINUSE='POWER';
      NO_LOAD_CHECK='Both';
      NO_IO_CHECK='Both';
      NO_ASSERT_CHECK='TRUE';
      NO_DIR_CHECK='TRUE';
      ALLOW_CONNECT='TRUE';
    'VSS_AG4':
      PIN_NUMBER='(0,0,0,0,0,0,0,0,0,0,0,0,0,0,0,0,0,0,0,0,0,0,0,0,0,0,0,0,0,0,AG4,0,0,0,0,0,0,0,0,0)';
      PINUSE='POWER';
      NO_LOAD_CHECK='Both';
      NO_IO_CHECK='Both';
      NO_ASSERT_CHECK='TRUE';
      NO_DIR_CHECK='TRUE';
      ALLOW_CONNECT='TRUE';
    'VSS_AG6':
      PIN_NUMBER='(0,0,0,0,0,0,0,0,0,0,0,0,0,0,0,0,0,0,0,0,0,0,0,0,0,0,0,0,0,0,AG6,0,0,0,0,0,0,0,0,0)';
      PINUSE='POWER';
      NO_LOAD_CHECK='Both';
      NO_IO_CHECK='Both';
      NO_ASSERT_CHECK='TRUE';
      NO_DIR_CHECK='TRUE';
      ALLOW_CONNECT='TRUE';
    'VSS_AG8':
      PIN_NUMBER='(0,0,0,0,0,0,0,0,0,0,0,0,0,0,0,0,0,0,0,0,0,0,0,0,0,0,0,0,0,0,AG8,0,0,0,0,0,0,0,0,0)';
      PINUSE='POWER';
      NO_LOAD_CHECK='Both';
      NO_IO_CHECK='Both';
      NO_ASSERT_CHECK='TRUE';
      NO_DIR_CHECK='TRUE';
      ALLOW_CONNECT='TRUE';
    'VSS_AG11':
      PIN_NUMBER='(0,0,0,0,0,0,0,0,0,0,0,0,0,0,0,0,0,0,0,0,0,0,0,0,0,0,0,0,0,0,AG11,0,0,0,0,0,0,0,0,0)';
      PINUSE='POWER';
      NO_LOAD_CHECK='Both';
      NO_IO_CHECK='Both';
      NO_ASSERT_CHECK='TRUE';
      NO_DIR_CHECK='TRUE';
      ALLOW_CONNECT='TRUE';
    'VSS_AG13':
      PIN_NUMBER='(0,0,0,0,0,0,0,0,0,0,0,0,0,0,0,0,0,0,0,0,0,0,0,0,0,0,0,0,0,0,AG13,0,0,0,0,0,0,0,0,0)';
      PINUSE='POWER';
      NO_LOAD_CHECK='Both';
      NO_IO_CHECK='Both';
      NO_ASSERT_CHECK='TRUE';
      NO_DIR_CHECK='TRUE';
      ALLOW_CONNECT='TRUE';
    'VSS_AG15':
      PIN_NUMBER='(0,0,0,0,0,0,0,0,0,0,0,0,0,0,0,0,0,0,0,0,0,0,0,0,0,0,0,0,0,0,AG15,0,0,0,0,0,0,0,0,0)';
      PINUSE='POWER';
      NO_LOAD_CHECK='Both';
      NO_IO_CHECK='Both';
      NO_ASSERT_CHECK='TRUE';
      NO_DIR_CHECK='TRUE';
      ALLOW_CONNECT='TRUE';
    'VSS_AG18':
      PIN_NUMBER='(0,0,0,0,0,0,0,0,0,0,0,0,0,0,0,0,0,0,0,0,0,0,0,0,0,0,0,0,0,0,AG18,0,0,0,0,0,0,0,0,0)';
      PINUSE='POWER';
      NO_LOAD_CHECK='Both';
      NO_IO_CHECK='Both';
      NO_ASSERT_CHECK='TRUE';
      NO_DIR_CHECK='TRUE';
      ALLOW_CONNECT='TRUE';
    'VSS_AG20':
      PIN_NUMBER='(0,0,0,0,0,0,0,0,0,0,0,0,0,0,0,0,0,0,0,0,0,0,0,0,0,0,0,0,0,0,AG20,0,0,0,0,0,0,0,0,0)';
      PINUSE='POWER';
      NO_LOAD_CHECK='Both';
      NO_IO_CHECK='Both';
      NO_ASSERT_CHECK='TRUE';
      NO_DIR_CHECK='TRUE';
      ALLOW_CONNECT='TRUE';
    'VSS_AG22':
      PIN_NUMBER='(0,0,0,0,0,0,0,0,0,0,0,0,0,0,0,0,0,0,0,0,0,0,0,0,0,0,0,0,0,0,AG22,0,0,0,0,0,0,0,0,0)';
      PINUSE='POWER';
      NO_LOAD_CHECK='Both';
      NO_IO_CHECK='Both';
      NO_ASSERT_CHECK='TRUE';
      NO_DIR_CHECK='TRUE';
      ALLOW_CONNECT='TRUE';
    'VSS_AG25':
      PIN_NUMBER='(0,0,0,0,0,0,0,0,0,0,0,0,0,0,0,0,0,0,0,0,0,0,0,0,0,0,0,0,0,0,AG25,0,0,0,0,0,0,0,0,0)';
      PINUSE='POWER';
      NO_LOAD_CHECK='Both';
      NO_IO_CHECK='Both';
      NO_ASSERT_CHECK='TRUE';
      NO_DIR_CHECK='TRUE';
      ALLOW_CONNECT='TRUE';
    'VSS_AG28':
      PIN_NUMBER='(0,0,0,0,0,0,0,0,0,0,0,0,0,0,0,0,0,0,0,0,0,0,0,0,0,0,0,0,0,0,AG28,0,0,0,0,0,0,0,0,0)';
      PINUSE='POWER';
      NO_LOAD_CHECK='Both';
      NO_IO_CHECK='Both';
      NO_ASSERT_CHECK='TRUE';
      NO_DIR_CHECK='TRUE';
      ALLOW_CONNECT='TRUE';
    'VSS_AG31':
      PIN_NUMBER='(0,0,0,0,0,0,0,0,0,0,0,0,0,0,0,0,0,0,0,0,0,0,0,0,0,0,0,0,0,0,AG31,0,0,0,0,0,0,0,0,0)';
      PINUSE='POWER';
      NO_LOAD_CHECK='Both';
      NO_IO_CHECK='Both';
      NO_ASSERT_CHECK='TRUE';
      NO_DIR_CHECK='TRUE';
      ALLOW_CONNECT='TRUE';
    'VSS_AG34':
      PIN_NUMBER='(0,0,0,0,0,0,0,0,0,0,0,0,0,0,0,0,0,0,0,0,0,0,0,0,0,0,0,0,0,0,AG34,0,0,0,0,0,0,0,0,0)';
      PINUSE='POWER';
      NO_LOAD_CHECK='Both';
      NO_IO_CHECK='Both';
      NO_ASSERT_CHECK='TRUE';
      NO_DIR_CHECK='TRUE';
      ALLOW_CONNECT='TRUE';
    'VSS_AG42':
      PIN_NUMBER='(0,0,0,0,0,0,0,0,0,0,0,0,0,0,0,0,0,0,0,0,0,0,0,0,0,0,0,0,0,0,AG42,0,0,0,0,0,0,0,0,0)';
      PINUSE='POWER';
      NO_LOAD_CHECK='Both';
      NO_IO_CHECK='Both';
      NO_ASSERT_CHECK='TRUE';
      NO_DIR_CHECK='TRUE';
      ALLOW_CONNECT='TRUE';
    'VSS_AG45':
      PIN_NUMBER='(0,0,0,0,0,0,0,0,0,0,0,0,0,0,0,0,0,0,0,0,0,0,0,0,0,0,0,0,0,0,AG45,0,0,0,0,0,0,0,0,0)';
      PINUSE='POWER';
      NO_LOAD_CHECK='Both';
      NO_IO_CHECK='Both';
      NO_ASSERT_CHECK='TRUE';
      NO_DIR_CHECK='TRUE';
      ALLOW_CONNECT='TRUE';
    'VSS_AG48':
      PIN_NUMBER='(0,0,0,0,0,0,0,0,0,0,0,0,0,0,0,0,0,0,0,0,0,0,0,0,0,0,0,0,0,0,AG48,0,0,0,0,0,0,0,0,0)';
      PINUSE='POWER';
      NO_LOAD_CHECK='Both';
      NO_IO_CHECK='Both';
      NO_ASSERT_CHECK='TRUE';
      NO_DIR_CHECK='TRUE';
      ALLOW_CONNECT='TRUE';
    'VSS_AG51':
      PIN_NUMBER='(0,0,0,0,0,0,0,0,0,0,0,0,0,0,0,0,0,0,0,0,0,0,0,0,0,0,0,0,0,0,AG51,0,0,0,0,0,0,0,0,0)';
      PINUSE='POWER';
      NO_LOAD_CHECK='Both';
      NO_IO_CHECK='Both';
      NO_ASSERT_CHECK='TRUE';
      NO_DIR_CHECK='TRUE';
      ALLOW_CONNECT='TRUE';
    'VSS_AG54':
      PIN_NUMBER='(0,0,0,0,0,0,0,0,0,0,0,0,0,0,0,0,0,0,0,0,0,0,0,0,0,0,0,0,0,0,AG54,0,0,0,0,0,0,0,0,0)';
      PINUSE='POWER';
      NO_LOAD_CHECK='Both';
      NO_IO_CHECK='Both';
      NO_ASSERT_CHECK='TRUE';
      NO_DIR_CHECK='TRUE';
      ALLOW_CONNECT='TRUE';
    'VSS_AG56':
      PIN_NUMBER='(0,0,0,0,0,0,0,0,0,0,0,0,0,0,0,0,0,0,0,0,0,0,0,0,0,0,0,0,0,0,AG56,0,0,0,0,0,0,0,0,0)';
      PINUSE='POWER';
      NO_LOAD_CHECK='Both';
      NO_IO_CHECK='Both';
      NO_ASSERT_CHECK='TRUE';
      NO_DIR_CHECK='TRUE';
      ALLOW_CONNECT='TRUE';
    'VSS_AG58':
      PIN_NUMBER='(0,0,0,0,0,0,0,0,0,0,0,0,0,0,0,0,0,0,0,0,0,0,0,0,0,0,0,0,0,0,AG58,0,0,0,0,0,0,0,0,0)';
      PINUSE='POWER';
      NO_LOAD_CHECK='Both';
      NO_IO_CHECK='Both';
      NO_ASSERT_CHECK='TRUE';
      NO_DIR_CHECK='TRUE';
      ALLOW_CONNECT='TRUE';
    'VSS_AG61':
      PIN_NUMBER='(0,0,0,0,0,0,0,0,0,0,0,0,0,0,0,0,0,0,0,0,0,0,0,0,0,0,0,0,0,0,AG61,0,0,0,0,0,0,0,0,0)';
      PINUSE='POWER';
      NO_LOAD_CHECK='Both';
      NO_IO_CHECK='Both';
      NO_ASSERT_CHECK='TRUE';
      NO_DIR_CHECK='TRUE';
      ALLOW_CONNECT='TRUE';
    'VSS_AG63':
      PIN_NUMBER='(0,0,0,0,0,0,0,0,0,0,0,0,0,0,0,0,0,0,0,0,0,0,0,0,0,0,0,0,0,0,AG63,0,0,0,0,0,0,0,0,0)';
      PINUSE='POWER';
      NO_LOAD_CHECK='Both';
      NO_IO_CHECK='Both';
      NO_ASSERT_CHECK='TRUE';
      NO_DIR_CHECK='TRUE';
      ALLOW_CONNECT='TRUE';
    'VSS_AG65':
      PIN_NUMBER='(0,0,0,0,0,0,0,0,0,0,0,0,0,0,0,0,0,0,0,0,0,0,0,0,0,0,0,0,0,0,AG65,0,0,0,0,0,0,0,0,0)';
      PINUSE='POWER';
      NO_LOAD_CHECK='Both';
      NO_IO_CHECK='Both';
      NO_ASSERT_CHECK='TRUE';
      NO_DIR_CHECK='TRUE';
      ALLOW_CONNECT='TRUE';
    'VSS_AG68':
      PIN_NUMBER='(0,0,0,0,0,0,0,0,0,0,0,0,0,0,0,0,0,0,0,0,0,0,0,0,0,0,0,0,0,0,AG68,0,0,0,0,0,0,0,0,0)';
      PINUSE='POWER';
      NO_LOAD_CHECK='Both';
      NO_IO_CHECK='Both';
      NO_ASSERT_CHECK='TRUE';
      NO_DIR_CHECK='TRUE';
      ALLOW_CONNECT='TRUE';
    'VSS_AG70':
      PIN_NUMBER='(0,0,0,0,0,0,0,0,0,0,0,0,0,0,0,0,0,0,0,0,0,0,0,0,0,0,0,0,0,0,AG70,0,0,0,0,0,0,0,0,0)';
      PINUSE='POWER';
      NO_LOAD_CHECK='Both';
      NO_IO_CHECK='Both';
      NO_ASSERT_CHECK='TRUE';
      NO_DIR_CHECK='TRUE';
      ALLOW_CONNECT='TRUE';
    'VSS_AG72':
      PIN_NUMBER='(0,0,0,0,0,0,0,0,0,0,0,0,0,0,0,0,0,0,0,0,0,0,0,0,0,0,0,0,0,0,AG72,0,0,0,0,0,0,0,0,0)';
      PINUSE='POWER';
      NO_LOAD_CHECK='Both';
      NO_IO_CHECK='Both';
      NO_ASSERT_CHECK='TRUE';
      NO_DIR_CHECK='TRUE';
      ALLOW_CONNECT='TRUE';
    'VSS_AG75':
      PIN_NUMBER='(0,0,0,0,0,0,0,0,0,0,0,0,0,0,0,0,0,0,0,0,0,0,0,0,0,0,0,0,0,0,AG75,0,0,0,0,0,0,0,0,0)';
      PINUSE='POWER';
      NO_LOAD_CHECK='Both';
      NO_IO_CHECK='Both';
      NO_ASSERT_CHECK='TRUE';
      NO_DIR_CHECK='TRUE';
      ALLOW_CONNECT='TRUE';
    'VSS_AH3':
      PIN_NUMBER='(0,0,0,0,0,0,0,0,0,0,0,0,0,0,0,0,0,0,0,0,0,0,0,0,0,0,0,0,0,0,AH3,0,0,0,0,0,0,0,0,0)';
      PINUSE='POWER';
      NO_LOAD_CHECK='Both';
      NO_IO_CHECK='Both';
      NO_ASSERT_CHECK='TRUE';
      NO_DIR_CHECK='TRUE';
      ALLOW_CONNECT='TRUE';
    'VSS_AH5':
      PIN_NUMBER='(0,0,0,0,0,0,0,0,0,0,0,0,0,0,0,0,0,0,0,0,0,0,0,0,0,0,0,0,0,0,AH5,0,0,0,0,0,0,0,0,0)';
      PINUSE='POWER';
      NO_LOAD_CHECK='Both';
      NO_IO_CHECK='Both';
      NO_ASSERT_CHECK='TRUE';
      NO_DIR_CHECK='TRUE';
      ALLOW_CONNECT='TRUE';
    'VSS_AH8':
      PIN_NUMBER='(0,0,0,0,0,0,0,0,0,0,0,0,0,0,0,0,0,0,0,0,0,0,0,0,0,0,0,0,0,0,AH8,0,0,0,0,0,0,0,0,0)';
      PINUSE='POWER';
      NO_LOAD_CHECK='Both';
      NO_IO_CHECK='Both';
      NO_ASSERT_CHECK='TRUE';
      NO_DIR_CHECK='TRUE';
      ALLOW_CONNECT='TRUE';
    'VSS_AH10':
      PIN_NUMBER='(0,0,0,0,0,0,0,0,0,0,0,0,0,0,0,0,0,0,0,0,0,0,0,0,0,0,0,0,0,0,AH10,0,0,0,0,0,0,0,0,0)';
      PINUSE='POWER';
      NO_LOAD_CHECK='Both';
      NO_IO_CHECK='Both';
      NO_ASSERT_CHECK='TRUE';
      NO_DIR_CHECK='TRUE';
      ALLOW_CONNECT='TRUE';
    'VSS_AH12':
      PIN_NUMBER='(0,0,0,0,0,0,0,0,0,0,0,0,0,0,0,0,0,0,0,0,0,0,0,0,0,0,0,0,0,0,AH12,0,0,0,0,0,0,0,0,0)';
      PINUSE='POWER';
      NO_LOAD_CHECK='Both';
      NO_IO_CHECK='Both';
      NO_ASSERT_CHECK='TRUE';
      NO_DIR_CHECK='TRUE';
      ALLOW_CONNECT='TRUE';
    'VSS_AH15':
      PIN_NUMBER='(0,0,0,0,0,0,0,0,0,0,0,0,0,0,0,0,0,0,0,0,0,0,0,0,0,0,0,0,0,0,AH15,0,0,0,0,0,0,0,0,0)';
      PINUSE='POWER';
      NO_LOAD_CHECK='Both';
      NO_IO_CHECK='Both';
      NO_ASSERT_CHECK='TRUE';
      NO_DIR_CHECK='TRUE';
      ALLOW_CONNECT='TRUE';
    'VSS_AH17':
      PIN_NUMBER='(0,0,0,0,0,0,0,0,0,0,0,0,0,0,0,0,0,0,0,0,0,0,0,0,0,0,0,0,0,0,AH17,0,0,0,0,0,0,0,0,0)';
      PINUSE='POWER';
      NO_LOAD_CHECK='Both';
      NO_IO_CHECK='Both';
      NO_ASSERT_CHECK='TRUE';
      NO_DIR_CHECK='TRUE';
      ALLOW_CONNECT='TRUE';
    'VSS_AH19':
      PIN_NUMBER='(0,0,0,0,0,0,0,0,0,0,0,0,0,0,0,0,0,0,0,0,0,0,0,0,0,0,0,0,0,0,AH19,0,0,0,0,0,0,0,0,0)';
      PINUSE='POWER';
      NO_LOAD_CHECK='Both';
      NO_IO_CHECK='Both';
      NO_ASSERT_CHECK='TRUE';
      NO_DIR_CHECK='TRUE';
      ALLOW_CONNECT='TRUE';
    'VSS_AH23':
      PIN_NUMBER='(0,0,0,0,0,0,0,0,0,0,0,0,0,0,0,0,0,0,0,0,0,0,0,0,0,0,0,0,0,0,AH23,0,0,0,0,0,0,0,0,0)';
      PINUSE='POWER';
      NO_LOAD_CHECK='Both';
      NO_IO_CHECK='Both';
      NO_ASSERT_CHECK='TRUE';
      NO_DIR_CHECK='TRUE';
      ALLOW_CONNECT='TRUE';
    'VSS_AH24':
      PIN_NUMBER='(0,0,0,0,0,0,0,0,0,0,0,0,0,0,0,0,0,0,0,0,0,0,0,0,0,0,0,0,0,0,AH24,0,0,0,0,0,0,0,0,0)';
      PINUSE='POWER';
      NO_LOAD_CHECK='Both';
      NO_IO_CHECK='Both';
      NO_ASSERT_CHECK='TRUE';
      NO_DIR_CHECK='TRUE';
      ALLOW_CONNECT='TRUE';
    'VSS_AH25':
      PIN_NUMBER='(0,0,0,0,0,0,0,0,0,0,0,0,0,0,0,0,0,0,0,0,0,0,0,0,0,0,0,0,0,0,AH25,0,0,0,0,0,0,0,0,0)';
      PINUSE='POWER';
      NO_LOAD_CHECK='Both';
      NO_IO_CHECK='Both';
      NO_ASSERT_CHECK='TRUE';
      NO_DIR_CHECK='TRUE';
      ALLOW_CONNECT='TRUE';
    'VSS_AH26':
      PIN_NUMBER='(0,0,0,0,0,0,0,0,0,0,0,0,0,0,0,0,0,0,0,0,0,0,0,0,0,0,0,0,0,0,AH26,0,0,0,0,0,0,0,0,0)';
      PINUSE='POWER';
      NO_LOAD_CHECK='Both';
      NO_IO_CHECK='Both';
      NO_ASSERT_CHECK='TRUE';
      NO_DIR_CHECK='TRUE';
      ALLOW_CONNECT='TRUE';
    'VSS_AH27':
      PIN_NUMBER='(0,0,0,0,0,0,0,0,0,0,0,0,0,0,0,0,0,0,0,0,0,0,0,0,0,0,0,0,0,0,AH27,0,0,0,0,0,0,0,0,0)';
      PINUSE='POWER';
      NO_LOAD_CHECK='Both';
      NO_IO_CHECK='Both';
      NO_ASSERT_CHECK='TRUE';
      NO_DIR_CHECK='TRUE';
      ALLOW_CONNECT='TRUE';
    'VSS_AH28':
      PIN_NUMBER='(0,0,0,0,0,0,0,0,0,0,0,0,0,0,0,0,0,0,0,0,0,0,0,0,0,0,0,0,0,0,AH28,0,0,0,0,0,0,0,0,0)';
      PINUSE='POWER';
      NO_LOAD_CHECK='Both';
      NO_IO_CHECK='Both';
      NO_ASSERT_CHECK='TRUE';
      NO_DIR_CHECK='TRUE';
      ALLOW_CONNECT='TRUE';
    'VSS_AH29':
      PIN_NUMBER='(0,0,0,0,0,0,0,0,0,0,0,0,0,0,0,0,0,0,0,0,0,0,0,0,0,0,0,0,0,0,AH29,0,0,0,0,0,0,0,0,0)';
      PINUSE='POWER';
      NO_LOAD_CHECK='Both';
      NO_IO_CHECK='Both';
      NO_ASSERT_CHECK='TRUE';
      NO_DIR_CHECK='TRUE';
      ALLOW_CONNECT='TRUE';
    'VSS_AH30':
      PIN_NUMBER='(0,0,0,0,0,0,0,0,0,0,0,0,0,0,0,0,0,0,0,0,0,0,0,0,0,0,0,0,0,0,AH30,0,0,0,0,0,0,0,0,0)';
      PINUSE='POWER';
      NO_LOAD_CHECK='Both';
      NO_IO_CHECK='Both';
      NO_ASSERT_CHECK='TRUE';
      NO_DIR_CHECK='TRUE';
      ALLOW_CONNECT='TRUE';
    'VSS_AH31':
      PIN_NUMBER='(0,0,0,0,0,0,0,0,0,0,0,0,0,0,0,0,0,0,0,0,0,0,0,0,0,0,0,0,0,0,AH31,0,0,0,0,0,0,0,0,0)';
      PINUSE='POWER';
      NO_LOAD_CHECK='Both';
      NO_IO_CHECK='Both';
      NO_ASSERT_CHECK='TRUE';
      NO_DIR_CHECK='TRUE';
      ALLOW_CONNECT='TRUE';
    'VSS_AH32':
      PIN_NUMBER='(0,0,0,0,0,0,0,0,0,0,0,0,0,0,0,0,0,0,0,0,0,0,0,0,0,0,0,0,0,0,AH32,0,0,0,0,0,0,0,0,0)';
      PINUSE='POWER';
      NO_LOAD_CHECK='Both';
      NO_IO_CHECK='Both';
      NO_ASSERT_CHECK='TRUE';
      NO_DIR_CHECK='TRUE';
      ALLOW_CONNECT='TRUE';
    'VSS_AH34':
      PIN_NUMBER='(0,0,0,0,0,0,0,0,0,0,0,0,0,0,0,0,0,0,0,0,0,0,0,0,0,0,0,0,0,0,AH34,0,0,0,0,0,0,0,0,0)';
      PINUSE='POWER';
      NO_LOAD_CHECK='Both';
      NO_IO_CHECK='Both';
      NO_ASSERT_CHECK='TRUE';
      NO_DIR_CHECK='TRUE';
      ALLOW_CONNECT='TRUE';
    'VSS_AH37':
      PIN_NUMBER='(0,0,0,0,0,0,0,0,0,0,0,0,0,0,0,0,0,0,0,0,0,0,0,0,0,0,0,0,0,0,AH37,0,0,0,0,0,0,0,0,0)';
      PINUSE='POWER';
      NO_LOAD_CHECK='Both';
      NO_IO_CHECK='Both';
      NO_ASSERT_CHECK='TRUE';
      NO_DIR_CHECK='TRUE';
      ALLOW_CONNECT='TRUE';
    'VSS_AH39':
      PIN_NUMBER='(0,0,0,0,0,0,0,0,0,0,0,0,0,0,0,0,0,0,0,0,0,0,0,0,0,0,0,0,0,0,AH39,0,0,0,0,0,0,0,0,0)';
      PINUSE='POWER';
      NO_LOAD_CHECK='Both';
      NO_IO_CHECK='Both';
      NO_ASSERT_CHECK='TRUE';
      NO_DIR_CHECK='TRUE';
      ALLOW_CONNECT='TRUE';
    'VSS_AH42':
      PIN_NUMBER='(0,0,0,0,0,0,0,0,0,0,0,0,0,0,0,0,0,0,0,0,0,0,0,0,0,0,0,0,0,0,AH42,0,0,0,0,0,0,0,0,0)';
      PINUSE='POWER';
      NO_LOAD_CHECK='Both';
      NO_IO_CHECK='Both';
      NO_ASSERT_CHECK='TRUE';
      NO_DIR_CHECK='TRUE';
      ALLOW_CONNECT='TRUE';
    'VSS_AH43':
      PIN_NUMBER='(0,0,0,0,0,0,0,0,0,0,0,0,0,0,0,0,0,0,0,0,0,0,0,0,0,0,0,0,0,0,AH43,0,0,0,0,0,0,0,0,0)';
      PINUSE='POWER';
      NO_LOAD_CHECK='Both';
      NO_IO_CHECK='Both';
      NO_ASSERT_CHECK='TRUE';
      NO_DIR_CHECK='TRUE';
      ALLOW_CONNECT='TRUE';
    'VSS_AH44':
      PIN_NUMBER='(0,0,0,0,0,0,0,0,0,0,0,0,0,0,0,0,0,0,0,0,0,0,0,0,0,0,0,0,0,0,AH44,0,0,0,0,0,0,0,0,0)';
      PINUSE='POWER';
      NO_LOAD_CHECK='Both';
      NO_IO_CHECK='Both';
      NO_ASSERT_CHECK='TRUE';
      NO_DIR_CHECK='TRUE';
      ALLOW_CONNECT='TRUE';
    'VSS_AH45':
      PIN_NUMBER='(0,0,0,0,0,0,0,0,0,0,0,0,0,0,0,0,0,0,0,0,0,0,0,0,0,0,0,0,0,0,AH45,0,0,0,0,0,0,0,0,0)';
      PINUSE='POWER';
      NO_LOAD_CHECK='Both';
      NO_IO_CHECK='Both';
      NO_ASSERT_CHECK='TRUE';
      NO_DIR_CHECK='TRUE';
      ALLOW_CONNECT='TRUE';
    'VSS_AH46':
      PIN_NUMBER='(0,0,0,0,0,0,0,0,0,0,0,0,0,0,0,0,0,0,0,0,0,0,0,0,0,0,0,0,0,0,AH46,0,0,0,0,0,0,0,0,0)';
      PINUSE='POWER';
      NO_LOAD_CHECK='Both';
      NO_IO_CHECK='Both';
      NO_ASSERT_CHECK='TRUE';
      NO_DIR_CHECK='TRUE';
      ALLOW_CONNECT='TRUE';
    'VSS_AH47':
      PIN_NUMBER='(0,0,0,0,0,0,0,0,0,0,0,0,0,0,0,0,0,0,0,0,0,0,0,0,0,0,0,0,0,0,AH47,0,0,0,0,0,0,0,0,0)';
      PINUSE='POWER';
      NO_LOAD_CHECK='Both';
      NO_IO_CHECK='Both';
      NO_ASSERT_CHECK='TRUE';
      NO_DIR_CHECK='TRUE';
      ALLOW_CONNECT='TRUE';
    'VSS_AH48':
      PIN_NUMBER='(0,0,0,0,0,0,0,0,0,0,0,0,0,0,0,0,0,0,0,0,0,0,0,0,0,0,0,0,0,0,AH48,0,0,0,0,0,0,0,0,0)';
      PINUSE='POWER';
      NO_LOAD_CHECK='Both';
      NO_IO_CHECK='Both';
      NO_ASSERT_CHECK='TRUE';
      NO_DIR_CHECK='TRUE';
      ALLOW_CONNECT='TRUE';
    'VSS_AH49':
      PIN_NUMBER='(0,0,0,0,0,0,0,0,0,0,0,0,0,0,0,0,0,0,0,0,0,0,0,0,0,0,0,0,0,0,AH49,0,0,0,0,0,0,0,0,0)';
      PINUSE='POWER';
      NO_LOAD_CHECK='Both';
      NO_IO_CHECK='Both';
      NO_ASSERT_CHECK='TRUE';
      NO_DIR_CHECK='TRUE';
      ALLOW_CONNECT='TRUE';
    'VSS_AH50':
      PIN_NUMBER='(0,0,0,0,0,0,0,0,0,0,0,0,0,0,0,0,0,0,0,0,0,0,0,0,0,0,0,0,0,0,AH50,0,0,0,0,0,0,0,0,0)';
      PINUSE='POWER';
      NO_LOAD_CHECK='Both';
      NO_IO_CHECK='Both';
      NO_ASSERT_CHECK='TRUE';
      NO_DIR_CHECK='TRUE';
      ALLOW_CONNECT='TRUE';
    'VSS_AH51':
      PIN_NUMBER='(0,0,0,0,0,0,0,0,0,0,0,0,0,0,0,0,0,0,0,0,0,0,0,0,0,0,0,0,0,0,AH51,0,0,0,0,0,0,0,0,0)';
      PINUSE='POWER';
      NO_LOAD_CHECK='Both';
      NO_IO_CHECK='Both';
      NO_ASSERT_CHECK='TRUE';
      NO_DIR_CHECK='TRUE';
      ALLOW_CONNECT='TRUE';
    'VSS_AH52':
      PIN_NUMBER='(0,0,0,0,0,0,0,0,0,0,0,0,0,0,0,0,0,0,0,0,0,0,0,0,0,0,0,0,0,0,AH52,0,0,0,0,0,0,0,0,0)';
      PINUSE='POWER';
      NO_LOAD_CHECK='Both';
      NO_IO_CHECK='Both';
      NO_ASSERT_CHECK='TRUE';
      NO_DIR_CHECK='TRUE';
      ALLOW_CONNECT='TRUE';
    'VSS_AH53':
      PIN_NUMBER='(0,0,0,0,0,0,0,0,0,0,0,0,0,0,0,0,0,0,0,0,0,0,0,0,0,0,0,0,0,0,AH53,0,0,0,0,0,0,0,0,0)';
      PINUSE='POWER';
      NO_LOAD_CHECK='Both';
      NO_IO_CHECK='Both';
      NO_ASSERT_CHECK='TRUE';
      NO_DIR_CHECK='TRUE';
      ALLOW_CONNECT='TRUE';
    'VSS_AH57':
      PIN_NUMBER='(0,0,0,0,0,0,0,0,0,0,0,0,0,0,0,0,0,0,0,0,0,0,0,0,0,0,0,0,0,0,AH57,0,0,0,0,0,0,0,0,0)';
      PINUSE='POWER';
      NO_LOAD_CHECK='Both';
      NO_IO_CHECK='Both';
      NO_ASSERT_CHECK='TRUE';
      NO_DIR_CHECK='TRUE';
      ALLOW_CONNECT='TRUE';
    'VSS_AH59':
      PIN_NUMBER='(0,0,0,0,0,0,0,0,0,0,0,0,0,0,0,0,0,0,0,0,0,0,0,0,0,0,0,0,0,0,AH59,0,0,0,0,0,0,0,0,0)';
      PINUSE='POWER';
      NO_LOAD_CHECK='Both';
      NO_IO_CHECK='Both';
      NO_ASSERT_CHECK='TRUE';
      NO_DIR_CHECK='TRUE';
      ALLOW_CONNECT='TRUE';
    'VSS_AH61':
      PIN_NUMBER='(0,0,0,0,0,0,0,0,0,0,0,0,0,0,0,0,0,0,0,0,0,0,0,0,0,0,0,0,0,0,AH61,0,0,0,0,0,0,0,0,0)';
      PINUSE='POWER';
      NO_LOAD_CHECK='Both';
      NO_IO_CHECK='Both';
      NO_ASSERT_CHECK='TRUE';
      NO_DIR_CHECK='TRUE';
      ALLOW_CONNECT='TRUE';
    'VSS_AH64':
      PIN_NUMBER='(0,0,0,0,0,0,0,0,0,0,0,0,0,0,0,0,0,0,0,0,0,0,0,0,0,0,0,0,0,0,AH64,0,0,0,0,0,0,0,0,0)';
      PINUSE='POWER';
      NO_LOAD_CHECK='Both';
      NO_IO_CHECK='Both';
      NO_ASSERT_CHECK='TRUE';
      NO_DIR_CHECK='TRUE';
      ALLOW_CONNECT='TRUE';
    'VSS_AH66':
      PIN_NUMBER='(0,0,0,0,0,0,0,0,0,0,0,0,0,0,0,0,0,0,0,0,0,0,0,0,0,0,0,0,0,0,AH66,0,0,0,0,0,0,0,0,0)';
      PINUSE='POWER';
      NO_LOAD_CHECK='Both';
      NO_IO_CHECK='Both';
      NO_ASSERT_CHECK='TRUE';
      NO_DIR_CHECK='TRUE';
      ALLOW_CONNECT='TRUE';
    'VSS_AH68':
      PIN_NUMBER='(0,0,0,0,0,0,0,0,0,0,0,0,0,0,0,0,0,0,0,0,0,0,0,0,0,0,0,0,0,0,AH68,0,0,0,0,0,0,0,0,0)';
      PINUSE='POWER';
      NO_LOAD_CHECK='Both';
      NO_IO_CHECK='Both';
      NO_ASSERT_CHECK='TRUE';
      NO_DIR_CHECK='TRUE';
      ALLOW_CONNECT='TRUE';
    'VSS_AH71':
      PIN_NUMBER='(0,0,0,0,0,0,0,0,0,0,0,0,0,0,0,0,0,0,0,0,0,0,0,0,0,0,0,0,0,0,AH71,0,0,0,0,0,0,0,0,0)';
      PINUSE='POWER';
      NO_LOAD_CHECK='Both';
      NO_IO_CHECK='Both';
      NO_ASSERT_CHECK='TRUE';
      NO_DIR_CHECK='TRUE';
      ALLOW_CONNECT='TRUE';
    'VSS_AH73':
      PIN_NUMBER='(0,0,0,0,0,0,0,0,0,0,0,0,0,0,0,0,0,0,0,0,0,0,0,0,0,0,0,0,0,0,AH73,0,0,0,0,0,0,0,0,0)';
      PINUSE='POWER';
      NO_LOAD_CHECK='Both';
      NO_IO_CHECK='Both';
      NO_ASSERT_CHECK='TRUE';
      NO_DIR_CHECK='TRUE';
      ALLOW_CONNECT='TRUE';
    'VSS_AJ1':
      PIN_NUMBER='(0,0,0,0,0,0,0,0,0,0,0,0,0,0,0,0,0,0,0,0,0,0,0,0,0,0,0,0,0,0,AJ1,0,0,0,0,0,0,0,0,0)';
      PINUSE='POWER';
      NO_LOAD_CHECK='Both';
      NO_IO_CHECK='Both';
      NO_ASSERT_CHECK='TRUE';
      NO_DIR_CHECK='TRUE';
      ALLOW_CONNECT='TRUE';
    'VSS_AJ6':
      PIN_NUMBER='(0,0,0,0,0,0,0,0,0,0,0,0,0,0,0,0,0,0,0,0,0,0,0,0,0,0,0,0,0,0,AJ6,0,0,0,0,0,0,0,0,0)';
      PINUSE='POWER';
      NO_LOAD_CHECK='Both';
      NO_IO_CHECK='Both';
      NO_ASSERT_CHECK='TRUE';
      NO_DIR_CHECK='TRUE';
      ALLOW_CONNECT='TRUE';
    'VSS_AJ8':
      PIN_NUMBER='(0,0,0,0,0,0,0,0,0,0,0,0,0,0,0,0,0,0,0,0,0,0,0,0,0,0,0,0,0,0,AJ8,0,0,0,0,0,0,0,0,0)';
      PINUSE='POWER';
      NO_LOAD_CHECK='Both';
      NO_IO_CHECK='Both';
      NO_ASSERT_CHECK='TRUE';
      NO_DIR_CHECK='TRUE';
      ALLOW_CONNECT='TRUE';
    'VSS_AJ15':
      PIN_NUMBER='(0,0,0,0,0,0,0,0,0,0,0,0,0,0,0,0,0,0,0,0,0,0,0,0,0,0,0,0,0,0,AJ15,0,0,0,0,0,0,0,0,0)';
      PINUSE='POWER';
      NO_LOAD_CHECK='Both';
      NO_IO_CHECK='Both';
      NO_ASSERT_CHECK='TRUE';
      NO_DIR_CHECK='TRUE';
      ALLOW_CONNECT='TRUE';
    'VSS_AJ20':
      PIN_NUMBER='(0,0,0,0,0,0,0,0,0,0,0,0,0,0,0,0,0,0,0,0,0,0,0,0,0,0,0,0,0,0,AJ20,0,0,0,0,0,0,0,0,0)';
      PINUSE='POWER';
      NO_LOAD_CHECK='Both';
      NO_IO_CHECK='Both';
      NO_ASSERT_CHECK='TRUE';
      NO_DIR_CHECK='TRUE';
      ALLOW_CONNECT='TRUE';
    'VSS_AJ22':
      PIN_NUMBER='(0,0,0,0,0,0,0,0,0,0,0,0,0,0,0,0,0,0,0,0,0,0,0,0,0,0,0,0,0,0,AJ22,0,0,0,0,0,0,0,0,0)';
      PINUSE='POWER';
      NO_LOAD_CHECK='Both';
      NO_IO_CHECK='Both';
      NO_ASSERT_CHECK='TRUE';
      NO_DIR_CHECK='TRUE';
      ALLOW_CONNECT='TRUE';
    'VSS_AJ25':
      PIN_NUMBER='(0,0,0,0,0,0,0,0,0,0,0,0,0,0,0,0,0,0,0,0,0,0,0,0,0,0,0,0,0,0,AJ25,0,0,0,0,0,0,0,0,0)';
      PINUSE='POWER';
      NO_LOAD_CHECK='Both';
      NO_IO_CHECK='Both';
      NO_ASSERT_CHECK='TRUE';
      NO_DIR_CHECK='TRUE';
      ALLOW_CONNECT='TRUE';
    'VSS_AJ28':
      PIN_NUMBER='(0,0,0,0,0,0,0,0,0,0,0,0,0,0,0,0,0,0,0,0,0,0,0,0,0,0,0,0,0,0,AJ28,0,0,0,0,0,0,0,0,0)';
      PINUSE='POWER';
      NO_LOAD_CHECK='Both';
      NO_IO_CHECK='Both';
      NO_ASSERT_CHECK='TRUE';
      NO_DIR_CHECK='TRUE';
      ALLOW_CONNECT='TRUE';
    'VSS_AJ31':
      PIN_NUMBER='(0,0,0,0,0,0,0,0,0,0,0,0,0,0,0,0,0,0,0,0,0,0,0,0,0,0,0,0,0,0,AJ31,0,0,0,0,0,0,0,0,0)';
      PINUSE='POWER';
      NO_LOAD_CHECK='Both';
      NO_IO_CHECK='Both';
      NO_ASSERT_CHECK='TRUE';
      NO_DIR_CHECK='TRUE';
      ALLOW_CONNECT='TRUE';
    'VSS_AJ34':
      PIN_NUMBER='(0,0,0,0,0,0,0,0,0,0,0,0,0,0,0,0,0,0,0,0,0,0,0,0,0,0,0,0,0,0,AJ34,0,0,0,0,0,0,0,0,0)';
      PINUSE='POWER';
      NO_LOAD_CHECK='Both';
      NO_IO_CHECK='Both';
      NO_ASSERT_CHECK='TRUE';
      NO_DIR_CHECK='TRUE';
      ALLOW_CONNECT='TRUE';
    'VSS_AJ35':
      PIN_NUMBER='(0,0,0,0,0,0,0,0,0,0,0,0,0,0,0,0,0,0,0,0,0,0,0,0,0,0,0,0,0,0,AJ35,0,0,0,0,0,0,0,0,0)';
      PINUSE='POWER';
      NO_LOAD_CHECK='Both';
      NO_IO_CHECK='Both';
      NO_ASSERT_CHECK='TRUE';
      NO_DIR_CHECK='TRUE';
      ALLOW_CONNECT='TRUE';
    'VSS_AJ36':
      PIN_NUMBER='(0,0,0,0,0,0,0,0,0,0,0,0,0,0,0,0,0,0,0,0,0,0,0,0,0,0,0,0,0,0,AJ36,0,0,0,0,0,0,0,0,0)';
      PINUSE='POWER';
      NO_LOAD_CHECK='Both';
      NO_IO_CHECK='Both';
      NO_ASSERT_CHECK='TRUE';
      NO_DIR_CHECK='TRUE';
      ALLOW_CONNECT='TRUE';
    'VSS_AJ40':
      PIN_NUMBER='(0,0,0,0,0,0,0,0,0,0,0,0,0,0,0,0,0,0,0,0,0,0,0,0,0,0,0,0,0,0,AJ40,0,0,0,0,0,0,0,0,0)';
      PINUSE='POWER';
      NO_LOAD_CHECK='Both';
      NO_IO_CHECK='Both';
      NO_ASSERT_CHECK='TRUE';
      NO_DIR_CHECK='TRUE';
      ALLOW_CONNECT='TRUE';
    'VSS_AJ41':
      PIN_NUMBER='(0,0,0,0,0,0,0,0,0,0,0,0,0,0,0,0,0,0,0,0,0,0,0,0,0,0,0,0,0,0,AJ41,0,0,0,0,0,0,0,0,0)';
      PINUSE='POWER';
      NO_LOAD_CHECK='Both';
      NO_IO_CHECK='Both';
      NO_ASSERT_CHECK='TRUE';
      NO_DIR_CHECK='TRUE';
      ALLOW_CONNECT='TRUE';
    'VSS_AJ42':
      PIN_NUMBER='(0,0,0,0,0,0,0,0,0,0,0,0,0,0,0,0,0,0,0,0,0,0,0,0,0,0,0,0,0,0,AJ42,0,0,0,0,0,0,0,0,0)';
      PINUSE='POWER';
      NO_LOAD_CHECK='Both';
      NO_IO_CHECK='Both';
      NO_ASSERT_CHECK='TRUE';
      NO_DIR_CHECK='TRUE';
      ALLOW_CONNECT='TRUE';
    'VSS_AJ45':
      PIN_NUMBER='(0,0,0,0,0,0,0,0,0,0,0,0,0,0,0,0,0,0,0,0,0,0,0,0,0,0,0,0,0,0,AJ45,0,0,0,0,0,0,0,0,0)';
      PINUSE='POWER';
      NO_LOAD_CHECK='Both';
      NO_IO_CHECK='Both';
      NO_ASSERT_CHECK='TRUE';
      NO_DIR_CHECK='TRUE';
      ALLOW_CONNECT='TRUE';
    'VSS_AJ48':
      PIN_NUMBER='(0,0,0,0,0,0,0,0,0,0,0,0,0,0,0,0,0,0,0,0,0,0,0,0,0,0,0,0,0,0,AJ48,0,0,0,0,0,0,0,0,0)';
      PINUSE='POWER';
      NO_LOAD_CHECK='Both';
      NO_IO_CHECK='Both';
      NO_ASSERT_CHECK='TRUE';
      NO_DIR_CHECK='TRUE';
      ALLOW_CONNECT='TRUE';
    'VSS_AJ51':
      PIN_NUMBER='(0,0,0,0,0,0,0,0,0,0,0,0,0,0,0,0,0,0,0,0,0,0,0,0,0,0,0,0,0,0,AJ51,0,0,0,0,0,0,0,0,0)';
      PINUSE='POWER';
      NO_LOAD_CHECK='Both';
      NO_IO_CHECK='Both';
      NO_ASSERT_CHECK='TRUE';
      NO_DIR_CHECK='TRUE';
      ALLOW_CONNECT='TRUE';
    'VSS_AJ54':
      PIN_NUMBER='(0,0,0,0,0,0,0,0,0,0,0,0,0,0,0,0,0,0,0,0,0,0,0,0,0,0,0,0,0,0,AJ54,0,0,0,0,0,0,0,0,0)';
      PINUSE='POWER';
      NO_LOAD_CHECK='Both';
      NO_IO_CHECK='Both';
      NO_ASSERT_CHECK='TRUE';
      NO_DIR_CHECK='TRUE';
      ALLOW_CONNECT='TRUE';
    'VSS_AJ56':
      PIN_NUMBER='(0,0,0,0,0,0,0,0,0,0,0,0,0,0,0,0,0,0,0,0,0,0,0,0,0,0,0,0,0,0,AJ56,0,0,0,0,0,0,0,0,0)';
      PINUSE='POWER';
      NO_LOAD_CHECK='Both';
      NO_IO_CHECK='Both';
      NO_ASSERT_CHECK='TRUE';
      NO_DIR_CHECK='TRUE';
      ALLOW_CONNECT='TRUE';
    'VSS_AJ61':
      PIN_NUMBER='(0,0,0,0,0,0,0,0,0,0,0,0,0,0,0,0,0,0,0,0,0,0,0,0,0,0,0,0,0,0,AJ61,0,0,0,0,0,0,0,0,0)';
      PINUSE='POWER';
      NO_LOAD_CHECK='Both';
      NO_IO_CHECK='Both';
      NO_ASSERT_CHECK='TRUE';
      NO_DIR_CHECK='TRUE';
      ALLOW_CONNECT='TRUE';
    'VSS_AJ63':
      PIN_NUMBER='(0,0,0,0,0,0,0,0,0,0,0,0,0,0,0,0,0,0,0,0,0,0,0,0,0,0,0,0,0,0,AJ63,0,0,0,0,0,0,0,0,0)';
      PINUSE='POWER';
      NO_LOAD_CHECK='Both';
      NO_IO_CHECK='Both';
      NO_ASSERT_CHECK='TRUE';
      NO_DIR_CHECK='TRUE';
      ALLOW_CONNECT='TRUE';
    'VSS_AJ68':
      PIN_NUMBER='(0,0,0,0,0,0,0,0,0,0,0,0,0,0,0,0,0,0,0,0,0,0,0,0,0,0,0,0,0,0,AJ68,0,0,0,0,0,0,0,0,0)';
      PINUSE='POWER';
      NO_LOAD_CHECK='Both';
      NO_IO_CHECK='Both';
      NO_ASSERT_CHECK='TRUE';
      NO_DIR_CHECK='TRUE';
      ALLOW_CONNECT='TRUE';
    'VSS_AJ70':
      PIN_NUMBER='(0,0,0,0,0,0,0,0,0,0,0,0,0,0,0,0,0,0,0,0,0,0,0,0,0,0,0,0,0,0,AJ70,0,0,0,0,0,0,0,0,0)';
      PINUSE='POWER';
      NO_LOAD_CHECK='Both';
      NO_IO_CHECK='Both';
      NO_ASSERT_CHECK='TRUE';
      NO_DIR_CHECK='TRUE';
      ALLOW_CONNECT='TRUE';
    'VSS_AJ75':
      PIN_NUMBER='(0,0,0,0,0,0,0,0,0,0,0,0,0,0,0,0,0,0,0,0,0,0,0,0,0,0,0,0,0,0,AJ75,0,0,0,0,0,0,0,0,0)';
      PINUSE='POWER';
      NO_LOAD_CHECK='Both';
      NO_IO_CHECK='Both';
      NO_ASSERT_CHECK='TRUE';
      NO_DIR_CHECK='TRUE';
      ALLOW_CONNECT='TRUE';
    'VSS_AK3':
      PIN_NUMBER='(0,0,0,0,0,0,0,0,0,0,0,0,0,0,0,0,0,0,0,0,0,0,0,0,0,0,0,0,0,0,AK3,0,0,0,0,0,0,0,0,0)';
      PINUSE='POWER';
      NO_LOAD_CHECK='Both';
      NO_IO_CHECK='Both';
      NO_ASSERT_CHECK='TRUE';
      NO_DIR_CHECK='TRUE';
      ALLOW_CONNECT='TRUE';
    'VSS_AK5':
      PIN_NUMBER='(0,0,0,0,0,0,0,0,0,0,0,0,0,0,0,0,0,0,0,0,0,0,0,0,0,0,0,0,0,0,AK5,0,0,0,0,0,0,0,0,0)';
      PINUSE='POWER';
      NO_LOAD_CHECK='Both';
      NO_IO_CHECK='Both';
      NO_ASSERT_CHECK='TRUE';
      NO_DIR_CHECK='TRUE';
      ALLOW_CONNECT='TRUE';
    'VSS_AK8':
      PIN_NUMBER='(0,0,0,0,0,0,0,0,0,0,0,0,0,0,0,0,0,0,0,0,0,0,0,0,0,0,0,0,0,0,AK8,0,0,0,0,0,0,0,0,0)';
      PINUSE='POWER';
      NO_LOAD_CHECK='Both';
      NO_IO_CHECK='Both';
      NO_ASSERT_CHECK='TRUE';
      NO_DIR_CHECK='TRUE';
      ALLOW_CONNECT='TRUE';
    'VSS_AM42':
      PIN_NUMBER='(0,0,0,0,0,0,0,0,0,0,0,0,0,0,0,0,0,0,0,0,0,0,0,0,0,0,0,0,0,0,0,AM42,0,0,0,0,0,0,0,0)';
      PINUSE='POWER';
      NO_LOAD_CHECK='Both';
      NO_IO_CHECK='Both';
      NO_ASSERT_CHECK='TRUE';
      NO_DIR_CHECK='TRUE';
      ALLOW_CONNECT='TRUE';
    'VSS_AM43':
      PIN_NUMBER='(0,0,0,0,0,0,0,0,0,0,0,0,0,0,0,0,0,0,0,0,0,0,0,0,0,0,0,0,0,0,0,AM43,0,0,0,0,0,0,0,0)';
      PINUSE='POWER';
      NO_LOAD_CHECK='Both';
      NO_IO_CHECK='Both';
      NO_ASSERT_CHECK='TRUE';
      NO_DIR_CHECK='TRUE';
      ALLOW_CONNECT='TRUE';
    'VSS_AM44':
      PIN_NUMBER='(0,0,0,0,0,0,0,0,0,0,0,0,0,0,0,0,0,0,0,0,0,0,0,0,0,0,0,0,0,0,0,AM44,0,0,0,0,0,0,0,0)';
      PINUSE='POWER';
      NO_LOAD_CHECK='Both';
      NO_IO_CHECK='Both';
      NO_ASSERT_CHECK='TRUE';
      NO_DIR_CHECK='TRUE';
      ALLOW_CONNECT='TRUE';
    'VSS_AM45':
      PIN_NUMBER='(0,0,0,0,0,0,0,0,0,0,0,0,0,0,0,0,0,0,0,0,0,0,0,0,0,0,0,0,0,0,0,AM45,0,0,0,0,0,0,0,0)';
      PINUSE='POWER';
      NO_LOAD_CHECK='Both';
      NO_IO_CHECK='Both';
      NO_ASSERT_CHECK='TRUE';
      NO_DIR_CHECK='TRUE';
      ALLOW_CONNECT='TRUE';
    'VSS_AM46':
      PIN_NUMBER='(0,0,0,0,0,0,0,0,0,0,0,0,0,0,0,0,0,0,0,0,0,0,0,0,0,0,0,0,0,0,0,AM46,0,0,0,0,0,0,0,0)';
      PINUSE='POWER';
      NO_LOAD_CHECK='Both';
      NO_IO_CHECK='Both';
      NO_ASSERT_CHECK='TRUE';
      NO_DIR_CHECK='TRUE';
      ALLOW_CONNECT='TRUE';
    'VSS_AM47':
      PIN_NUMBER='(0,0,0,0,0,0,0,0,0,0,0,0,0,0,0,0,0,0,0,0,0,0,0,0,0,0,0,0,0,0,0,AM47,0,0,0,0,0,0,0,0)';
      PINUSE='POWER';
      NO_LOAD_CHECK='Both';
      NO_IO_CHECK='Both';
      NO_ASSERT_CHECK='TRUE';
      NO_DIR_CHECK='TRUE';
      ALLOW_CONNECT='TRUE';
    'VSS_AM48':
      PIN_NUMBER='(0,0,0,0,0,0,0,0,0,0,0,0,0,0,0,0,0,0,0,0,0,0,0,0,0,0,0,0,0,0,0,AM48,0,0,0,0,0,0,0,0)';
      PINUSE='POWER';
      NO_LOAD_CHECK='Both';
      NO_IO_CHECK='Both';
      NO_ASSERT_CHECK='TRUE';
      NO_DIR_CHECK='TRUE';
      ALLOW_CONNECT='TRUE';
    'VSS_AM49':
      PIN_NUMBER='(0,0,0,0,0,0,0,0,0,0,0,0,0,0,0,0,0,0,0,0,0,0,0,0,0,0,0,0,0,0,0,AM49,0,0,0,0,0,0,0,0)';
      PINUSE='POWER';
      NO_LOAD_CHECK='Both';
      NO_IO_CHECK='Both';
      NO_ASSERT_CHECK='TRUE';
      NO_DIR_CHECK='TRUE';
      ALLOW_CONNECT='TRUE';
    'VSS_AM50':
      PIN_NUMBER='(0,0,0,0,0,0,0,0,0,0,0,0,0,0,0,0,0,0,0,0,0,0,0,0,0,0,0,0,0,0,0,AM50,0,0,0,0,0,0,0,0)';
      PINUSE='POWER';
      NO_LOAD_CHECK='Both';
      NO_IO_CHECK='Both';
      NO_ASSERT_CHECK='TRUE';
      NO_DIR_CHECK='TRUE';
      ALLOW_CONNECT='TRUE';
    'VSS_AM51':
      PIN_NUMBER='(0,0,0,0,0,0,0,0,0,0,0,0,0,0,0,0,0,0,0,0,0,0,0,0,0,0,0,0,0,0,0,AM51,0,0,0,0,0,0,0,0)';
      PINUSE='POWER';
      NO_LOAD_CHECK='Both';
      NO_IO_CHECK='Both';
      NO_ASSERT_CHECK='TRUE';
      NO_DIR_CHECK='TRUE';
      ALLOW_CONNECT='TRUE';
    'VSS_AM52':
      PIN_NUMBER='(0,0,0,0,0,0,0,0,0,0,0,0,0,0,0,0,0,0,0,0,0,0,0,0,0,0,0,0,0,0,0,AM52,0,0,0,0,0,0,0,0)';
      PINUSE='POWER';
      NO_LOAD_CHECK='Both';
      NO_IO_CHECK='Both';
      NO_ASSERT_CHECK='TRUE';
      NO_DIR_CHECK='TRUE';
      ALLOW_CONNECT='TRUE';
    'VSS_AM53':
      PIN_NUMBER='(0,0,0,0,0,0,0,0,0,0,0,0,0,0,0,0,0,0,0,0,0,0,0,0,0,0,0,0,0,0,0,AM53,0,0,0,0,0,0,0,0)';
      PINUSE='POWER';
      NO_LOAD_CHECK='Both';
      NO_IO_CHECK='Both';
      NO_ASSERT_CHECK='TRUE';
      NO_DIR_CHECK='TRUE';
      ALLOW_CONNECT='TRUE';
    'VSS_AM59':
      PIN_NUMBER='(0,0,0,0,0,0,0,0,0,0,0,0,0,0,0,0,0,0,0,0,0,0,0,0,0,0,0,0,0,0,0,AM59,0,0,0,0,0,0,0,0)';
      PINUSE='POWER';
      NO_LOAD_CHECK='Both';
      NO_IO_CHECK='Both';
      NO_ASSERT_CHECK='TRUE';
      NO_DIR_CHECK='TRUE';
      ALLOW_CONNECT='TRUE';
    'VSS_AM61':
      PIN_NUMBER='(0,0,0,0,0,0,0,0,0,0,0,0,0,0,0,0,0,0,0,0,0,0,0,0,0,0,0,0,0,0,0,AM61,0,0,0,0,0,0,0,0)';
      PINUSE='POWER';
      NO_LOAD_CHECK='Both';
      NO_IO_CHECK='Both';
      NO_ASSERT_CHECK='TRUE';
      NO_DIR_CHECK='TRUE';
      ALLOW_CONNECT='TRUE';
    'VSS_AM66':
      PIN_NUMBER='(0,0,0,0,0,0,0,0,0,0,0,0,0,0,0,0,0,0,0,0,0,0,0,0,0,0,0,0,0,0,0,AM66,0,0,0,0,0,0,0,0)';
      PINUSE='POWER';
      NO_LOAD_CHECK='Both';
      NO_IO_CHECK='Both';
      NO_ASSERT_CHECK='TRUE';
      NO_DIR_CHECK='TRUE';
      ALLOW_CONNECT='TRUE';
    'VSS_AM68':
      PIN_NUMBER='(0,0,0,0,0,0,0,0,0,0,0,0,0,0,0,0,0,0,0,0,0,0,0,0,0,0,0,0,0,0,0,AM68,0,0,0,0,0,0,0,0)';
      PINUSE='POWER';
      NO_LOAD_CHECK='Both';
      NO_IO_CHECK='Both';
      NO_ASSERT_CHECK='TRUE';
      NO_DIR_CHECK='TRUE';
      ALLOW_CONNECT='TRUE';
    'VSS_AM73':
      PIN_NUMBER='(0,0,0,0,0,0,0,0,0,0,0,0,0,0,0,0,0,0,0,0,0,0,0,0,0,0,0,0,0,0,0,AM73,0,0,0,0,0,0,0,0)';
      PINUSE='POWER';
      NO_LOAD_CHECK='Both';
      NO_IO_CHECK='Both';
      NO_ASSERT_CHECK='TRUE';
      NO_DIR_CHECK='TRUE';
      ALLOW_CONNECT='TRUE';
    'VSS_AN1':
      PIN_NUMBER='(0,0,0,0,0,0,0,0,0,0,0,0,0,0,0,0,0,0,0,0,0,0,0,0,0,0,0,0,0,0,0,AN1,0,0,0,0,0,0,0,0)';
      PINUSE='POWER';
      NO_LOAD_CHECK='Both';
      NO_IO_CHECK='Both';
      NO_ASSERT_CHECK='TRUE';
      NO_DIR_CHECK='TRUE';
      ALLOW_CONNECT='TRUE';
    'VSS_AN4':
      PIN_NUMBER='(0,0,0,0,0,0,0,0,0,0,0,0,0,0,0,0,0,0,0,0,0,0,0,0,0,0,0,0,0,0,0,AN4,0,0,0,0,0,0,0,0)';
      PINUSE='POWER';
      NO_LOAD_CHECK='Both';
      NO_IO_CHECK='Both';
      NO_ASSERT_CHECK='TRUE';
      NO_DIR_CHECK='TRUE';
      ALLOW_CONNECT='TRUE';
    'VSS_AN6':
      PIN_NUMBER='(0,0,0,0,0,0,0,0,0,0,0,0,0,0,0,0,0,0,0,0,0,0,0,0,0,0,0,0,0,0,0,AN6,0,0,0,0,0,0,0,0)';
      PINUSE='POWER';
      NO_LOAD_CHECK='Both';
      NO_IO_CHECK='Both';
      NO_ASSERT_CHECK='TRUE';
      NO_DIR_CHECK='TRUE';
      ALLOW_CONNECT='TRUE';
    'VSS_AN8':
      PIN_NUMBER='(0,0,0,0,0,0,0,0,0,0,0,0,0,0,0,0,0,0,0,0,0,0,0,0,0,0,0,0,0,0,0,AN8,0,0,0,0,0,0,0,0)';
      PINUSE='POWER';
      NO_LOAD_CHECK='Both';
      NO_IO_CHECK='Both';
      NO_ASSERT_CHECK='TRUE';
      NO_DIR_CHECK='TRUE';
      ALLOW_CONNECT='TRUE';
    'VSS_AN11':
      PIN_NUMBER='(0,0,0,0,0,0,0,0,0,0,0,0,0,0,0,0,0,0,0,0,0,0,0,0,0,0,0,0,0,0,0,AN11,0,0,0,0,0,0,0,0)';
      PINUSE='POWER';
      NO_LOAD_CHECK='Both';
      NO_IO_CHECK='Both';
      NO_ASSERT_CHECK='TRUE';
      NO_DIR_CHECK='TRUE';
      ALLOW_CONNECT='TRUE';
    'VSS_AN13':
      PIN_NUMBER='(0,0,0,0,0,0,0,0,0,0,0,0,0,0,0,0,0,0,0,0,0,0,0,0,0,0,0,0,0,0,0,AN13,0,0,0,0,0,0,0,0)';
      PINUSE='POWER';
      NO_LOAD_CHECK='Both';
      NO_IO_CHECK='Both';
      NO_ASSERT_CHECK='TRUE';
      NO_DIR_CHECK='TRUE';
      ALLOW_CONNECT='TRUE';
    'VSS_AN15':
      PIN_NUMBER='(0,0,0,0,0,0,0,0,0,0,0,0,0,0,0,0,0,0,0,0,0,0,0,0,0,0,0,0,0,0,0,AN15,0,0,0,0,0,0,0,0)';
      PINUSE='POWER';
      NO_LOAD_CHECK='Both';
      NO_IO_CHECK='Both';
      NO_ASSERT_CHECK='TRUE';
      NO_DIR_CHECK='TRUE';
      ALLOW_CONNECT='TRUE';
    'VSS_AN18':
      PIN_NUMBER='(0,0,0,0,0,0,0,0,0,0,0,0,0,0,0,0,0,0,0,0,0,0,0,0,0,0,0,0,0,0,0,AN18,0,0,0,0,0,0,0,0)';
      PINUSE='POWER';
      NO_LOAD_CHECK='Both';
      NO_IO_CHECK='Both';
      NO_ASSERT_CHECK='TRUE';
      NO_DIR_CHECK='TRUE';
      ALLOW_CONNECT='TRUE';
    'VSS_AN22':
      PIN_NUMBER='(0,0,0,0,0,0,0,0,0,0,0,0,0,0,0,0,0,0,0,0,0,0,0,0,0,0,0,0,0,0,0,AN22,0,0,0,0,0,0,0,0)';
      PINUSE='POWER';
      NO_LOAD_CHECK='Both';
      NO_IO_CHECK='Both';
      NO_ASSERT_CHECK='TRUE';
      NO_DIR_CHECK='TRUE';
      ALLOW_CONNECT='TRUE';
    'VSS_AN25':
      PIN_NUMBER='(0,0,0,0,0,0,0,0,0,0,0,0,0,0,0,0,0,0,0,0,0,0,0,0,0,0,0,0,0,0,0,AN25,0,0,0,0,0,0,0,0)';
      PINUSE='POWER';
      NO_LOAD_CHECK='Both';
      NO_IO_CHECK='Both';
      NO_ASSERT_CHECK='TRUE';
      NO_DIR_CHECK='TRUE';
      ALLOW_CONNECT='TRUE';
    'VSS_AN28':
      PIN_NUMBER='(0,0,0,0,0,0,0,0,0,0,0,0,0,0,0,0,0,0,0,0,0,0,0,0,0,0,0,0,0,0,0,AN28,0,0,0,0,0,0,0,0)';
      PINUSE='POWER';
      NO_LOAD_CHECK='Both';
      NO_IO_CHECK='Both';
      NO_ASSERT_CHECK='TRUE';
      NO_DIR_CHECK='TRUE';
      ALLOW_CONNECT='TRUE';
    'VSS_AN31':
      PIN_NUMBER='(0,0,0,0,0,0,0,0,0,0,0,0,0,0,0,0,0,0,0,0,0,0,0,0,0,0,0,0,0,0,0,AN31,0,0,0,0,0,0,0,0)';
      PINUSE='POWER';
      NO_LOAD_CHECK='Both';
      NO_IO_CHECK='Both';
      NO_ASSERT_CHECK='TRUE';
      NO_DIR_CHECK='TRUE';
      ALLOW_CONNECT='TRUE';
    'VSS_AN34':
      PIN_NUMBER='(0,0,0,0,0,0,0,0,0,0,0,0,0,0,0,0,0,0,0,0,0,0,0,0,0,0,0,0,0,0,0,AN34,0,0,0,0,0,0,0,0)';
      PINUSE='POWER';
      NO_LOAD_CHECK='Both';
      NO_IO_CHECK='Both';
      NO_ASSERT_CHECK='TRUE';
      NO_DIR_CHECK='TRUE';
      ALLOW_CONNECT='TRUE';
    'VSS_AN35':
      PIN_NUMBER='(0,0,0,0,0,0,0,0,0,0,0,0,0,0,0,0,0,0,0,0,0,0,0,0,0,0,0,0,0,0,0,AN35,0,0,0,0,0,0,0,0)';
      PINUSE='POWER';
      NO_LOAD_CHECK='Both';
      NO_IO_CHECK='Both';
      NO_ASSERT_CHECK='TRUE';
      NO_DIR_CHECK='TRUE';
      ALLOW_CONNECT='TRUE';
    'VSS_AN36':
      PIN_NUMBER='(0,0,0,0,0,0,0,0,0,0,0,0,0,0,0,0,0,0,0,0,0,0,0,0,0,0,0,0,0,0,0,AN36,0,0,0,0,0,0,0,0)';
      PINUSE='POWER';
      NO_LOAD_CHECK='Both';
      NO_IO_CHECK='Both';
      NO_ASSERT_CHECK='TRUE';
      NO_DIR_CHECK='TRUE';
      ALLOW_CONNECT='TRUE';
    'VSS_AN40':
      PIN_NUMBER='(0,0,0,0,0,0,0,0,0,0,0,0,0,0,0,0,0,0,0,0,0,0,0,0,0,0,0,0,0,0,0,AN40,0,0,0,0,0,0,0,0)';
      PINUSE='POWER';
      NO_LOAD_CHECK='Both';
      NO_IO_CHECK='Both';
      NO_ASSERT_CHECK='TRUE';
      NO_DIR_CHECK='TRUE';
      ALLOW_CONNECT='TRUE';
    'VSS_AN41':
      PIN_NUMBER='(0,0,0,0,0,0,0,0,0,0,0,0,0,0,0,0,0,0,0,0,0,0,0,0,0,0,0,0,0,0,0,AN41,0,0,0,0,0,0,0,0)';
      PINUSE='POWER';
      NO_LOAD_CHECK='Both';
      NO_IO_CHECK='Both';
      NO_ASSERT_CHECK='TRUE';
      NO_DIR_CHECK='TRUE';
      ALLOW_CONNECT='TRUE';
    'VSS_AN42':
      PIN_NUMBER='(0,0,0,0,0,0,0,0,0,0,0,0,0,0,0,0,0,0,0,0,0,0,0,0,0,0,0,0,0,0,0,AN42,0,0,0,0,0,0,0,0)';
      PINUSE='POWER';
      NO_LOAD_CHECK='Both';
      NO_IO_CHECK='Both';
      NO_ASSERT_CHECK='TRUE';
      NO_DIR_CHECK='TRUE';
      ALLOW_CONNECT='TRUE';
    'VSS_AN45':
      PIN_NUMBER='(0,0,0,0,0,0,0,0,0,0,0,0,0,0,0,0,0,0,0,0,0,0,0,0,0,0,0,0,0,0,0,AN45,0,0,0,0,0,0,0,0)';
      PINUSE='POWER';
      NO_LOAD_CHECK='Both';
      NO_IO_CHECK='Both';
      NO_ASSERT_CHECK='TRUE';
      NO_DIR_CHECK='TRUE';
      ALLOW_CONNECT='TRUE';
    'VSS_AN48':
      PIN_NUMBER='(0,0,0,0,0,0,0,0,0,0,0,0,0,0,0,0,0,0,0,0,0,0,0,0,0,0,0,0,0,0,0,AN48,0,0,0,0,0,0,0,0)';
      PINUSE='POWER';
      NO_LOAD_CHECK='Both';
      NO_IO_CHECK='Both';
      NO_ASSERT_CHECK='TRUE';
      NO_DIR_CHECK='TRUE';
      ALLOW_CONNECT='TRUE';
    'VSS_AN51':
      PIN_NUMBER='(0,0,0,0,0,0,0,0,0,0,0,0,0,0,0,0,0,0,0,0,0,0,0,0,0,0,0,0,0,0,0,AN51,0,0,0,0,0,0,0,0)';
      PINUSE='POWER';
      NO_LOAD_CHECK='Both';
      NO_IO_CHECK='Both';
      NO_ASSERT_CHECK='TRUE';
      NO_DIR_CHECK='TRUE';
      ALLOW_CONNECT='TRUE';
    'VSS_AN54':
      PIN_NUMBER='(0,0,0,0,0,0,0,0,0,0,0,0,0,0,0,0,0,0,0,0,0,0,0,0,0,0,0,0,0,0,0,AN54,0,0,0,0,0,0,0,0)';
      PINUSE='POWER';
      NO_LOAD_CHECK='Both';
      NO_IO_CHECK='Both';
      NO_ASSERT_CHECK='TRUE';
      NO_DIR_CHECK='TRUE';
      ALLOW_CONNECT='TRUE';
    'VSS_AN56':
      PIN_NUMBER='(0,0,0,0,0,0,0,0,0,0,0,0,0,0,0,0,0,0,0,0,0,0,0,0,0,0,0,0,0,0,0,AN56,0,0,0,0,0,0,0,0)';
      PINUSE='POWER';
      NO_LOAD_CHECK='Both';
      NO_IO_CHECK='Both';
      NO_ASSERT_CHECK='TRUE';
      NO_DIR_CHECK='TRUE';
      ALLOW_CONNECT='TRUE';
    'VSS_AN58':
      PIN_NUMBER='(0,0,0,0,0,0,0,0,0,0,0,0,0,0,0,0,0,0,0,0,0,0,0,0,0,0,0,0,0,0,0,AN58,0,0,0,0,0,0,0,0)';
      PINUSE='POWER';
      NO_LOAD_CHECK='Both';
      NO_IO_CHECK='Both';
      NO_ASSERT_CHECK='TRUE';
      NO_DIR_CHECK='TRUE';
      ALLOW_CONNECT='TRUE';
    'VSS_AN61':
      PIN_NUMBER='(0,0,0,0,0,0,0,0,0,0,0,0,0,0,0,0,0,0,0,0,0,0,0,0,0,0,0,0,0,0,0,AN61,0,0,0,0,0,0,0,0)';
      PINUSE='POWER';
      NO_LOAD_CHECK='Both';
      NO_IO_CHECK='Both';
      NO_ASSERT_CHECK='TRUE';
      NO_DIR_CHECK='TRUE';
      ALLOW_CONNECT='TRUE';
    'VSS_AN63':
      PIN_NUMBER='(0,0,0,0,0,0,0,0,0,0,0,0,0,0,0,0,0,0,0,0,0,0,0,0,0,0,0,0,0,0,0,AN63,0,0,0,0,0,0,0,0)';
      PINUSE='POWER';
      NO_LOAD_CHECK='Both';
      NO_IO_CHECK='Both';
      NO_ASSERT_CHECK='TRUE';
      NO_DIR_CHECK='TRUE';
      ALLOW_CONNECT='TRUE';
    'VSS_AN65':
      PIN_NUMBER='(0,0,0,0,0,0,0,0,0,0,0,0,0,0,0,0,0,0,0,0,0,0,0,0,0,0,0,0,0,0,0,AN65,0,0,0,0,0,0,0,0)';
      PINUSE='POWER';
      NO_LOAD_CHECK='Both';
      NO_IO_CHECK='Both';
      NO_ASSERT_CHECK='TRUE';
      NO_DIR_CHECK='TRUE';
      ALLOW_CONNECT='TRUE';
    'VSS_AN68':
      PIN_NUMBER='(0,0,0,0,0,0,0,0,0,0,0,0,0,0,0,0,0,0,0,0,0,0,0,0,0,0,0,0,0,0,0,AN68,0,0,0,0,0,0,0,0)';
      PINUSE='POWER';
      NO_LOAD_CHECK='Both';
      NO_IO_CHECK='Both';
      NO_ASSERT_CHECK='TRUE';
      NO_DIR_CHECK='TRUE';
      ALLOW_CONNECT='TRUE';
    'VSS_AN70':
      PIN_NUMBER='(0,0,0,0,0,0,0,0,0,0,0,0,0,0,0,0,0,0,0,0,0,0,0,0,0,0,0,0,0,0,0,AN70,0,0,0,0,0,0,0,0)';
      PINUSE='POWER';
      NO_LOAD_CHECK='Both';
      NO_IO_CHECK='Both';
      NO_ASSERT_CHECK='TRUE';
      NO_DIR_CHECK='TRUE';
      ALLOW_CONNECT='TRUE';
    'VSS_AN72':
      PIN_NUMBER='(0,0,0,0,0,0,0,0,0,0,0,0,0,0,0,0,0,0,0,0,0,0,0,0,0,0,0,0,0,0,0,AN72,0,0,0,0,0,0,0,0)';
      PINUSE='POWER';
      NO_LOAD_CHECK='Both';
      NO_IO_CHECK='Both';
      NO_ASSERT_CHECK='TRUE';
      NO_DIR_CHECK='TRUE';
      ALLOW_CONNECT='TRUE';
    'VSS_AN75':
      PIN_NUMBER='(0,0,0,0,0,0,0,0,0,0,0,0,0,0,0,0,0,0,0,0,0,0,0,0,0,0,0,0,0,0,0,AN75,0,0,0,0,0,0,0,0)';
      PINUSE='POWER';
      NO_LOAD_CHECK='Both';
      NO_IO_CHECK='Both';
      NO_ASSERT_CHECK='TRUE';
      NO_DIR_CHECK='TRUE';
      ALLOW_CONNECT='TRUE';
    'VSS_AP3':
      PIN_NUMBER='(0,0,0,0,0,0,0,0,0,0,0,0,0,0,0,0,0,0,0,0,0,0,0,0,0,0,0,0,0,0,0,AP3,0,0,0,0,0,0,0,0)';
      PINUSE='POWER';
      NO_LOAD_CHECK='Both';
      NO_IO_CHECK='Both';
      NO_ASSERT_CHECK='TRUE';
      NO_DIR_CHECK='TRUE';
      ALLOW_CONNECT='TRUE';
    'VSS_AP5':
      PIN_NUMBER='(0,0,0,0,0,0,0,0,0,0,0,0,0,0,0,0,0,0,0,0,0,0,0,0,0,0,0,0,0,0,0,AP5,0,0,0,0,0,0,0,0)';
      PINUSE='POWER';
      NO_LOAD_CHECK='Both';
      NO_IO_CHECK='Both';
      NO_ASSERT_CHECK='TRUE';
      NO_DIR_CHECK='TRUE';
      ALLOW_CONNECT='TRUE';
    'VSS_AP8':
      PIN_NUMBER='(0,0,0,0,0,0,0,0,0,0,0,0,0,0,0,0,0,0,0,0,0,0,0,0,0,0,0,0,0,0,0,AP8,0,0,0,0,0,0,0,0)';
      PINUSE='POWER';
      NO_LOAD_CHECK='Both';
      NO_IO_CHECK='Both';
      NO_ASSERT_CHECK='TRUE';
      NO_DIR_CHECK='TRUE';
      ALLOW_CONNECT='TRUE';
    'VSS_AP10':
      PIN_NUMBER='(0,0,0,0,0,0,0,0,0,0,0,0,0,0,0,0,0,0,0,0,0,0,0,0,0,0,0,0,0,0,0,AP10,0,0,0,0,0,0,0,0)';
      PINUSE='POWER';
      NO_LOAD_CHECK='Both';
      NO_IO_CHECK='Both';
      NO_ASSERT_CHECK='TRUE';
      NO_DIR_CHECK='TRUE';
      ALLOW_CONNECT='TRUE';
    'VSS_AP12':
      PIN_NUMBER='(0,0,0,0,0,0,0,0,0,0,0,0,0,0,0,0,0,0,0,0,0,0,0,0,0,0,0,0,0,0,0,AP12,0,0,0,0,0,0,0,0)';
      PINUSE='POWER';
      NO_LOAD_CHECK='Both';
      NO_IO_CHECK='Both';
      NO_ASSERT_CHECK='TRUE';
      NO_DIR_CHECK='TRUE';
      ALLOW_CONNECT='TRUE';
    'VSS_AP15':
      PIN_NUMBER='(0,0,0,0,0,0,0,0,0,0,0,0,0,0,0,0,0,0,0,0,0,0,0,0,0,0,0,0,0,0,0,AP15,0,0,0,0,0,0,0,0)';
      PINUSE='POWER';
      NO_LOAD_CHECK='Both';
      NO_IO_CHECK='Both';
      NO_ASSERT_CHECK='TRUE';
      NO_DIR_CHECK='TRUE';
      ALLOW_CONNECT='TRUE';
    'VSS_AP17':
      PIN_NUMBER='(0,0,0,0,0,0,0,0,0,0,0,0,0,0,0,0,0,0,0,0,0,0,0,0,0,0,0,0,0,0,0,AP17,0,0,0,0,0,0,0,0)';
      PINUSE='POWER';
      NO_LOAD_CHECK='Both';
      NO_IO_CHECK='Both';
      NO_ASSERT_CHECK='TRUE';
      NO_DIR_CHECK='TRUE';
      ALLOW_CONNECT='TRUE';
    'VSS_AP19':
      PIN_NUMBER='(0,0,0,0,0,0,0,0,0,0,0,0,0,0,0,0,0,0,0,0,0,0,0,0,0,0,0,0,0,0,0,AP19,0,0,0,0,0,0,0,0)';
      PINUSE='POWER';
      NO_LOAD_CHECK='Both';
      NO_IO_CHECK='Both';
      NO_ASSERT_CHECK='TRUE';
      NO_DIR_CHECK='TRUE';
      ALLOW_CONNECT='TRUE';
    'VSS_AP22':
      PIN_NUMBER='(0,0,0,0,0,0,0,0,0,0,0,0,0,0,0,0,0,0,0,0,0,0,0,0,0,0,0,0,0,0,0,AP22,0,0,0,0,0,0,0,0)';
      PINUSE='POWER';
      NO_LOAD_CHECK='Both';
      NO_IO_CHECK='Both';
      NO_ASSERT_CHECK='TRUE';
      NO_DIR_CHECK='TRUE';
      ALLOW_CONNECT='TRUE';
    'VSS_AP25':
      PIN_NUMBER='(0,0,0,0,0,0,0,0,0,0,0,0,0,0,0,0,0,0,0,0,0,0,0,0,0,0,0,0,0,0,0,AP25,0,0,0,0,0,0,0,0)';
      PINUSE='POWER';
      NO_LOAD_CHECK='Both';
      NO_IO_CHECK='Both';
      NO_ASSERT_CHECK='TRUE';
      NO_DIR_CHECK='TRUE';
      ALLOW_CONNECT='TRUE';
    'VSS_AP28':
      PIN_NUMBER='(0,0,0,0,0,0,0,0,0,0,0,0,0,0,0,0,0,0,0,0,0,0,0,0,0,0,0,0,0,0,0,AP28,0,0,0,0,0,0,0,0)';
      PINUSE='POWER';
      NO_LOAD_CHECK='Both';
      NO_IO_CHECK='Both';
      NO_ASSERT_CHECK='TRUE';
      NO_DIR_CHECK='TRUE';
      ALLOW_CONNECT='TRUE';
    'VSS_AP31':
      PIN_NUMBER='(0,0,0,0,0,0,0,0,0,0,0,0,0,0,0,0,0,0,0,0,0,0,0,0,0,0,0,0,0,0,0,AP31,0,0,0,0,0,0,0,0)';
      PINUSE='POWER';
      NO_LOAD_CHECK='Both';
      NO_IO_CHECK='Both';
      NO_ASSERT_CHECK='TRUE';
      NO_DIR_CHECK='TRUE';
      ALLOW_CONNECT='TRUE';
    'VSS_AP34':
      PIN_NUMBER='(0,0,0,0,0,0,0,0,0,0,0,0,0,0,0,0,0,0,0,0,0,0,0,0,0,0,0,0,0,0,0,AP34,0,0,0,0,0,0,0,0)';
      PINUSE='POWER';
      NO_LOAD_CHECK='Both';
      NO_IO_CHECK='Both';
      NO_ASSERT_CHECK='TRUE';
      NO_DIR_CHECK='TRUE';
      ALLOW_CONNECT='TRUE';
    'VSS_AP37':
      PIN_NUMBER='(0,0,0,0,0,0,0,0,0,0,0,0,0,0,0,0,0,0,0,0,0,0,0,0,0,0,0,0,0,0,0,AP37,0,0,0,0,0,0,0,0)';
      PINUSE='POWER';
      NO_LOAD_CHECK='Both';
      NO_IO_CHECK='Both';
      NO_ASSERT_CHECK='TRUE';
      NO_DIR_CHECK='TRUE';
      ALLOW_CONNECT='TRUE';
    'VSS_AP39':
      PIN_NUMBER='(0,0,0,0,0,0,0,0,0,0,0,0,0,0,0,0,0,0,0,0,0,0,0,0,0,0,0,0,0,0,0,AP39,0,0,0,0,0,0,0,0)';
      PINUSE='POWER';
      NO_LOAD_CHECK='Both';
      NO_IO_CHECK='Both';
      NO_ASSERT_CHECK='TRUE';
      NO_DIR_CHECK='TRUE';
      ALLOW_CONNECT='TRUE';
    'VSS_AP42':
      PIN_NUMBER='(0,0,0,0,0,0,0,0,0,0,0,0,0,0,0,0,0,0,0,0,0,0,0,0,0,0,0,0,0,0,0,AP42,0,0,0,0,0,0,0,0)';
      PINUSE='POWER';
      NO_LOAD_CHECK='Both';
      NO_IO_CHECK='Both';
      NO_ASSERT_CHECK='TRUE';
      NO_DIR_CHECK='TRUE';
      ALLOW_CONNECT='TRUE';
    'VSS_AP45':
      PIN_NUMBER='(0,0,0,0,0,0,0,0,0,0,0,0,0,0,0,0,0,0,0,0,0,0,0,0,0,0,0,0,0,0,0,AP45,0,0,0,0,0,0,0,0)';
      PINUSE='POWER';
      NO_LOAD_CHECK='Both';
      NO_IO_CHECK='Both';
      NO_ASSERT_CHECK='TRUE';
      NO_DIR_CHECK='TRUE';
      ALLOW_CONNECT='TRUE';
    'VSS_AP48':
      PIN_NUMBER='(0,0,0,0,0,0,0,0,0,0,0,0,0,0,0,0,0,0,0,0,0,0,0,0,0,0,0,0,0,0,0,AP48,0,0,0,0,0,0,0,0)';
      PINUSE='POWER';
      NO_LOAD_CHECK='Both';
      NO_IO_CHECK='Both';
      NO_ASSERT_CHECK='TRUE';
      NO_DIR_CHECK='TRUE';
      ALLOW_CONNECT='TRUE';
    'VSS_AP51':
      PIN_NUMBER='(0,0,0,0,0,0,0,0,0,0,0,0,0,0,0,0,0,0,0,0,0,0,0,0,0,0,0,0,0,0,0,AP51,0,0,0,0,0,0,0,0)';
      PINUSE='POWER';
      NO_LOAD_CHECK='Both';
      NO_IO_CHECK='Both';
      NO_ASSERT_CHECK='TRUE';
      NO_DIR_CHECK='TRUE';
      ALLOW_CONNECT='TRUE';
    'VSS_AP54':
      PIN_NUMBER='(0,0,0,0,0,0,0,0,0,0,0,0,0,0,0,0,0,0,0,0,0,0,0,0,0,0,0,0,0,0,0,AP54,0,0,0,0,0,0,0,0)';
      PINUSE='POWER';
      NO_LOAD_CHECK='Both';
      NO_IO_CHECK='Both';
      NO_ASSERT_CHECK='TRUE';
      NO_DIR_CHECK='TRUE';
      ALLOW_CONNECT='TRUE';
    'VSS_AP57':
      PIN_NUMBER='(0,0,0,0,0,0,0,0,0,0,0,0,0,0,0,0,0,0,0,0,0,0,0,0,0,0,0,0,0,0,0,AP57,0,0,0,0,0,0,0,0)';
      PINUSE='POWER';
      NO_LOAD_CHECK='Both';
      NO_IO_CHECK='Both';
      NO_ASSERT_CHECK='TRUE';
      NO_DIR_CHECK='TRUE';
      ALLOW_CONNECT='TRUE';
    'VSS_AP59':
      PIN_NUMBER='(0,0,0,0,0,0,0,0,0,0,0,0,0,0,0,0,0,0,0,0,0,0,0,0,0,0,0,0,0,0,0,AP59,0,0,0,0,0,0,0,0)';
      PINUSE='POWER';
      NO_LOAD_CHECK='Both';
      NO_IO_CHECK='Both';
      NO_ASSERT_CHECK='TRUE';
      NO_DIR_CHECK='TRUE';
      ALLOW_CONNECT='TRUE';
    'VSS_AP61':
      PIN_NUMBER='(0,0,0,0,0,0,0,0,0,0,0,0,0,0,0,0,0,0,0,0,0,0,0,0,0,0,0,0,0,0,0,AP61,0,0,0,0,0,0,0,0)';
      PINUSE='POWER';
      NO_LOAD_CHECK='Both';
      NO_IO_CHECK='Both';
      NO_ASSERT_CHECK='TRUE';
      NO_DIR_CHECK='TRUE';
      ALLOW_CONNECT='TRUE';
    'VSS_AP64':
      PIN_NUMBER='(0,0,0,0,0,0,0,0,0,0,0,0,0,0,0,0,0,0,0,0,0,0,0,0,0,0,0,0,0,0,0,AP64,0,0,0,0,0,0,0,0)';
      PINUSE='POWER';
      NO_LOAD_CHECK='Both';
      NO_IO_CHECK='Both';
      NO_ASSERT_CHECK='TRUE';
      NO_DIR_CHECK='TRUE';
      ALLOW_CONNECT='TRUE';
    'VSS_AP66':
      PIN_NUMBER='(0,0,0,0,0,0,0,0,0,0,0,0,0,0,0,0,0,0,0,0,0,0,0,0,0,0,0,0,0,0,0,AP66,0,0,0,0,0,0,0,0)';
      PINUSE='POWER';
      NO_LOAD_CHECK='Both';
      NO_IO_CHECK='Both';
      NO_ASSERT_CHECK='TRUE';
      NO_DIR_CHECK='TRUE';
      ALLOW_CONNECT='TRUE';
    'VSS_AP68':
      PIN_NUMBER='(0,0,0,0,0,0,0,0,0,0,0,0,0,0,0,0,0,0,0,0,0,0,0,0,0,0,0,0,0,0,0,AP68,0,0,0,0,0,0,0,0)';
      PINUSE='POWER';
      NO_LOAD_CHECK='Both';
      NO_IO_CHECK='Both';
      NO_ASSERT_CHECK='TRUE';
      NO_DIR_CHECK='TRUE';
      ALLOW_CONNECT='TRUE';
    'VSS_AP71':
      PIN_NUMBER='(0,0,0,0,0,0,0,0,0,0,0,0,0,0,0,0,0,0,0,0,0,0,0,0,0,0,0,0,0,0,0,AP71,0,0,0,0,0,0,0,0)';
      PINUSE='POWER';
      NO_LOAD_CHECK='Both';
      NO_IO_CHECK='Both';
      NO_ASSERT_CHECK='TRUE';
      NO_DIR_CHECK='TRUE';
      ALLOW_CONNECT='TRUE';
    'VSS_AP73':
      PIN_NUMBER='(0,0,0,0,0,0,0,0,0,0,0,0,0,0,0,0,0,0,0,0,0,0,0,0,0,0,0,0,0,0,0,AP73,0,0,0,0,0,0,0,0)';
      PINUSE='POWER';
      NO_LOAD_CHECK='Both';
      NO_IO_CHECK='Both';
      NO_ASSERT_CHECK='TRUE';
      NO_DIR_CHECK='TRUE';
      ALLOW_CONNECT='TRUE';
    'VSS_AR1':
      PIN_NUMBER='(0,0,0,0,0,0,0,0,0,0,0,0,0,0,0,0,0,0,0,0,0,0,0,0,0,0,0,0,0,0,0,AR1,0,0,0,0,0,0,0,0)';
      PINUSE='POWER';
      NO_LOAD_CHECK='Both';
      NO_IO_CHECK='Both';
      NO_ASSERT_CHECK='TRUE';
      NO_DIR_CHECK='TRUE';
      ALLOW_CONNECT='TRUE';
    'VSS_AR5':
      PIN_NUMBER='(0,0,0,0,0,0,0,0,0,0,0,0,0,0,0,0,0,0,0,0,0,0,0,0,0,0,0,0,0,0,0,AR5,0,0,0,0,0,0,0,0)';
      PINUSE='POWER';
      NO_LOAD_CHECK='Both';
      NO_IO_CHECK='Both';
      NO_ASSERT_CHECK='TRUE';
      NO_DIR_CHECK='TRUE';
      ALLOW_CONNECT='TRUE';
    'VSS_AR6':
      PIN_NUMBER='(0,0,0,0,0,0,0,0,0,0,0,0,0,0,0,0,0,0,0,0,0,0,0,0,0,0,0,0,0,0,0,AR6,0,0,0,0,0,0,0,0)';
      PINUSE='POWER';
      NO_LOAD_CHECK='Both';
      NO_IO_CHECK='Both';
      NO_ASSERT_CHECK='TRUE';
      NO_DIR_CHECK='TRUE';
      ALLOW_CONNECT='TRUE';
    'VSS_AR8':
      PIN_NUMBER='(0,0,0,0,0,0,0,0,0,0,0,0,0,0,0,0,0,0,0,0,0,0,0,0,0,0,0,0,0,0,0,AR8,0,0,0,0,0,0,0,0)';
      PINUSE='POWER';
      NO_LOAD_CHECK='Both';
      NO_IO_CHECK='Both';
      NO_ASSERT_CHECK='TRUE';
      NO_DIR_CHECK='TRUE';
      ALLOW_CONNECT='TRUE';
    'VSS_AR9':
      PIN_NUMBER='(0,0,0,0,0,0,0,0,0,0,0,0,0,0,0,0,0,0,0,0,0,0,0,0,0,0,0,0,0,0,0,AR9,0,0,0,0,0,0,0,0)';
      PINUSE='POWER';
      NO_LOAD_CHECK='Both';
      NO_IO_CHECK='Both';
      NO_ASSERT_CHECK='TRUE';
      NO_DIR_CHECK='TRUE';
      ALLOW_CONNECT='TRUE';
    'VSS_AR12':
      PIN_NUMBER='(0,0,0,0,0,0,0,0,0,0,0,0,0,0,0,0,0,0,0,0,0,0,0,0,0,0,0,0,0,0,0,AR12,0,0,0,0,0,0,0,0)';
      PINUSE='POWER';
      NO_LOAD_CHECK='Both';
      NO_IO_CHECK='Both';
      NO_ASSERT_CHECK='TRUE';
      NO_DIR_CHECK='TRUE';
      ALLOW_CONNECT='TRUE';
    'VSS_AR13':
      PIN_NUMBER='(0,0,0,0,0,0,0,0,0,0,0,0,0,0,0,0,0,0,0,0,0,0,0,0,0,0,0,0,0,0,0,AR13,0,0,0,0,0,0,0,0)';
      PINUSE='POWER';
      NO_LOAD_CHECK='Both';
      NO_IO_CHECK='Both';
      NO_ASSERT_CHECK='TRUE';
      NO_DIR_CHECK='TRUE';
      ALLOW_CONNECT='TRUE';
    'VSS_AR15':
      PIN_NUMBER='(0,0,0,0,0,0,0,0,0,0,0,0,0,0,0,0,0,0,0,0,0,0,0,0,0,0,0,0,0,0,0,AR15,0,0,0,0,0,0,0,0)';
      PINUSE='POWER';
      NO_LOAD_CHECK='Both';
      NO_IO_CHECK='Both';
      NO_ASSERT_CHECK='TRUE';
      NO_DIR_CHECK='TRUE';
      ALLOW_CONNECT='TRUE';
    'VSS_AR16':
      PIN_NUMBER='(0,0,0,0,0,0,0,0,0,0,0,0,0,0,0,0,0,0,0,0,0,0,0,0,0,0,0,0,0,0,0,AR16,0,0,0,0,0,0,0,0)';
      PINUSE='POWER';
      NO_LOAD_CHECK='Both';
      NO_IO_CHECK='Both';
      NO_ASSERT_CHECK='TRUE';
      NO_DIR_CHECK='TRUE';
      ALLOW_CONNECT='TRUE';
    'VSS_AR19':
      PIN_NUMBER='(0,0,0,0,0,0,0,0,0,0,0,0,0,0,0,0,0,0,0,0,0,0,0,0,0,0,0,0,0,0,0,AR19,0,0,0,0,0,0,0,0)';
      PINUSE='POWER';
      NO_LOAD_CHECK='Both';
      NO_IO_CHECK='Both';
      NO_ASSERT_CHECK='TRUE';
      NO_DIR_CHECK='TRUE';
      ALLOW_CONNECT='TRUE';
    'VSS_AR20':
      PIN_NUMBER='(0,0,0,0,0,0,0,0,0,0,0,0,0,0,0,0,0,0,0,0,0,0,0,0,0,0,0,0,0,0,0,AR20,0,0,0,0,0,0,0,0)';
      PINUSE='POWER';
      NO_LOAD_CHECK='Both';
      NO_IO_CHECK='Both';
      NO_ASSERT_CHECK='TRUE';
      NO_DIR_CHECK='TRUE';
      ALLOW_CONNECT='TRUE';
    'VSS_AR22':
      PIN_NUMBER='(0,0,0,0,0,0,0,0,0,0,0,0,0,0,0,0,0,0,0,0,0,0,0,0,0,0,0,0,0,0,0,AR22,0,0,0,0,0,0,0,0)';
      PINUSE='POWER';
      NO_LOAD_CHECK='Both';
      NO_IO_CHECK='Both';
      NO_ASSERT_CHECK='TRUE';
      NO_DIR_CHECK='TRUE';
      ALLOW_CONNECT='TRUE';
    'VSS_AR24':
      PIN_NUMBER='(0,0,0,0,0,0,0,0,0,0,0,0,0,0,0,0,0,0,0,0,0,0,0,0,0,0,0,0,0,0,0,AR24,0,0,0,0,0,0,0,0)';
      PINUSE='POWER';
      NO_LOAD_CHECK='Both';
      NO_IO_CHECK='Both';
      NO_ASSERT_CHECK='TRUE';
      NO_DIR_CHECK='TRUE';
      ALLOW_CONNECT='TRUE';
    'VSS_AR26':
      PIN_NUMBER='(0,0,0,0,0,0,0,0,0,0,0,0,0,0,0,0,0,0,0,0,0,0,0,0,0,0,0,0,0,0,0,AR26,0,0,0,0,0,0,0,0)';
      PINUSE='POWER';
      NO_LOAD_CHECK='Both';
      NO_IO_CHECK='Both';
      NO_ASSERT_CHECK='TRUE';
      NO_DIR_CHECK='TRUE';
      ALLOW_CONNECT='TRUE';
    'VSS_AR28':
      PIN_NUMBER='(0,0,0,0,0,0,0,0,0,0,0,0,0,0,0,0,0,0,0,0,0,0,0,0,0,0,0,0,0,0,0,AR28,0,0,0,0,0,0,0,0)';
      PINUSE='POWER';
      NO_LOAD_CHECK='Both';
      NO_IO_CHECK='Both';
      NO_ASSERT_CHECK='TRUE';
      NO_DIR_CHECK='TRUE';
      ALLOW_CONNECT='TRUE';
    'VSS_AR30':
      PIN_NUMBER='(0,0,0,0,0,0,0,0,0,0,0,0,0,0,0,0,0,0,0,0,0,0,0,0,0,0,0,0,0,0,0,AR30,0,0,0,0,0,0,0,0)';
      PINUSE='POWER';
      NO_LOAD_CHECK='Both';
      NO_IO_CHECK='Both';
      NO_ASSERT_CHECK='TRUE';
      NO_DIR_CHECK='TRUE';
      ALLOW_CONNECT='TRUE';
    'VSS_AR32':
      PIN_NUMBER='(0,0,0,0,0,0,0,0,0,0,0,0,0,0,0,0,0,0,0,0,0,0,0,0,0,0,0,0,0,0,0,AR32,0,0,0,0,0,0,0,0)';
      PINUSE='POWER';
      NO_LOAD_CHECK='Both';
      NO_IO_CHECK='Both';
      NO_ASSERT_CHECK='TRUE';
      NO_DIR_CHECK='TRUE';
      ALLOW_CONNECT='TRUE';
    'VSS_AR34':
      PIN_NUMBER='(0,0,0,0,0,0,0,0,0,0,0,0,0,0,0,0,0,0,0,0,0,0,0,0,0,0,0,0,0,0,0,AR34,0,0,0,0,0,0,0,0)';
      PINUSE='POWER';
      NO_LOAD_CHECK='Both';
      NO_IO_CHECK='Both';
      NO_ASSERT_CHECK='TRUE';
      NO_DIR_CHECK='TRUE';
      ALLOW_CONNECT='TRUE';
    'VSS_AR36':
      PIN_NUMBER='(0,0,0,0,0,0,0,0,0,0,0,0,0,0,0,0,0,0,0,0,0,0,0,0,0,0,0,0,0,0,0,AR36,0,0,0,0,0,0,0,0)';
      PINUSE='POWER';
      NO_LOAD_CHECK='Both';
      NO_IO_CHECK='Both';
      NO_ASSERT_CHECK='TRUE';
      NO_DIR_CHECK='TRUE';
      ALLOW_CONNECT='TRUE';
    'VSS_AR41':
      PIN_NUMBER='(0,0,0,0,0,0,0,0,0,0,0,0,0,0,0,0,0,0,0,0,0,0,0,0,0,0,0,0,0,0,0,AR41,0,0,0,0,0,0,0,0)';
      PINUSE='POWER';
      NO_LOAD_CHECK='Both';
      NO_IO_CHECK='Both';
      NO_ASSERT_CHECK='TRUE';
      NO_DIR_CHECK='TRUE';
      ALLOW_CONNECT='TRUE';
    'VSS_AR43':
      PIN_NUMBER='(0,0,0,0,0,0,0,0,0,0,0,0,0,0,0,0,0,0,0,0,0,0,0,0,0,0,0,0,0,0,0,AR43,0,0,0,0,0,0,0,0)';
      PINUSE='POWER';
      NO_LOAD_CHECK='Both';
      NO_IO_CHECK='Both';
      NO_ASSERT_CHECK='TRUE';
      NO_DIR_CHECK='TRUE';
      ALLOW_CONNECT='TRUE';
    'VSS_AR45':
      PIN_NUMBER='(0,0,0,0,0,0,0,0,0,0,0,0,0,0,0,0,0,0,0,0,0,0,0,0,0,0,0,0,0,0,0,AR45,0,0,0,0,0,0,0,0)';
      PINUSE='POWER';
      NO_LOAD_CHECK='Both';
      NO_IO_CHECK='Both';
      NO_ASSERT_CHECK='TRUE';
      NO_DIR_CHECK='TRUE';
      ALLOW_CONNECT='TRUE';
    'VSS_AR47':
      PIN_NUMBER='(0,0,0,0,0,0,0,0,0,0,0,0,0,0,0,0,0,0,0,0,0,0,0,0,0,0,0,0,0,0,0,AR47,0,0,0,0,0,0,0,0)';
      PINUSE='POWER';
      NO_LOAD_CHECK='Both';
      NO_IO_CHECK='Both';
      NO_ASSERT_CHECK='TRUE';
      NO_DIR_CHECK='TRUE';
      ALLOW_CONNECT='TRUE';
    'VSS_AR49':
      PIN_NUMBER='(0,0,0,0,0,0,0,0,0,0,0,0,0,0,0,0,0,0,0,0,0,0,0,0,0,0,0,0,0,0,0,AR49,0,0,0,0,0,0,0,0)';
      PINUSE='POWER';
      NO_LOAD_CHECK='Both';
      NO_IO_CHECK='Both';
      NO_ASSERT_CHECK='TRUE';
      NO_DIR_CHECK='TRUE';
      ALLOW_CONNECT='TRUE';
    'VSS_AR51':
      PIN_NUMBER='(0,0,0,0,0,0,0,0,0,0,0,0,0,0,0,0,0,0,0,0,0,0,0,0,0,0,0,0,0,0,0,AR51,0,0,0,0,0,0,0,0)';
      PINUSE='POWER';
      NO_LOAD_CHECK='Both';
      NO_IO_CHECK='Both';
      NO_ASSERT_CHECK='TRUE';
      NO_DIR_CHECK='TRUE';
      ALLOW_CONNECT='TRUE';
    'VSS_AR53':
      PIN_NUMBER='(0,0,0,0,0,0,0,0,0,0,0,0,0,0,0,0,0,0,0,0,0,0,0,0,0,0,0,0,0,0,0,AR53,0,0,0,0,0,0,0,0)';
      PINUSE='POWER';
      NO_LOAD_CHECK='Both';
      NO_IO_CHECK='Both';
      NO_ASSERT_CHECK='TRUE';
      NO_DIR_CHECK='TRUE';
      ALLOW_CONNECT='TRUE';
    'VSS_AR56':
      PIN_NUMBER='(0,0,0,0,0,0,0,0,0,0,0,0,0,0,0,0,0,0,0,0,0,0,0,0,0,0,0,0,0,0,0,AR56,0,0,0,0,0,0,0,0)';
      PINUSE='POWER';
      NO_LOAD_CHECK='Both';
      NO_IO_CHECK='Both';
      NO_ASSERT_CHECK='TRUE';
      NO_DIR_CHECK='TRUE';
      ALLOW_CONNECT='TRUE';
    'VSS_AR57':
      PIN_NUMBER='(0,0,0,0,0,0,0,0,0,0,0,0,0,0,0,0,0,0,0,0,0,0,0,0,0,0,0,0,0,0,0,AR57,0,0,0,0,0,0,0,0)';
      PINUSE='POWER';
      NO_LOAD_CHECK='Both';
      NO_IO_CHECK='Both';
      NO_ASSERT_CHECK='TRUE';
      NO_DIR_CHECK='TRUE';
      ALLOW_CONNECT='TRUE';
    'VSS_AR60':
      PIN_NUMBER='(0,0,0,0,0,0,0,0,0,0,0,0,0,0,0,0,0,0,0,0,0,0,0,0,0,0,0,0,0,0,0,AR60,0,0,0,0,0,0,0,0)';
      PINUSE='POWER';
      NO_LOAD_CHECK='Both';
      NO_IO_CHECK='Both';
      NO_ASSERT_CHECK='TRUE';
      NO_DIR_CHECK='TRUE';
      ALLOW_CONNECT='TRUE';
    'VSS_AR61':
      PIN_NUMBER='(0,0,0,0,0,0,0,0,0,0,0,0,0,0,0,0,0,0,0,0,0,0,0,0,0,0,0,0,0,0,0,AR61,0,0,0,0,0,0,0,0)';
      PINUSE='POWER';
      NO_LOAD_CHECK='Both';
      NO_IO_CHECK='Both';
      NO_ASSERT_CHECK='TRUE';
      NO_DIR_CHECK='TRUE';
      ALLOW_CONNECT='TRUE';
    'VSS_AR63':
      PIN_NUMBER='(0,0,0,0,0,0,0,0,0,0,0,0,0,0,0,0,0,0,0,0,0,0,0,0,0,0,0,0,0,0,0,AR63,0,0,0,0,0,0,0,0)';
      PINUSE='POWER';
      NO_LOAD_CHECK='Both';
      NO_IO_CHECK='Both';
      NO_ASSERT_CHECK='TRUE';
      NO_DIR_CHECK='TRUE';
      ALLOW_CONNECT='TRUE';
    'VSS_AR64':
      PIN_NUMBER='(0,0,0,0,0,0,0,0,0,0,0,0,0,0,0,0,0,0,0,0,0,0,0,0,0,0,0,0,0,0,0,AR64,0,0,0,0,0,0,0,0)';
      PINUSE='POWER';
      NO_LOAD_CHECK='Both';
      NO_IO_CHECK='Both';
      NO_ASSERT_CHECK='TRUE';
      NO_DIR_CHECK='TRUE';
      ALLOW_CONNECT='TRUE';
    'VSS_AR67':
      PIN_NUMBER='(0,0,0,0,0,0,0,0,0,0,0,0,0,0,0,0,0,0,0,0,0,0,0,0,0,0,0,0,0,0,0,AR67,0,0,0,0,0,0,0,0)';
      PINUSE='POWER';
      NO_LOAD_CHECK='Both';
      NO_IO_CHECK='Both';
      NO_ASSERT_CHECK='TRUE';
      NO_DIR_CHECK='TRUE';
      ALLOW_CONNECT='TRUE';
    'VSS_AR68':
      PIN_NUMBER='(0,0,0,0,0,0,0,0,0,0,0,0,0,0,0,0,0,0,0,0,0,0,0,0,0,0,0,0,0,0,0,AR68,0,0,0,0,0,0,0,0)';
      PINUSE='POWER';
      NO_LOAD_CHECK='Both';
      NO_IO_CHECK='Both';
      NO_ASSERT_CHECK='TRUE';
      NO_DIR_CHECK='TRUE';
      ALLOW_CONNECT='TRUE';
    'VSS_AR70':
      PIN_NUMBER='(0,0,0,0,0,0,0,0,0,0,0,0,0,0,0,0,0,0,0,0,0,0,0,0,0,0,0,0,0,0,0,AR70,0,0,0,0,0,0,0,0)';
      PINUSE='POWER';
      NO_LOAD_CHECK='Both';
      NO_IO_CHECK='Both';
      NO_ASSERT_CHECK='TRUE';
      NO_DIR_CHECK='TRUE';
      ALLOW_CONNECT='TRUE';
    'VSS_AR71':
      PIN_NUMBER='(0,0,0,0,0,0,0,0,0,0,0,0,0,0,0,0,0,0,0,0,0,0,0,0,0,0,0,0,0,0,0,AR71,0,0,0,0,0,0,0,0)';
      PINUSE='POWER';
      NO_LOAD_CHECK='Both';
      NO_IO_CHECK='Both';
      NO_ASSERT_CHECK='TRUE';
      NO_DIR_CHECK='TRUE';
      ALLOW_CONNECT='TRUE';
    'VSS_AR75':
      PIN_NUMBER='(0,0,0,0,0,0,0,0,0,0,0,0,0,0,0,0,0,0,0,0,0,0,0,0,0,0,0,0,0,0,0,AR75,0,0,0,0,0,0,0,0)';
      PINUSE='POWER';
      NO_LOAD_CHECK='Both';
      NO_IO_CHECK='Both';
      NO_ASSERT_CHECK='TRUE';
      NO_DIR_CHECK='TRUE';
      ALLOW_CONNECT='TRUE';
    'VSS_AT3':
      PIN_NUMBER='(0,0,0,0,0,0,0,0,0,0,0,0,0,0,0,0,0,0,0,0,0,0,0,0,0,0,0,0,0,0,0,AT3,0,0,0,0,0,0,0,0)';
      PINUSE='POWER';
      NO_LOAD_CHECK='Both';
      NO_IO_CHECK='Both';
      NO_ASSERT_CHECK='TRUE';
      NO_DIR_CHECK='TRUE';
      ALLOW_CONNECT='TRUE';
    'VSS_AT4':
      PIN_NUMBER='(0,0,0,0,0,0,0,0,0,0,0,0,0,0,0,0,0,0,0,0,0,0,0,0,0,0,0,0,0,0,0,AT4,0,0,0,0,0,0,0,0)';
      PINUSE='POWER';
      NO_LOAD_CHECK='Both';
      NO_IO_CHECK='Both';
      NO_ASSERT_CHECK='TRUE';
      NO_DIR_CHECK='TRUE';
      ALLOW_CONNECT='TRUE';
    'VSS_AT5':
      PIN_NUMBER='(0,0,0,0,0,0,0,0,0,0,0,0,0,0,0,0,0,0,0,0,0,0,0,0,0,0,0,0,0,0,0,AT5,0,0,0,0,0,0,0,0)';
      PINUSE='POWER';
      NO_LOAD_CHECK='Both';
      NO_IO_CHECK='Both';
      NO_ASSERT_CHECK='TRUE';
      NO_DIR_CHECK='TRUE';
      ALLOW_CONNECT='TRUE';
    'VSS_AT6':
      PIN_NUMBER='(0,0,0,0,0,0,0,0,0,0,0,0,0,0,0,0,0,0,0,0,0,0,0,0,0,0,0,0,0,0,0,AT6,0,0,0,0,0,0,0,0)';
      PINUSE='POWER';
      NO_LOAD_CHECK='Both';
      NO_IO_CHECK='Both';
      NO_ASSERT_CHECK='TRUE';
      NO_DIR_CHECK='TRUE';
      ALLOW_CONNECT='TRUE';
    'VSS_AT8':
      PIN_NUMBER='(0,0,0,0,0,0,0,0,0,0,0,0,0,0,0,0,0,0,0,0,0,0,0,0,0,0,0,0,0,0,0,AT8,0,0,0,0,0,0,0,0)';
      PINUSE='POWER';
      NO_LOAD_CHECK='Both';
      NO_IO_CHECK='Both';
      NO_ASSERT_CHECK='TRUE';
      NO_DIR_CHECK='TRUE';
      ALLOW_CONNECT='TRUE';
    'VSS_AT9':
      PIN_NUMBER='(0,0,0,0,0,0,0,0,0,0,0,0,0,0,0,0,0,0,0,0,0,0,0,0,0,0,0,0,0,0,0,AT9,0,0,0,0,0,0,0,0)';
      PINUSE='POWER';
      NO_LOAD_CHECK='Both';
      NO_IO_CHECK='Both';
      NO_ASSERT_CHECK='TRUE';
      NO_DIR_CHECK='TRUE';
      ALLOW_CONNECT='TRUE';
    'VSS_AT10':
      PIN_NUMBER='(0,0,0,0,0,0,0,0,0,0,0,0,0,0,0,0,0,0,0,0,0,0,0,0,0,0,0,0,0,0,0,AT10,0,0,0,0,0,0,0,0)';
      PINUSE='POWER';
      NO_LOAD_CHECK='Both';
      NO_IO_CHECK='Both';
      NO_ASSERT_CHECK='TRUE';
      NO_DIR_CHECK='TRUE';
      ALLOW_CONNECT='TRUE';
    'VSS_AT12':
      PIN_NUMBER='(0,0,0,0,0,0,0,0,0,0,0,0,0,0,0,0,0,0,0,0,0,0,0,0,0,0,0,0,0,0,0,AT12,0,0,0,0,0,0,0,0)';
      PINUSE='POWER';
      NO_LOAD_CHECK='Both';
      NO_IO_CHECK='Both';
      NO_ASSERT_CHECK='TRUE';
      NO_DIR_CHECK='TRUE';
      ALLOW_CONNECT='TRUE';
    'VSS_AT13':
      PIN_NUMBER='(0,0,0,0,0,0,0,0,0,0,0,0,0,0,0,0,0,0,0,0,0,0,0,0,0,0,0,0,0,0,0,AT13,0,0,0,0,0,0,0,0)';
      PINUSE='POWER';
      NO_LOAD_CHECK='Both';
      NO_IO_CHECK='Both';
      NO_ASSERT_CHECK='TRUE';
      NO_DIR_CHECK='TRUE';
      ALLOW_CONNECT='TRUE';
    'VSS_AT15':
      PIN_NUMBER='(0,0,0,0,0,0,0,0,0,0,0,0,0,0,0,0,0,0,0,0,0,0,0,0,0,0,0,0,0,0,0,AT15,0,0,0,0,0,0,0,0)';
      PINUSE='POWER';
      NO_LOAD_CHECK='Both';
      NO_IO_CHECK='Both';
      NO_ASSERT_CHECK='TRUE';
      NO_DIR_CHECK='TRUE';
      ALLOW_CONNECT='TRUE';
    'VSS_AT16':
      PIN_NUMBER='(0,0,0,0,0,0,0,0,0,0,0,0,0,0,0,0,0,0,0,0,0,0,0,0,0,0,0,0,0,0,0,AT16,0,0,0,0,0,0,0,0)';
      PINUSE='POWER';
      NO_LOAD_CHECK='Both';
      NO_IO_CHECK='Both';
      NO_ASSERT_CHECK='TRUE';
      NO_DIR_CHECK='TRUE';
      ALLOW_CONNECT='TRUE';
    'VSS_AT17':
      PIN_NUMBER='(0,0,0,0,0,0,0,0,0,0,0,0,0,0,0,0,0,0,0,0,0,0,0,0,0,0,0,0,0,0,0,AT17,0,0,0,0,0,0,0,0)';
      PINUSE='POWER';
      NO_LOAD_CHECK='Both';
      NO_IO_CHECK='Both';
      NO_ASSERT_CHECK='TRUE';
      NO_DIR_CHECK='TRUE';
      ALLOW_CONNECT='TRUE';
    'VSS_AT19':
      PIN_NUMBER='(0,0,0,0,0,0,0,0,0,0,0,0,0,0,0,0,0,0,0,0,0,0,0,0,0,0,0,0,0,0,0,AT19,0,0,0,0,0,0,0,0)';
      PINUSE='POWER';
      NO_LOAD_CHECK='Both';
      NO_IO_CHECK='Both';
      NO_ASSERT_CHECK='TRUE';
      NO_DIR_CHECK='TRUE';
      ALLOW_CONNECT='TRUE';
    'VSS_AT20':
      PIN_NUMBER='(0,0,0,0,0,0,0,0,0,0,0,0,0,0,0,0,0,0,0,0,0,0,0,0,0,0,0,0,0,0,0,AT20,0,0,0,0,0,0,0,0)';
      PINUSE='POWER';
      NO_LOAD_CHECK='Both';
      NO_IO_CHECK='Both';
      NO_ASSERT_CHECK='TRUE';
      NO_DIR_CHECK='TRUE';
      ALLOW_CONNECT='TRUE';
    'VSS_AT23':
      PIN_NUMBER='(0,0,0,0,0,0,0,0,0,0,0,0,0,0,0,0,0,0,0,0,0,0,0,0,0,0,0,0,0,0,0,AT23,0,0,0,0,0,0,0,0)';
      PINUSE='POWER';
      NO_LOAD_CHECK='Both';
      NO_IO_CHECK='Both';
      NO_ASSERT_CHECK='TRUE';
      NO_DIR_CHECK='TRUE';
      ALLOW_CONNECT='TRUE';
    'VSS_AT25':
      PIN_NUMBER='(0,0,0,0,0,0,0,0,0,0,0,0,0,0,0,0,0,0,0,0,0,0,0,0,0,0,0,0,0,0,0,AT25,0,0,0,0,0,0,0,0)';
      PINUSE='POWER';
      NO_LOAD_CHECK='Both';
      NO_IO_CHECK='Both';
      NO_ASSERT_CHECK='TRUE';
      NO_DIR_CHECK='TRUE';
      ALLOW_CONNECT='TRUE';
    'VSS_AT27':
      PIN_NUMBER='(0,0,0,0,0,0,0,0,0,0,0,0,0,0,0,0,0,0,0,0,0,0,0,0,0,0,0,0,0,0,0,AT27,0,0,0,0,0,0,0,0)';
      PINUSE='POWER';
      NO_LOAD_CHECK='Both';
      NO_IO_CHECK='Both';
      NO_ASSERT_CHECK='TRUE';
      NO_DIR_CHECK='TRUE';
      ALLOW_CONNECT='TRUE';
    'VSS_AT29':
      PIN_NUMBER='(0,0,0,0,0,0,0,0,0,0,0,0,0,0,0,0,0,0,0,0,0,0,0,0,0,0,0,0,0,0,0,AT29,0,0,0,0,0,0,0,0)';
      PINUSE='POWER';
      NO_LOAD_CHECK='Both';
      NO_IO_CHECK='Both';
      NO_ASSERT_CHECK='TRUE';
      NO_DIR_CHECK='TRUE';
      ALLOW_CONNECT='TRUE';
    'VSS_AT31':
      PIN_NUMBER='(0,0,0,0,0,0,0,0,0,0,0,0,0,0,0,0,0,0,0,0,0,0,0,0,0,0,0,0,0,0,0,AT31,0,0,0,0,0,0,0,0)';
      PINUSE='POWER';
      NO_LOAD_CHECK='Both';
      NO_IO_CHECK='Both';
      NO_ASSERT_CHECK='TRUE';
      NO_DIR_CHECK='TRUE';
      ALLOW_CONNECT='TRUE';
    'VSS_AT33':
      PIN_NUMBER='(0,0,0,0,0,0,0,0,0,0,0,0,0,0,0,0,0,0,0,0,0,0,0,0,0,0,0,0,0,0,0,AT33,0,0,0,0,0,0,0,0)';
      PINUSE='POWER';
      NO_LOAD_CHECK='Both';
      NO_IO_CHECK='Both';
      NO_ASSERT_CHECK='TRUE';
      NO_DIR_CHECK='TRUE';
      ALLOW_CONNECT='TRUE';
    'VSS_AT35':
      PIN_NUMBER='(0,0,0,0,0,0,0,0,0,0,0,0,0,0,0,0,0,0,0,0,0,0,0,0,0,0,0,0,0,0,0,AT35,0,0,0,0,0,0,0,0)';
      PINUSE='POWER';
      NO_LOAD_CHECK='Both';
      NO_IO_CHECK='Both';
      NO_ASSERT_CHECK='TRUE';
      NO_DIR_CHECK='TRUE';
      ALLOW_CONNECT='TRUE';
    'VSS_AT37':
      PIN_NUMBER='(0,0,0,0,0,0,0,0,0,0,0,0,0,0,0,0,0,0,0,0,0,0,0,0,0,0,0,0,0,0,0,AT37,0,0,0,0,0,0,0,0)';
      PINUSE='POWER';
      NO_LOAD_CHECK='Both';
      NO_IO_CHECK='Both';
      NO_ASSERT_CHECK='TRUE';
      NO_DIR_CHECK='TRUE';
      ALLOW_CONNECT='TRUE';
    'VSS_AT40':
      PIN_NUMBER='(0,0,0,0,0,0,0,0,0,0,0,0,0,0,0,0,0,0,0,0,0,0,0,0,0,0,0,0,0,0,0,AT40,0,0,0,0,0,0,0,0)';
      PINUSE='POWER';
      NO_LOAD_CHECK='Both';
      NO_IO_CHECK='Both';
      NO_ASSERT_CHECK='TRUE';
      NO_DIR_CHECK='TRUE';
      ALLOW_CONNECT='TRUE';
    'VSS_AT42':
      PIN_NUMBER='(0,0,0,0,0,0,0,0,0,0,0,0,0,0,0,0,0,0,0,0,0,0,0,0,0,0,0,0,0,0,0,AT42,0,0,0,0,0,0,0,0)';
      PINUSE='POWER';
      NO_LOAD_CHECK='Both';
      NO_IO_CHECK='Both';
      NO_ASSERT_CHECK='TRUE';
      NO_DIR_CHECK='TRUE';
      ALLOW_CONNECT='TRUE';
    'VSS_AT44':
      PIN_NUMBER='(0,0,0,0,0,0,0,0,0,0,0,0,0,0,0,0,0,0,0,0,0,0,0,0,0,0,0,0,0,0,0,AT44,0,0,0,0,0,0,0,0)';
      PINUSE='POWER';
      NO_LOAD_CHECK='Both';
      NO_IO_CHECK='Both';
      NO_ASSERT_CHECK='TRUE';
      NO_DIR_CHECK='TRUE';
      ALLOW_CONNECT='TRUE';
    'VSS_AT46':
      PIN_NUMBER='(0,0,0,0,0,0,0,0,0,0,0,0,0,0,0,0,0,0,0,0,0,0,0,0,0,0,0,0,0,0,0,AT46,0,0,0,0,0,0,0,0)';
      PINUSE='POWER';
      NO_LOAD_CHECK='Both';
      NO_IO_CHECK='Both';
      NO_ASSERT_CHECK='TRUE';
      NO_DIR_CHECK='TRUE';
      ALLOW_CONNECT='TRUE';
    'VSS_AT48':
      PIN_NUMBER='(0,0,0,0,0,0,0,0,0,0,0,0,0,0,0,0,0,0,0,0,0,0,0,0,0,0,0,0,0,0,0,AT48,0,0,0,0,0,0,0,0)';
      PINUSE='POWER';
      NO_LOAD_CHECK='Both';
      NO_IO_CHECK='Both';
      NO_ASSERT_CHECK='TRUE';
      NO_DIR_CHECK='TRUE';
      ALLOW_CONNECT='TRUE';
    'VSS_AT50':
      PIN_NUMBER='(0,0,0,0,0,0,0,0,0,0,0,0,0,0,0,0,0,0,0,0,0,0,0,0,0,0,0,0,0,0,0,AT50,0,0,0,0,0,0,0,0)';
      PINUSE='POWER';
      NO_LOAD_CHECK='Both';
      NO_IO_CHECK='Both';
      NO_ASSERT_CHECK='TRUE';
      NO_DIR_CHECK='TRUE';
      ALLOW_CONNECT='TRUE';
    'VSS_AT52':
      PIN_NUMBER='(0,0,0,0,0,0,0,0,0,0,0,0,0,0,0,0,0,0,0,0,0,0,0,0,0,0,0,0,0,0,0,AT52,0,0,0,0,0,0,0,0)';
      PINUSE='POWER';
      NO_LOAD_CHECK='Both';
      NO_IO_CHECK='Both';
      NO_ASSERT_CHECK='TRUE';
      NO_DIR_CHECK='TRUE';
      ALLOW_CONNECT='TRUE';
    'VSS_AT54':
      PIN_NUMBER='(0,0,0,0,0,0,0,0,0,0,0,0,0,0,0,0,0,0,0,0,0,0,0,0,0,0,0,0,0,0,0,AT54,0,0,0,0,0,0,0,0)';
      PINUSE='POWER';
      NO_LOAD_CHECK='Both';
      NO_IO_CHECK='Both';
      NO_ASSERT_CHECK='TRUE';
      NO_DIR_CHECK='TRUE';
      ALLOW_CONNECT='TRUE';
    'VSS_AT56':
      PIN_NUMBER='(0,0,0,0,0,0,0,0,0,0,0,0,0,0,0,0,0,0,0,0,0,0,0,0,0,0,0,0,0,0,0,AT56,0,0,0,0,0,0,0,0)';
      PINUSE='POWER';
      NO_LOAD_CHECK='Both';
      NO_IO_CHECK='Both';
      NO_ASSERT_CHECK='TRUE';
      NO_DIR_CHECK='TRUE';
      ALLOW_CONNECT='TRUE';
    'VSS_AT57':
      PIN_NUMBER='(0,0,0,0,0,0,0,0,0,0,0,0,0,0,0,0,0,0,0,0,0,0,0,0,0,0,0,0,0,0,0,AT57,0,0,0,0,0,0,0,0)';
      PINUSE='POWER';
      NO_LOAD_CHECK='Both';
      NO_IO_CHECK='Both';
      NO_ASSERT_CHECK='TRUE';
      NO_DIR_CHECK='TRUE';
      ALLOW_CONNECT='TRUE';
    'VSS_AT59':
      PIN_NUMBER='(0,0,0,0,0,0,0,0,0,0,0,0,0,0,0,0,0,0,0,0,0,0,0,0,0,0,0,0,0,0,0,AT59,0,0,0,0,0,0,0,0)';
      PINUSE='POWER';
      NO_LOAD_CHECK='Both';
      NO_IO_CHECK='Both';
      NO_ASSERT_CHECK='TRUE';
      NO_DIR_CHECK='TRUE';
      ALLOW_CONNECT='TRUE';
    'VSS_AT60':
      PIN_NUMBER='(0,0,0,0,0,0,0,0,0,0,0,0,0,0,0,0,0,0,0,0,0,0,0,0,0,0,0,0,0,0,0,AT60,0,0,0,0,0,0,0,0)';
      PINUSE='POWER';
      NO_LOAD_CHECK='Both';
      NO_IO_CHECK='Both';
      NO_ASSERT_CHECK='TRUE';
      NO_DIR_CHECK='TRUE';
      ALLOW_CONNECT='TRUE';
    'VSS_AT61':
      PIN_NUMBER='(0,0,0,0,0,0,0,0,0,0,0,0,0,0,0,0,0,0,0,0,0,0,0,0,0,0,0,0,0,0,0,AT61,0,0,0,0,0,0,0,0)';
      PINUSE='POWER';
      NO_LOAD_CHECK='Both';
      NO_IO_CHECK='Both';
      NO_ASSERT_CHECK='TRUE';
      NO_DIR_CHECK='TRUE';
      ALLOW_CONNECT='TRUE';
    'VSS_AT63':
      PIN_NUMBER='(0,0,0,0,0,0,0,0,0,0,0,0,0,0,0,0,0,0,0,0,0,0,0,0,0,0,0,0,0,0,0,AT63,0,0,0,0,0,0,0,0)';
      PINUSE='POWER';
      NO_LOAD_CHECK='Both';
      NO_IO_CHECK='Both';
      NO_ASSERT_CHECK='TRUE';
      NO_DIR_CHECK='TRUE';
      ALLOW_CONNECT='TRUE';
    'VSS_AT64':
      PIN_NUMBER='(0,0,0,0,0,0,0,0,0,0,0,0,0,0,0,0,0,0,0,0,0,0,0,0,0,0,0,0,0,0,0,AT64,0,0,0,0,0,0,0,0)';
      PINUSE='POWER';
      NO_LOAD_CHECK='Both';
      NO_IO_CHECK='Both';
      NO_ASSERT_CHECK='TRUE';
      NO_DIR_CHECK='TRUE';
      ALLOW_CONNECT='TRUE';
    'VSS_AT66':
      PIN_NUMBER='(0,0,0,0,0,0,0,0,0,0,0,0,0,0,0,0,0,0,0,0,0,0,0,0,0,0,0,0,0,0,0,AT66,0,0,0,0,0,0,0,0)';
      PINUSE='POWER';
      NO_LOAD_CHECK='Both';
      NO_IO_CHECK='Both';
      NO_ASSERT_CHECK='TRUE';
      NO_DIR_CHECK='TRUE';
      ALLOW_CONNECT='TRUE';
    'VSS_AT67':
      PIN_NUMBER='(0,0,0,0,0,0,0,0,0,0,0,0,0,0,0,0,0,0,0,0,0,0,0,0,0,0,0,0,0,0,0,AT67,0,0,0,0,0,0,0,0)';
      PINUSE='POWER';
      NO_LOAD_CHECK='Both';
      NO_IO_CHECK='Both';
      NO_ASSERT_CHECK='TRUE';
      NO_DIR_CHECK='TRUE';
      ALLOW_CONNECT='TRUE';
    'VSS_AT68':
      PIN_NUMBER='(0,0,0,0,0,0,0,0,0,0,0,0,0,0,0,0,0,0,0,0,0,0,0,0,0,0,0,0,0,0,0,AT68,0,0,0,0,0,0,0,0)';
      PINUSE='POWER';
      NO_LOAD_CHECK='Both';
      NO_IO_CHECK='Both';
      NO_ASSERT_CHECK='TRUE';
      NO_DIR_CHECK='TRUE';
      ALLOW_CONNECT='TRUE';
    'VSS_AT70':
      PIN_NUMBER='(0,0,0,0,0,0,0,0,0,0,0,0,0,0,0,0,0,0,0,0,0,0,0,0,0,0,0,0,0,0,0,AT70,0,0,0,0,0,0,0,0)';
      PINUSE='POWER';
      NO_LOAD_CHECK='Both';
      NO_IO_CHECK='Both';
      NO_ASSERT_CHECK='TRUE';
      NO_DIR_CHECK='TRUE';
      ALLOW_CONNECT='TRUE';
    'VSS_AT71':
      PIN_NUMBER='(0,0,0,0,0,0,0,0,0,0,0,0,0,0,0,0,0,0,0,0,0,0,0,0,0,0,0,0,0,0,0,AT71,0,0,0,0,0,0,0,0)';
      PINUSE='POWER';
      NO_LOAD_CHECK='Both';
      NO_IO_CHECK='Both';
      NO_ASSERT_CHECK='TRUE';
      NO_DIR_CHECK='TRUE';
      ALLOW_CONNECT='TRUE';
    'VSS_AT72':
      PIN_NUMBER='(0,0,0,0,0,0,0,0,0,0,0,0,0,0,0,0,0,0,0,0,0,0,0,0,0,0,0,0,0,0,0,AT72,0,0,0,0,0,0,0,0)';
      PINUSE='POWER';
      NO_LOAD_CHECK='Both';
      NO_IO_CHECK='Both';
      NO_ASSERT_CHECK='TRUE';
      NO_DIR_CHECK='TRUE';
      ALLOW_CONNECT='TRUE';
    'VSS_AT73':
      PIN_NUMBER='(0,0,0,0,0,0,0,0,0,0,0,0,0,0,0,0,0,0,0,0,0,0,0,0,0,0,0,0,0,0,0,AT73,0,0,0,0,0,0,0,0)';
      PINUSE='POWER';
      NO_LOAD_CHECK='Both';
      NO_IO_CHECK='Both';
      NO_ASSERT_CHECK='TRUE';
      NO_DIR_CHECK='TRUE';
      ALLOW_CONNECT='TRUE';
    'VSS_AU1':
      PIN_NUMBER='(0,0,0,0,0,0,0,0,0,0,0,0,0,0,0,0,0,0,0,0,0,0,0,0,0,0,0,0,0,0,0,AU1,0,0,0,0,0,0,0,0)';
      PINUSE='POWER';
      NO_LOAD_CHECK='Both';
      NO_IO_CHECK='Both';
      NO_ASSERT_CHECK='TRUE';
      NO_DIR_CHECK='TRUE';
      ALLOW_CONNECT='TRUE';
    'VSS_AU3':
      PIN_NUMBER='(0,0,0,0,0,0,0,0,0,0,0,0,0,0,0,0,0,0,0,0,0,0,0,0,0,0,0,0,0,0,0,AU3,0,0,0,0,0,0,0,0)';
      PINUSE='POWER';
      NO_LOAD_CHECK='Both';
      NO_IO_CHECK='Both';
      NO_ASSERT_CHECK='TRUE';
      NO_DIR_CHECK='TRUE';
      ALLOW_CONNECT='TRUE';
    'VSS_AU4':
      PIN_NUMBER='(0,0,0,0,0,0,0,0,0,0,0,0,0,0,0,0,0,0,0,0,0,0,0,0,0,0,0,0,0,0,0,AU4,0,0,0,0,0,0,0,0)';
      PINUSE='POWER';
      NO_LOAD_CHECK='Both';
      NO_IO_CHECK='Both';
      NO_ASSERT_CHECK='TRUE';
      NO_DIR_CHECK='TRUE';
      ALLOW_CONNECT='TRUE';
    'VSS_AU6':
      PIN_NUMBER='(0,0,0,0,0,0,0,0,0,0,0,0,0,0,0,0,0,0,0,0,0,0,0,0,0,0,0,0,0,0,0,AU6,0,0,0,0,0,0,0,0)';
      PINUSE='POWER';
      NO_LOAD_CHECK='Both';
      NO_IO_CHECK='Both';
      NO_ASSERT_CHECK='TRUE';
      NO_DIR_CHECK='TRUE';
      ALLOW_CONNECT='TRUE';
    'VSS_AU8':
      PIN_NUMBER='(0,0,0,0,0,0,0,0,0,0,0,0,0,0,0,0,0,0,0,0,0,0,0,0,0,0,0,0,0,0,0,AU8,0,0,0,0,0,0,0,0)';
      PINUSE='POWER';
      NO_LOAD_CHECK='Both';
      NO_IO_CHECK='Both';
      NO_ASSERT_CHECK='TRUE';
      NO_DIR_CHECK='TRUE';
      ALLOW_CONNECT='TRUE';
    'VSS_AU11':
      PIN_NUMBER='(0,0,0,0,0,0,0,0,0,0,0,0,0,0,0,0,0,0,0,0,0,0,0,0,0,0,0,0,0,0,0,AU11,0,0,0,0,0,0,0,0)';
      PINUSE='POWER';
      NO_LOAD_CHECK='Both';
      NO_IO_CHECK='Both';
      NO_ASSERT_CHECK='TRUE';
      NO_DIR_CHECK='TRUE';
      ALLOW_CONNECT='TRUE';
    'VSS_AU13':
      PIN_NUMBER='(0,0,0,0,0,0,0,0,0,0,0,0,0,0,0,0,0,0,0,0,0,0,0,0,0,0,0,0,0,0,0,AU13,0,0,0,0,0,0,0,0)';
      PINUSE='POWER';
      NO_LOAD_CHECK='Both';
      NO_IO_CHECK='Both';
      NO_ASSERT_CHECK='TRUE';
      NO_DIR_CHECK='TRUE';
      ALLOW_CONNECT='TRUE';
    'VSS_AU15':
      PIN_NUMBER='(0,0,0,0,0,0,0,0,0,0,0,0,0,0,0,0,0,0,0,0,0,0,0,0,0,0,0,0,0,0,0,AU15,0,0,0,0,0,0,0,0)';
      PINUSE='POWER';
      NO_LOAD_CHECK='Both';
      NO_IO_CHECK='Both';
      NO_ASSERT_CHECK='TRUE';
      NO_DIR_CHECK='TRUE';
      ALLOW_CONNECT='TRUE';
    'VSS_AU18':
      PIN_NUMBER='(0,0,0,0,0,0,0,0,0,0,0,0,0,0,0,0,0,0,0,0,0,0,0,0,0,0,0,0,0,0,0,AU18,0,0,0,0,0,0,0,0)';
      PINUSE='POWER';
      NO_LOAD_CHECK='Both';
      NO_IO_CHECK='Both';
      NO_ASSERT_CHECK='TRUE';
      NO_DIR_CHECK='TRUE';
      ALLOW_CONNECT='TRUE';
    'VSS_AU20':
      PIN_NUMBER='(0,0,0,0,0,0,0,0,0,0,0,0,0,0,0,0,0,0,0,0,0,0,0,0,0,0,0,0,0,0,0,AU20,0,0,0,0,0,0,0,0)';
      PINUSE='POWER';
      NO_LOAD_CHECK='Both';
      NO_IO_CHECK='Both';
      NO_ASSERT_CHECK='TRUE';
      NO_DIR_CHECK='TRUE';
      ALLOW_CONNECT='TRUE';
    'VSS_AU22':
      PIN_NUMBER='(0,0,0,0,0,0,0,0,0,0,0,0,0,0,0,0,0,0,0,0,0,0,0,0,0,0,0,0,0,0,0,AU22,0,0,0,0,0,0,0,0)';
      PINUSE='POWER';
      NO_LOAD_CHECK='Both';
      NO_IO_CHECK='Both';
      NO_ASSERT_CHECK='TRUE';
      NO_DIR_CHECK='TRUE';
      ALLOW_CONNECT='TRUE';
    'VSS_AU24':
      PIN_NUMBER='(0,0,0,0,0,0,0,0,0,0,0,0,0,0,0,0,0,0,0,0,0,0,0,0,0,0,0,0,0,0,0,AU24,0,0,0,0,0,0,0,0)';
      PINUSE='POWER';
      NO_LOAD_CHECK='Both';
      NO_IO_CHECK='Both';
      NO_ASSERT_CHECK='TRUE';
      NO_DIR_CHECK='TRUE';
      ALLOW_CONNECT='TRUE';
    'VSS_AU26':
      PIN_NUMBER='(0,0,0,0,0,0,0,0,0,0,0,0,0,0,0,0,0,0,0,0,0,0,0,0,0,0,0,0,0,0,0,AU26,0,0,0,0,0,0,0,0)';
      PINUSE='POWER';
      NO_LOAD_CHECK='Both';
      NO_IO_CHECK='Both';
      NO_ASSERT_CHECK='TRUE';
      NO_DIR_CHECK='TRUE';
      ALLOW_CONNECT='TRUE';
    'VSS_AU28':
      PIN_NUMBER='(0,0,0,0,0,0,0,0,0,0,0,0,0,0,0,0,0,0,0,0,0,0,0,0,0,0,0,0,0,0,0,AU28,0,0,0,0,0,0,0,0)';
      PINUSE='POWER';
      NO_LOAD_CHECK='Both';
      NO_IO_CHECK='Both';
      NO_ASSERT_CHECK='TRUE';
      NO_DIR_CHECK='TRUE';
      ALLOW_CONNECT='TRUE';
    'VSS_AU30':
      PIN_NUMBER='(0,0,0,0,0,0,0,0,0,0,0,0,0,0,0,0,0,0,0,0,0,0,0,0,0,0,0,0,0,0,0,AU30,0,0,0,0,0,0,0,0)';
      PINUSE='POWER';
      NO_LOAD_CHECK='Both';
      NO_IO_CHECK='Both';
      NO_ASSERT_CHECK='TRUE';
      NO_DIR_CHECK='TRUE';
      ALLOW_CONNECT='TRUE';
    'VSS_AU32':
      PIN_NUMBER='(0,0,0,0,0,0,0,0,0,0,0,0,0,0,0,0,0,0,0,0,0,0,0,0,0,0,0,0,0,0,0,AU32,0,0,0,0,0,0,0,0)';
      PINUSE='POWER';
      NO_LOAD_CHECK='Both';
      NO_IO_CHECK='Both';
      NO_ASSERT_CHECK='TRUE';
      NO_DIR_CHECK='TRUE';
      ALLOW_CONNECT='TRUE';
    'VSS_AU34':
      PIN_NUMBER='(0,0,0,0,0,0,0,0,0,0,0,0,0,0,0,0,0,0,0,0,0,0,0,0,0,0,0,0,0,0,0,AU34,0,0,0,0,0,0,0,0)';
      PINUSE='POWER';
      NO_LOAD_CHECK='Both';
      NO_IO_CHECK='Both';
      NO_ASSERT_CHECK='TRUE';
      NO_DIR_CHECK='TRUE';
      ALLOW_CONNECT='TRUE';
    'VSS_AU36':
      PIN_NUMBER='(0,0,0,0,0,0,0,0,0,0,0,0,0,0,0,0,0,0,0,0,0,0,0,0,0,0,0,0,0,0,0,AU36,0,0,0,0,0,0,0,0)';
      PINUSE='POWER';
      NO_LOAD_CHECK='Both';
      NO_IO_CHECK='Both';
      NO_ASSERT_CHECK='TRUE';
      NO_DIR_CHECK='TRUE';
      ALLOW_CONNECT='TRUE';
    'VSS_AU41':
      PIN_NUMBER='(0,0,0,0,0,0,0,0,0,0,0,0,0,0,0,0,0,0,0,0,0,0,0,0,0,0,0,0,0,0,0,AU41,0,0,0,0,0,0,0,0)';
      PINUSE='POWER';
      NO_LOAD_CHECK='Both';
      NO_IO_CHECK='Both';
      NO_ASSERT_CHECK='TRUE';
      NO_DIR_CHECK='TRUE';
      ALLOW_CONNECT='TRUE';
    'VSS_AU43':
      PIN_NUMBER='(0,0,0,0,0,0,0,0,0,0,0,0,0,0,0,0,0,0,0,0,0,0,0,0,0,0,0,0,0,0,0,AU43,0,0,0,0,0,0,0,0)';
      PINUSE='POWER';
      NO_LOAD_CHECK='Both';
      NO_IO_CHECK='Both';
      NO_ASSERT_CHECK='TRUE';
      NO_DIR_CHECK='TRUE';
      ALLOW_CONNECT='TRUE';
    'VSS_AU45':
      PIN_NUMBER='(0,0,0,0,0,0,0,0,0,0,0,0,0,0,0,0,0,0,0,0,0,0,0,0,0,0,0,0,0,0,0,AU45,0,0,0,0,0,0,0,0)';
      PINUSE='POWER';
      NO_LOAD_CHECK='Both';
      NO_IO_CHECK='Both';
      NO_ASSERT_CHECK='TRUE';
      NO_DIR_CHECK='TRUE';
      ALLOW_CONNECT='TRUE';
    'VSS_AU47':
      PIN_NUMBER='(0,0,0,0,0,0,0,0,0,0,0,0,0,0,0,0,0,0,0,0,0,0,0,0,0,0,0,0,0,0,0,AU47,0,0,0,0,0,0,0,0)';
      PINUSE='POWER';
      NO_LOAD_CHECK='Both';
      NO_IO_CHECK='Both';
      NO_ASSERT_CHECK='TRUE';
      NO_DIR_CHECK='TRUE';
      ALLOW_CONNECT='TRUE';
    'VSS_AU49':
      PIN_NUMBER='(0,0,0,0,0,0,0,0,0,0,0,0,0,0,0,0,0,0,0,0,0,0,0,0,0,0,0,0,0,0,0,AU49,0,0,0,0,0,0,0,0)';
      PINUSE='POWER';
      NO_LOAD_CHECK='Both';
      NO_IO_CHECK='Both';
      NO_ASSERT_CHECK='TRUE';
      NO_DIR_CHECK='TRUE';
      ALLOW_CONNECT='TRUE';
    'VSS_AU51':
      PIN_NUMBER='(0,0,0,0,0,0,0,0,0,0,0,0,0,0,0,0,0,0,0,0,0,0,0,0,0,0,0,0,0,0,0,AU51,0,0,0,0,0,0,0,0)';
      PINUSE='POWER';
      NO_LOAD_CHECK='Both';
      NO_IO_CHECK='Both';
      NO_ASSERT_CHECK='TRUE';
      NO_DIR_CHECK='TRUE';
      ALLOW_CONNECT='TRUE';
    'VSS_AU53':
      PIN_NUMBER='(0,0,0,0,0,0,0,0,0,0,0,0,0,0,0,0,0,0,0,0,0,0,0,0,0,0,0,0,0,0,0,AU53,0,0,0,0,0,0,0,0)';
      PINUSE='POWER';
      NO_LOAD_CHECK='Both';
      NO_IO_CHECK='Both';
      NO_ASSERT_CHECK='TRUE';
      NO_DIR_CHECK='TRUE';
      ALLOW_CONNECT='TRUE';
    'VSS_AU56':
      PIN_NUMBER='(0,0,0,0,0,0,0,0,0,0,0,0,0,0,0,0,0,0,0,0,0,0,0,0,0,0,0,0,0,0,0,AU56,0,0,0,0,0,0,0,0)';
      PINUSE='POWER';
      NO_LOAD_CHECK='Both';
      NO_IO_CHECK='Both';
      NO_ASSERT_CHECK='TRUE';
      NO_DIR_CHECK='TRUE';
      ALLOW_CONNECT='TRUE';
    'VSS_AU58':
      PIN_NUMBER='(0,0,0,0,0,0,0,0,0,0,0,0,0,0,0,0,0,0,0,0,0,0,0,0,0,0,0,0,0,0,0,AU58,0,0,0,0,0,0,0,0)';
      PINUSE='POWER';
      NO_LOAD_CHECK='Both';
      NO_IO_CHECK='Both';
      NO_ASSERT_CHECK='TRUE';
      NO_DIR_CHECK='TRUE';
      ALLOW_CONNECT='TRUE';
    'VSS_AU61':
      PIN_NUMBER='(0,0,0,0,0,0,0,0,0,0,0,0,0,0,0,0,0,0,0,0,0,0,0,0,0,0,0,0,0,0,0,AU61,0,0,0,0,0,0,0,0)';
      PINUSE='POWER';
      NO_LOAD_CHECK='Both';
      NO_IO_CHECK='Both';
      NO_ASSERT_CHECK='TRUE';
      NO_DIR_CHECK='TRUE';
      ALLOW_CONNECT='TRUE';
    'VSS_AU63':
      PIN_NUMBER='(0,0,0,0,0,0,0,0,0,0,0,0,0,0,0,0,0,0,0,0,0,0,0,0,0,0,0,0,0,0,0,AU63,0,0,0,0,0,0,0,0)';
      PINUSE='POWER';
      NO_LOAD_CHECK='Both';
      NO_IO_CHECK='Both';
      NO_ASSERT_CHECK='TRUE';
      NO_DIR_CHECK='TRUE';
      ALLOW_CONNECT='TRUE';
    'VSS_AU65':
      PIN_NUMBER='(0,0,0,0,0,0,0,0,0,0,0,0,0,0,0,0,0,0,0,0,0,0,0,0,0,0,0,0,0,0,0,AU65,0,0,0,0,0,0,0,0)';
      PINUSE='POWER';
      NO_LOAD_CHECK='Both';
      NO_IO_CHECK='Both';
      NO_ASSERT_CHECK='TRUE';
      NO_DIR_CHECK='TRUE';
      ALLOW_CONNECT='TRUE';
    'VSS_AU68':
      PIN_NUMBER='(0,0,0,0,0,0,0,0,0,0,0,0,0,0,0,0,0,0,0,0,0,0,0,0,0,0,0,0,0,0,0,AU68,0,0,0,0,0,0,0,0)';
      PINUSE='POWER';
      NO_LOAD_CHECK='Both';
      NO_IO_CHECK='Both';
      NO_ASSERT_CHECK='TRUE';
      NO_DIR_CHECK='TRUE';
      ALLOW_CONNECT='TRUE';
    'VSS_AU70':
      PIN_NUMBER='(0,0,0,0,0,0,0,0,0,0,0,0,0,0,0,0,0,0,0,0,0,0,0,0,0,0,0,0,0,0,0,AU70,0,0,0,0,0,0,0,0)';
      PINUSE='POWER';
      NO_LOAD_CHECK='Both';
      NO_IO_CHECK='Both';
      NO_ASSERT_CHECK='TRUE';
      NO_DIR_CHECK='TRUE';
      ALLOW_CONNECT='TRUE';
    'VSS_AU72':
      PIN_NUMBER='(0,0,0,0,0,0,0,0,0,0,0,0,0,0,0,0,0,0,0,0,0,0,0,0,0,0,0,0,0,0,0,AU72,0,0,0,0,0,0,0,0)';
      PINUSE='POWER';
      NO_LOAD_CHECK='Both';
      NO_IO_CHECK='Both';
      NO_ASSERT_CHECK='TRUE';
      NO_DIR_CHECK='TRUE';
      ALLOW_CONNECT='TRUE';
    'VSS_AU73':
      PIN_NUMBER='(0,0,0,0,0,0,0,0,0,0,0,0,0,0,0,0,0,0,0,0,0,0,0,0,0,0,0,0,0,0,0,AU73,0,0,0,0,0,0,0,0)';
      PINUSE='POWER';
      NO_LOAD_CHECK='Both';
      NO_IO_CHECK='Both';
      NO_ASSERT_CHECK='TRUE';
      NO_DIR_CHECK='TRUE';
      ALLOW_CONNECT='TRUE';
    'VSS_AU75':
      PIN_NUMBER='(0,0,0,0,0,0,0,0,0,0,0,0,0,0,0,0,0,0,0,0,0,0,0,0,0,0,0,0,0,0,0,AU75,0,0,0,0,0,0,0,0)';
      PINUSE='POWER';
      NO_LOAD_CHECK='Both';
      NO_IO_CHECK='Both';
      NO_ASSERT_CHECK='TRUE';
      NO_DIR_CHECK='TRUE';
      ALLOW_CONNECT='TRUE';
    'VSS_AV3':
      PIN_NUMBER='(0,0,0,0,0,0,0,0,0,0,0,0,0,0,0,0,0,0,0,0,0,0,0,0,0,0,0,0,0,0,0,AV3,0,0,0,0,0,0,0,0)';
      PINUSE='POWER';
      NO_LOAD_CHECK='Both';
      NO_IO_CHECK='Both';
      NO_ASSERT_CHECK='TRUE';
      NO_DIR_CHECK='TRUE';
      ALLOW_CONNECT='TRUE';
    'VSS_AV8':
      PIN_NUMBER='(0,0,0,0,0,0,0,0,0,0,0,0,0,0,0,0,0,0,0,0,0,0,0,0,0,0,0,0,0,0,0,AV8,0,0,0,0,0,0,0,0)';
      PINUSE='POWER';
      NO_LOAD_CHECK='Both';
      NO_IO_CHECK='Both';
      NO_ASSERT_CHECK='TRUE';
      NO_DIR_CHECK='TRUE';
      ALLOW_CONNECT='TRUE';
    'VSS_AV10':
      PIN_NUMBER='(0,0,0,0,0,0,0,0,0,0,0,0,0,0,0,0,0,0,0,0,0,0,0,0,0,0,0,0,0,0,0,AV10,0,0,0,0,0,0,0,0)';
      PINUSE='POWER';
      NO_LOAD_CHECK='Both';
      NO_IO_CHECK='Both';
      NO_ASSERT_CHECK='TRUE';
      NO_DIR_CHECK='TRUE';
      ALLOW_CONNECT='TRUE';
    'VSS_AV15':
      PIN_NUMBER='(0,0,0,0,0,0,0,0,0,0,0,0,0,0,0,0,0,0,0,0,0,0,0,0,0,0,0,0,0,0,0,AV15,0,0,0,0,0,0,0,0)';
      PINUSE='POWER';
      NO_LOAD_CHECK='Both';
      NO_IO_CHECK='Both';
      NO_ASSERT_CHECK='TRUE';
      NO_DIR_CHECK='TRUE';
      ALLOW_CONNECT='TRUE';
    'VSS_AV17':
      PIN_NUMBER='(0,0,0,0,0,0,0,0,0,0,0,0,0,0,0,0,0,0,0,0,0,0,0,0,0,0,0,0,0,0,0,AV17,0,0,0,0,0,0,0,0)';
      PINUSE='POWER';
      NO_LOAD_CHECK='Both';
      NO_IO_CHECK='Both';
      NO_ASSERT_CHECK='TRUE';
      NO_DIR_CHECK='TRUE';
      ALLOW_CONNECT='TRUE';
    'VSS_AV23':
      PIN_NUMBER='(0,0,0,0,0,0,0,0,0,0,0,0,0,0,0,0,0,0,0,0,0,0,0,0,0,0,0,0,0,0,0,AV23,0,0,0,0,0,0,0,0)';
      PINUSE='POWER';
      NO_LOAD_CHECK='Both';
      NO_IO_CHECK='Both';
      NO_ASSERT_CHECK='TRUE';
      NO_DIR_CHECK='TRUE';
      ALLOW_CONNECT='TRUE';
    'VSS_AV25':
      PIN_NUMBER='(0,0,0,0,0,0,0,0,0,0,0,0,0,0,0,0,0,0,0,0,0,0,0,0,0,0,0,0,0,0,0,AV25,0,0,0,0,0,0,0,0)';
      PINUSE='POWER';
      NO_LOAD_CHECK='Both';
      NO_IO_CHECK='Both';
      NO_ASSERT_CHECK='TRUE';
      NO_DIR_CHECK='TRUE';
      ALLOW_CONNECT='TRUE';
    'VSS_AV27':
      PIN_NUMBER='(0,0,0,0,0,0,0,0,0,0,0,0,0,0,0,0,0,0,0,0,0,0,0,0,0,0,0,0,0,0,0,AV27,0,0,0,0,0,0,0,0)';
      PINUSE='POWER';
      NO_LOAD_CHECK='Both';
      NO_IO_CHECK='Both';
      NO_ASSERT_CHECK='TRUE';
      NO_DIR_CHECK='TRUE';
      ALLOW_CONNECT='TRUE';
    'VSS_AV29':
      PIN_NUMBER='(0,0,0,0,0,0,0,0,0,0,0,0,0,0,0,0,0,0,0,0,0,0,0,0,0,0,0,0,0,0,0,AV29,0,0,0,0,0,0,0,0)';
      PINUSE='POWER';
      NO_LOAD_CHECK='Both';
      NO_IO_CHECK='Both';
      NO_ASSERT_CHECK='TRUE';
      NO_DIR_CHECK='TRUE';
      ALLOW_CONNECT='TRUE';
    'VSS_AV31':
      PIN_NUMBER='(0,0,0,0,0,0,0,0,0,0,0,0,0,0,0,0,0,0,0,0,0,0,0,0,0,0,0,0,0,0,0,AV31,0,0,0,0,0,0,0,0)';
      PINUSE='POWER';
      NO_LOAD_CHECK='Both';
      NO_IO_CHECK='Both';
      NO_ASSERT_CHECK='TRUE';
      NO_DIR_CHECK='TRUE';
      ALLOW_CONNECT='TRUE';
    'VSS_AV33':
      PIN_NUMBER='(0,0,0,0,0,0,0,0,0,0,0,0,0,0,0,0,0,0,0,0,0,0,0,0,0,0,0,0,0,0,0,AV33,0,0,0,0,0,0,0,0)';
      PINUSE='POWER';
      NO_LOAD_CHECK='Both';
      NO_IO_CHECK='Both';
      NO_ASSERT_CHECK='TRUE';
      NO_DIR_CHECK='TRUE';
      ALLOW_CONNECT='TRUE';
    'VSS_AV35':
      PIN_NUMBER='(0,0,0,0,0,0,0,0,0,0,0,0,0,0,0,0,0,0,0,0,0,0,0,0,0,0,0,0,0,0,0,AV35,0,0,0,0,0,0,0,0)';
      PINUSE='POWER';
      NO_LOAD_CHECK='Both';
      NO_IO_CHECK='Both';
      NO_ASSERT_CHECK='TRUE';
      NO_DIR_CHECK='TRUE';
      ALLOW_CONNECT='TRUE';
    'VSS_AV37':
      PIN_NUMBER='(0,0,0,0,0,0,0,0,0,0,0,0,0,0,0,0,0,0,0,0,0,0,0,0,0,0,0,0,0,0,0,AV37,0,0,0,0,0,0,0,0)';
      PINUSE='POWER';
      NO_LOAD_CHECK='Both';
      NO_IO_CHECK='Both';
      NO_ASSERT_CHECK='TRUE';
      NO_DIR_CHECK='TRUE';
      ALLOW_CONNECT='TRUE';
    'VSS_AV40':
      PIN_NUMBER='(0,0,0,0,0,0,0,0,0,0,0,0,0,0,0,0,0,0,0,0,0,0,0,0,0,0,0,0,0,0,0,AV40,0,0,0,0,0,0,0,0)';
      PINUSE='POWER';
      NO_LOAD_CHECK='Both';
      NO_IO_CHECK='Both';
      NO_ASSERT_CHECK='TRUE';
      NO_DIR_CHECK='TRUE';
      ALLOW_CONNECT='TRUE';
    'VSS_AV42':
      PIN_NUMBER='(0,0,0,0,0,0,0,0,0,0,0,0,0,0,0,0,0,0,0,0,0,0,0,0,0,0,0,0,0,0,0,AV42,0,0,0,0,0,0,0,0)';
      PINUSE='POWER';
      NO_LOAD_CHECK='Both';
      NO_IO_CHECK='Both';
      NO_ASSERT_CHECK='TRUE';
      NO_DIR_CHECK='TRUE';
      ALLOW_CONNECT='TRUE';
    'VSS_AV44':
      PIN_NUMBER='(0,0,0,0,0,0,0,0,0,0,0,0,0,0,0,0,0,0,0,0,0,0,0,0,0,0,0,0,0,0,0,AV44,0,0,0,0,0,0,0,0)';
      PINUSE='POWER';
      NO_LOAD_CHECK='Both';
      NO_IO_CHECK='Both';
      NO_ASSERT_CHECK='TRUE';
      NO_DIR_CHECK='TRUE';
      ALLOW_CONNECT='TRUE';
    'VSS_AV46':
      PIN_NUMBER='(0,0,0,0,0,0,0,0,0,0,0,0,0,0,0,0,0,0,0,0,0,0,0,0,0,0,0,0,0,0,0,AV46,0,0,0,0,0,0,0,0)';
      PINUSE='POWER';
      NO_LOAD_CHECK='Both';
      NO_IO_CHECK='Both';
      NO_ASSERT_CHECK='TRUE';
      NO_DIR_CHECK='TRUE';
      ALLOW_CONNECT='TRUE';
    'VSS_AV48':
      PIN_NUMBER='(0,0,0,0,0,0,0,0,0,0,0,0,0,0,0,0,0,0,0,0,0,0,0,0,0,0,0,0,0,0,0,AV48,0,0,0,0,0,0,0,0)';
      PINUSE='POWER';
      NO_LOAD_CHECK='Both';
      NO_IO_CHECK='Both';
      NO_ASSERT_CHECK='TRUE';
      NO_DIR_CHECK='TRUE';
      ALLOW_CONNECT='TRUE';
    'VSS_AV50':
      PIN_NUMBER='(0,0,0,0,0,0,0,0,0,0,0,0,0,0,0,0,0,0,0,0,0,0,0,0,0,0,0,0,0,0,0,AV50,0,0,0,0,0,0,0,0)';
      PINUSE='POWER';
      NO_LOAD_CHECK='Both';
      NO_IO_CHECK='Both';
      NO_ASSERT_CHECK='TRUE';
      NO_DIR_CHECK='TRUE';
      ALLOW_CONNECT='TRUE';
    'VSS_AV52':
      PIN_NUMBER='(0,0,0,0,0,0,0,0,0,0,0,0,0,0,0,0,0,0,0,0,0,0,0,0,0,0,0,0,0,0,0,AV52,0,0,0,0,0,0,0,0)';
      PINUSE='POWER';
      NO_LOAD_CHECK='Both';
      NO_IO_CHECK='Both';
      NO_ASSERT_CHECK='TRUE';
      NO_DIR_CHECK='TRUE';
      ALLOW_CONNECT='TRUE';
    'VSS_AV54':
      PIN_NUMBER='(0,0,0,0,0,0,0,0,0,0,0,0,0,0,0,0,0,0,0,0,0,0,0,0,0,0,0,0,0,0,0,AV54,0,0,0,0,0,0,0,0)';
      PINUSE='POWER';
      NO_LOAD_CHECK='Both';
      NO_IO_CHECK='Both';
      NO_ASSERT_CHECK='TRUE';
      NO_DIR_CHECK='TRUE';
      ALLOW_CONNECT='TRUE';
    'VSS_AV59':
      PIN_NUMBER='(0,0,0,0,0,0,0,0,0,0,0,0,0,0,0,0,0,0,0,0,0,0,0,0,0,0,0,0,0,0,0,AV59,0,0,0,0,0,0,0,0)';
      PINUSE='POWER';
      NO_LOAD_CHECK='Both';
      NO_IO_CHECK='Both';
      NO_ASSERT_CHECK='TRUE';
      NO_DIR_CHECK='TRUE';
      ALLOW_CONNECT='TRUE';
    'VSS_AV61':
      PIN_NUMBER='(0,0,0,0,0,0,0,0,0,0,0,0,0,0,0,0,0,0,0,0,0,0,0,0,0,0,0,0,0,0,0,AV61,0,0,0,0,0,0,0,0)';
      PINUSE='POWER';
      NO_LOAD_CHECK='Both';
      NO_IO_CHECK='Both';
      NO_ASSERT_CHECK='TRUE';
      NO_DIR_CHECK='TRUE';
      ALLOW_CONNECT='TRUE';
    'VSS_AV66':
      PIN_NUMBER='(0,0,0,0,0,0,0,0,0,0,0,0,0,0,0,0,0,0,0,0,0,0,0,0,0,0,0,0,0,0,0,AV66,0,0,0,0,0,0,0,0)';
      PINUSE='POWER';
      NO_LOAD_CHECK='Both';
      NO_IO_CHECK='Both';
      NO_ASSERT_CHECK='TRUE';
      NO_DIR_CHECK='TRUE';
      ALLOW_CONNECT='TRUE';
    'VSS_AV68':
      PIN_NUMBER='(0,0,0,0,0,0,0,0,0,0,0,0,0,0,0,0,0,0,0,0,0,0,0,0,0,0,0,0,0,0,0,AV68,0,0,0,0,0,0,0,0)';
      PINUSE='POWER';
      NO_LOAD_CHECK='Both';
      NO_IO_CHECK='Both';
      NO_ASSERT_CHECK='TRUE';
      NO_DIR_CHECK='TRUE';
      ALLOW_CONNECT='TRUE';
    'VSS_AV73':
      PIN_NUMBER='(0,0,0,0,0,0,0,0,0,0,0,0,0,0,0,0,0,0,0,0,0,0,0,0,0,0,0,0,0,0,0,AV73,0,0,0,0,0,0,0,0)';
      PINUSE='POWER';
      NO_LOAD_CHECK='Both';
      NO_IO_CHECK='Both';
      NO_ASSERT_CHECK='TRUE';
      NO_DIR_CHECK='TRUE';
      ALLOW_CONNECT='TRUE';
    'VSS_AW1':
      PIN_NUMBER='(0,0,0,0,0,0,0,0,0,0,0,0,0,0,0,0,0,0,0,0,0,0,0,0,0,0,0,0,0,0,0,AW1,0,0,0,0,0,0,0,0)';
      PINUSE='POWER';
      NO_LOAD_CHECK='Both';
      NO_IO_CHECK='Both';
      NO_ASSERT_CHECK='TRUE';
      NO_DIR_CHECK='TRUE';
      ALLOW_CONNECT='TRUE';
    'VSS_AW4':
      PIN_NUMBER='(0,0,0,0,0,0,0,0,0,0,0,0,0,0,0,0,0,0,0,0,0,0,0,0,0,0,0,0,0,0,0,AW4,0,0,0,0,0,0,0,0)';
      PINUSE='POWER';
      NO_LOAD_CHECK='Both';
      NO_IO_CHECK='Both';
      NO_ASSERT_CHECK='TRUE';
      NO_DIR_CHECK='TRUE';
      ALLOW_CONNECT='TRUE';
    'VSS_AW6':
      PIN_NUMBER='(0,0,0,0,0,0,0,0,0,0,0,0,0,0,0,0,0,0,0,0,0,0,0,0,0,0,0,0,0,0,0,AW6,0,0,0,0,0,0,0,0)';
      PINUSE='POWER';
      NO_LOAD_CHECK='Both';
      NO_IO_CHECK='Both';
      NO_ASSERT_CHECK='TRUE';
      NO_DIR_CHECK='TRUE';
      ALLOW_CONNECT='TRUE';
    'VSS_AW8':
      PIN_NUMBER='(0,0,0,0,0,0,0,0,0,0,0,0,0,0,0,0,0,0,0,0,0,0,0,0,0,0,0,0,0,0,0,AW8,0,0,0,0,0,0,0,0)';
      PINUSE='POWER';
      NO_LOAD_CHECK='Both';
      NO_IO_CHECK='Both';
      NO_ASSERT_CHECK='TRUE';
      NO_DIR_CHECK='TRUE';
      ALLOW_CONNECT='TRUE';
    'VSS_AW11':
      PIN_NUMBER='(0,0,0,0,0,0,0,0,0,0,0,0,0,0,0,0,0,0,0,0,0,0,0,0,0,0,0,0,0,0,0,AW11,0,0,0,0,0,0,0,0)';
      PINUSE='POWER';
      NO_LOAD_CHECK='Both';
      NO_IO_CHECK='Both';
      NO_ASSERT_CHECK='TRUE';
      NO_DIR_CHECK='TRUE';
      ALLOW_CONNECT='TRUE';
    'VSS_AW13':
      PIN_NUMBER='(0,0,0,0,0,0,0,0,0,0,0,0,0,0,0,0,0,0,0,0,0,0,0,0,0,0,0,0,0,0,0,AW13,0,0,0,0,0,0,0,0)';
      PINUSE='POWER';
      NO_LOAD_CHECK='Both';
      NO_IO_CHECK='Both';
      NO_ASSERT_CHECK='TRUE';
      NO_DIR_CHECK='TRUE';
      ALLOW_CONNECT='TRUE';
    'VSS_AW15':
      PIN_NUMBER='(0,0,0,0,0,0,0,0,0,0,0,0,0,0,0,0,0,0,0,0,0,0,0,0,0,0,0,0,0,0,0,AW15,0,0,0,0,0,0,0,0)';
      PINUSE='POWER';
      NO_LOAD_CHECK='Both';
      NO_IO_CHECK='Both';
      NO_ASSERT_CHECK='TRUE';
      NO_DIR_CHECK='TRUE';
      ALLOW_CONNECT='TRUE';
    'VSS_AW18':
      PIN_NUMBER='(0,0,0,0,0,0,0,0,0,0,0,0,0,0,0,0,0,0,0,0,0,0,0,0,0,0,0,0,0,0,0,AW18,0,0,0,0,0,0,0,0)';
      PINUSE='POWER';
      NO_LOAD_CHECK='Both';
      NO_IO_CHECK='Both';
      NO_ASSERT_CHECK='TRUE';
      NO_DIR_CHECK='TRUE';
      ALLOW_CONNECT='TRUE';
    'VSS_AW20':
      PIN_NUMBER='(0,0,0,0,0,0,0,0,0,0,0,0,0,0,0,0,0,0,0,0,0,0,0,0,0,0,0,0,0,0,0,AW20,0,0,0,0,0,0,0,0)';
      PINUSE='POWER';
      NO_LOAD_CHECK='Both';
      NO_IO_CHECK='Both';
      NO_ASSERT_CHECK='TRUE';
      NO_DIR_CHECK='TRUE';
      ALLOW_CONNECT='TRUE';
    'VSS_AW22':
      PIN_NUMBER='(0,0,0,0,0,0,0,0,0,0,0,0,0,0,0,0,0,0,0,0,0,0,0,0,0,0,0,0,0,0,0,AW22,0,0,0,0,0,0,0,0)';
      PINUSE='POWER';
      NO_LOAD_CHECK='Both';
      NO_IO_CHECK='Both';
      NO_ASSERT_CHECK='TRUE';
      NO_DIR_CHECK='TRUE';
      ALLOW_CONNECT='TRUE';
    'VSS_AW24':
      PIN_NUMBER='(0,0,0,0,0,0,0,0,0,0,0,0,0,0,0,0,0,0,0,0,0,0,0,0,0,0,0,0,0,0,0,AW24,0,0,0,0,0,0,0,0)';
      PINUSE='POWER';
      NO_LOAD_CHECK='Both';
      NO_IO_CHECK='Both';
      NO_ASSERT_CHECK='TRUE';
      NO_DIR_CHECK='TRUE';
      ALLOW_CONNECT='TRUE';
    'VSS_AW26':
      PIN_NUMBER='(0,0,0,0,0,0,0,0,0,0,0,0,0,0,0,0,0,0,0,0,0,0,0,0,0,0,0,0,0,0,0,AW26,0,0,0,0,0,0,0,0)';
      PINUSE='POWER';
      NO_LOAD_CHECK='Both';
      NO_IO_CHECK='Both';
      NO_ASSERT_CHECK='TRUE';
      NO_DIR_CHECK='TRUE';
      ALLOW_CONNECT='TRUE';
    'VSS_AW28':
      PIN_NUMBER='(0,0,0,0,0,0,0,0,0,0,0,0,0,0,0,0,0,0,0,0,0,0,0,0,0,0,0,0,0,0,0,AW28,0,0,0,0,0,0,0,0)';
      PINUSE='POWER';
      NO_LOAD_CHECK='Both';
      NO_IO_CHECK='Both';
      NO_ASSERT_CHECK='TRUE';
      NO_DIR_CHECK='TRUE';
      ALLOW_CONNECT='TRUE';
    'VSS_AW49':
      PIN_NUMBER='(0,0,0,0,0,0,0,0,0,0,0,0,0,0,0,0,0,0,0,0,0,0,0,0,0,0,0,0,0,0,0,AW49,0,0,0,0,0,0,0,0)';
      PINUSE='POWER';
      NO_LOAD_CHECK='Both';
      NO_IO_CHECK='Both';
      NO_ASSERT_CHECK='TRUE';
      NO_DIR_CHECK='TRUE';
      ALLOW_CONNECT='TRUE';
    'VSS_AW51':
      PIN_NUMBER='(0,0,0,0,0,0,0,0,0,0,0,0,0,0,0,0,0,0,0,0,0,0,0,0,0,0,0,0,0,0,0,AW51,0,0,0,0,0,0,0,0)';
      PINUSE='POWER';
      NO_LOAD_CHECK='Both';
      NO_IO_CHECK='Both';
      NO_ASSERT_CHECK='TRUE';
      NO_DIR_CHECK='TRUE';
      ALLOW_CONNECT='TRUE';
    'VSS_AW53':
      PIN_NUMBER='(0,0,0,0,0,0,0,0,0,0,0,0,0,0,0,0,0,0,0,0,0,0,0,0,0,0,0,0,0,0,0,AW53,0,0,0,0,0,0,0,0)';
      PINUSE='POWER';
      NO_LOAD_CHECK='Both';
      NO_IO_CHECK='Both';
      NO_ASSERT_CHECK='TRUE';
      NO_DIR_CHECK='TRUE';
      ALLOW_CONNECT='TRUE';
    'VSS_AW56':
      PIN_NUMBER='(0,0,0,0,0,0,0,0,0,0,0,0,0,0,0,0,0,0,0,0,0,0,0,0,0,0,0,0,0,0,0,AW56,0,0,0,0,0,0,0,0)';
      PINUSE='POWER';
      NO_LOAD_CHECK='Both';
      NO_IO_CHECK='Both';
      NO_ASSERT_CHECK='TRUE';
      NO_DIR_CHECK='TRUE';
      ALLOW_CONNECT='TRUE';
    'VSS_AW58':
      PIN_NUMBER='(0,0,0,0,0,0,0,0,0,0,0,0,0,0,0,0,0,0,0,0,0,0,0,0,0,0,0,0,0,0,0,AW58,0,0,0,0,0,0,0,0)';
      PINUSE='POWER';
      NO_LOAD_CHECK='Both';
      NO_IO_CHECK='Both';
      NO_ASSERT_CHECK='TRUE';
      NO_DIR_CHECK='TRUE';
      ALLOW_CONNECT='TRUE';
    'VSS_AW61':
      PIN_NUMBER='(0,0,0,0,0,0,0,0,0,0,0,0,0,0,0,0,0,0,0,0,0,0,0,0,0,0,0,0,0,0,0,AW61,0,0,0,0,0,0,0,0)';
      PINUSE='POWER';
      NO_LOAD_CHECK='Both';
      NO_IO_CHECK='Both';
      NO_ASSERT_CHECK='TRUE';
      NO_DIR_CHECK='TRUE';
      ALLOW_CONNECT='TRUE';
    'VSS_AW63':
      PIN_NUMBER='(0,0,0,0,0,0,0,0,0,0,0,0,0,0,0,0,0,0,0,0,0,0,0,0,0,0,0,0,0,0,0,0,AW63,0,0,0,0,0,0,0)';
      PINUSE='POWER';
      NO_LOAD_CHECK='Both';
      NO_IO_CHECK='Both';
      NO_ASSERT_CHECK='TRUE';
      NO_DIR_CHECK='TRUE';
      ALLOW_CONNECT='TRUE';
    'VSS_AW65':
      PIN_NUMBER='(0,0,0,0,0,0,0,0,0,0,0,0,0,0,0,0,0,0,0,0,0,0,0,0,0,0,0,0,0,0,0,0,AW65,0,0,0,0,0,0,0)';
      PINUSE='POWER';
      NO_LOAD_CHECK='Both';
      NO_IO_CHECK='Both';
      NO_ASSERT_CHECK='TRUE';
      NO_DIR_CHECK='TRUE';
      ALLOW_CONNECT='TRUE';
    'VSS_AW68':
      PIN_NUMBER='(0,0,0,0,0,0,0,0,0,0,0,0,0,0,0,0,0,0,0,0,0,0,0,0,0,0,0,0,0,0,0,0,AW68,0,0,0,0,0,0,0)';
      PINUSE='POWER';
      NO_LOAD_CHECK='Both';
      NO_IO_CHECK='Both';
      NO_ASSERT_CHECK='TRUE';
      NO_DIR_CHECK='TRUE';
      ALLOW_CONNECT='TRUE';
    'VSS_AW70':
      PIN_NUMBER='(0,0,0,0,0,0,0,0,0,0,0,0,0,0,0,0,0,0,0,0,0,0,0,0,0,0,0,0,0,0,0,0,AW70,0,0,0,0,0,0,0)';
      PINUSE='POWER';
      NO_LOAD_CHECK='Both';
      NO_IO_CHECK='Both';
      NO_ASSERT_CHECK='TRUE';
      NO_DIR_CHECK='TRUE';
      ALLOW_CONNECT='TRUE';
    'VSS_AW72':
      PIN_NUMBER='(0,0,0,0,0,0,0,0,0,0,0,0,0,0,0,0,0,0,0,0,0,0,0,0,0,0,0,0,0,0,0,0,AW72,0,0,0,0,0,0,0)';
      PINUSE='POWER';
      NO_LOAD_CHECK='Both';
      NO_IO_CHECK='Both';
      NO_ASSERT_CHECK='TRUE';
      NO_DIR_CHECK='TRUE';
      ALLOW_CONNECT='TRUE';
    'VSS_AW75':
      PIN_NUMBER='(0,0,0,0,0,0,0,0,0,0,0,0,0,0,0,0,0,0,0,0,0,0,0,0,0,0,0,0,0,0,0,0,AW75,0,0,0,0,0,0,0)';
      PINUSE='POWER';
      NO_LOAD_CHECK='Both';
      NO_IO_CHECK='Both';
      NO_ASSERT_CHECK='TRUE';
      NO_DIR_CHECK='TRUE';
      ALLOW_CONNECT='TRUE';
    'VSS_AY3':
      PIN_NUMBER='(0,0,0,0,0,0,0,0,0,0,0,0,0,0,0,0,0,0,0,0,0,0,0,0,0,0,0,0,0,0,0,0,AY3,0,0,0,0,0,0,0)';
      PINUSE='POWER';
      NO_LOAD_CHECK='Both';
      NO_IO_CHECK='Both';
      NO_ASSERT_CHECK='TRUE';
      NO_DIR_CHECK='TRUE';
      ALLOW_CONNECT='TRUE';
    'VSS_AY5':
      PIN_NUMBER='(0,0,0,0,0,0,0,0,0,0,0,0,0,0,0,0,0,0,0,0,0,0,0,0,0,0,0,0,0,0,0,0,AY5,0,0,0,0,0,0,0)';
      PINUSE='POWER';
      NO_LOAD_CHECK='Both';
      NO_IO_CHECK='Both';
      NO_ASSERT_CHECK='TRUE';
      NO_DIR_CHECK='TRUE';
      ALLOW_CONNECT='TRUE';
    'VSS_AY8':
      PIN_NUMBER='(0,0,0,0,0,0,0,0,0,0,0,0,0,0,0,0,0,0,0,0,0,0,0,0,0,0,0,0,0,0,0,0,AY8,0,0,0,0,0,0,0)';
      PINUSE='POWER';
      NO_LOAD_CHECK='Both';
      NO_IO_CHECK='Both';
      NO_ASSERT_CHECK='TRUE';
      NO_DIR_CHECK='TRUE';
      ALLOW_CONNECT='TRUE';
    'VSS_AY10':
      PIN_NUMBER='(0,0,0,0,0,0,0,0,0,0,0,0,0,0,0,0,0,0,0,0,0,0,0,0,0,0,0,0,0,0,0,0,AY10,0,0,0,0,0,0,0)';
      PINUSE='POWER';
      NO_LOAD_CHECK='Both';
      NO_IO_CHECK='Both';
      NO_ASSERT_CHECK='TRUE';
      NO_DIR_CHECK='TRUE';
      ALLOW_CONNECT='TRUE';
    'VSS_AY12':
      PIN_NUMBER='(0,0,0,0,0,0,0,0,0,0,0,0,0,0,0,0,0,0,0,0,0,0,0,0,0,0,0,0,0,0,0,0,AY12,0,0,0,0,0,0,0)';
      PINUSE='POWER';
      NO_LOAD_CHECK='Both';
      NO_IO_CHECK='Both';
      NO_ASSERT_CHECK='TRUE';
      NO_DIR_CHECK='TRUE';
      ALLOW_CONNECT='TRUE';
    'VSS_AY15':
      PIN_NUMBER='(0,0,0,0,0,0,0,0,0,0,0,0,0,0,0,0,0,0,0,0,0,0,0,0,0,0,0,0,0,0,0,0,AY15,0,0,0,0,0,0,0)';
      PINUSE='POWER';
      NO_LOAD_CHECK='Both';
      NO_IO_CHECK='Both';
      NO_ASSERT_CHECK='TRUE';
      NO_DIR_CHECK='TRUE';
      ALLOW_CONNECT='TRUE';
    'VSS_AY17':
      PIN_NUMBER='(0,0,0,0,0,0,0,0,0,0,0,0,0,0,0,0,0,0,0,0,0,0,0,0,0,0,0,0,0,0,0,0,AY17,0,0,0,0,0,0,0)';
      PINUSE='POWER';
      NO_LOAD_CHECK='Both';
      NO_IO_CHECK='Both';
      NO_ASSERT_CHECK='TRUE';
      NO_DIR_CHECK='TRUE';
      ALLOW_CONNECT='TRUE';
    'VSS_AY19':
      PIN_NUMBER='(0,0,0,0,0,0,0,0,0,0,0,0,0,0,0,0,0,0,0,0,0,0,0,0,0,0,0,0,0,0,0,0,AY19,0,0,0,0,0,0,0)';
      PINUSE='POWER';
      NO_LOAD_CHECK='Both';
      NO_IO_CHECK='Both';
      NO_ASSERT_CHECK='TRUE';
      NO_DIR_CHECK='TRUE';
      ALLOW_CONNECT='TRUE';
    'VSS_AY23':
      PIN_NUMBER='(0,0,0,0,0,0,0,0,0,0,0,0,0,0,0,0,0,0,0,0,0,0,0,0,0,0,0,0,0,0,0,0,AY23,0,0,0,0,0,0,0)';
      PINUSE='POWER';
      NO_LOAD_CHECK='Both';
      NO_IO_CHECK='Both';
      NO_ASSERT_CHECK='TRUE';
      NO_DIR_CHECK='TRUE';
      ALLOW_CONNECT='TRUE';
    'VSS_AY25':
      PIN_NUMBER='(0,0,0,0,0,0,0,0,0,0,0,0,0,0,0,0,0,0,0,0,0,0,0,0,0,0,0,0,0,0,0,0,AY25,0,0,0,0,0,0,0)';
      PINUSE='POWER';
      NO_LOAD_CHECK='Both';
      NO_IO_CHECK='Both';
      NO_ASSERT_CHECK='TRUE';
      NO_DIR_CHECK='TRUE';
      ALLOW_CONNECT='TRUE';
    'VSS_AY27':
      PIN_NUMBER='(0,0,0,0,0,0,0,0,0,0,0,0,0,0,0,0,0,0,0,0,0,0,0,0,0,0,0,0,0,0,0,0,AY27,0,0,0,0,0,0,0)';
      PINUSE='POWER';
      NO_LOAD_CHECK='Both';
      NO_IO_CHECK='Both';
      NO_ASSERT_CHECK='TRUE';
      NO_DIR_CHECK='TRUE';
      ALLOW_CONNECT='TRUE';
    'VSS_AY48':
      PIN_NUMBER='(0,0,0,0,0,0,0,0,0,0,0,0,0,0,0,0,0,0,0,0,0,0,0,0,0,0,0,0,0,0,0,0,AY48,0,0,0,0,0,0,0)';
      PINUSE='POWER';
      NO_LOAD_CHECK='Both';
      NO_IO_CHECK='Both';
      NO_ASSERT_CHECK='TRUE';
      NO_DIR_CHECK='TRUE';
      ALLOW_CONNECT='TRUE';
    'VSS_AY50':
      PIN_NUMBER='(0,0,0,0,0,0,0,0,0,0,0,0,0,0,0,0,0,0,0,0,0,0,0,0,0,0,0,0,0,0,0,0,AY50,0,0,0,0,0,0,0)';
      PINUSE='POWER';
      NO_LOAD_CHECK='Both';
      NO_IO_CHECK='Both';
      NO_ASSERT_CHECK='TRUE';
      NO_DIR_CHECK='TRUE';
      ALLOW_CONNECT='TRUE';
    'VSS_AY52':
      PIN_NUMBER='(0,0,0,0,0,0,0,0,0,0,0,0,0,0,0,0,0,0,0,0,0,0,0,0,0,0,0,0,0,0,0,0,AY52,0,0,0,0,0,0,0)';
      PINUSE='POWER';
      NO_LOAD_CHECK='Both';
      NO_IO_CHECK='Both';
      NO_ASSERT_CHECK='TRUE';
      NO_DIR_CHECK='TRUE';
      ALLOW_CONNECT='TRUE';
    'VSS_AY54':
      PIN_NUMBER='(0,0,0,0,0,0,0,0,0,0,0,0,0,0,0,0,0,0,0,0,0,0,0,0,0,0,0,0,0,0,0,0,AY54,0,0,0,0,0,0,0)';
      PINUSE='POWER';
      NO_LOAD_CHECK='Both';
      NO_IO_CHECK='Both';
      NO_ASSERT_CHECK='TRUE';
      NO_DIR_CHECK='TRUE';
      ALLOW_CONNECT='TRUE';
    'VSS_AY57':
      PIN_NUMBER='(0,0,0,0,0,0,0,0,0,0,0,0,0,0,0,0,0,0,0,0,0,0,0,0,0,0,0,0,0,0,0,0,AY57,0,0,0,0,0,0,0)';
      PINUSE='POWER';
      NO_LOAD_CHECK='Both';
      NO_IO_CHECK='Both';
      NO_ASSERT_CHECK='TRUE';
      NO_DIR_CHECK='TRUE';
      ALLOW_CONNECT='TRUE';
    'VSS_AY59':
      PIN_NUMBER='(0,0,0,0,0,0,0,0,0,0,0,0,0,0,0,0,0,0,0,0,0,0,0,0,0,0,0,0,0,0,0,0,AY59,0,0,0,0,0,0,0)';
      PINUSE='POWER';
      NO_LOAD_CHECK='Both';
      NO_IO_CHECK='Both';
      NO_ASSERT_CHECK='TRUE';
      NO_DIR_CHECK='TRUE';
      ALLOW_CONNECT='TRUE';
    'VSS_AY61':
      PIN_NUMBER='(0,0,0,0,0,0,0,0,0,0,0,0,0,0,0,0,0,0,0,0,0,0,0,0,0,0,0,0,0,0,0,0,AY61,0,0,0,0,0,0,0)';
      PINUSE='POWER';
      NO_LOAD_CHECK='Both';
      NO_IO_CHECK='Both';
      NO_ASSERT_CHECK='TRUE';
      NO_DIR_CHECK='TRUE';
      ALLOW_CONNECT='TRUE';
    'VSS_AY64':
      PIN_NUMBER='(0,0,0,0,0,0,0,0,0,0,0,0,0,0,0,0,0,0,0,0,0,0,0,0,0,0,0,0,0,0,0,0,AY64,0,0,0,0,0,0,0)';
      PINUSE='POWER';
      NO_LOAD_CHECK='Both';
      NO_IO_CHECK='Both';
      NO_ASSERT_CHECK='TRUE';
      NO_DIR_CHECK='TRUE';
      ALLOW_CONNECT='TRUE';
    'VSS_AY66':
      PIN_NUMBER='(0,0,0,0,0,0,0,0,0,0,0,0,0,0,0,0,0,0,0,0,0,0,0,0,0,0,0,0,0,0,0,0,AY66,0,0,0,0,0,0,0)';
      PINUSE='POWER';
      NO_LOAD_CHECK='Both';
      NO_IO_CHECK='Both';
      NO_ASSERT_CHECK='TRUE';
      NO_DIR_CHECK='TRUE';
      ALLOW_CONNECT='TRUE';
    'VSS_AY68':
      PIN_NUMBER='(0,0,0,0,0,0,0,0,0,0,0,0,0,0,0,0,0,0,0,0,0,0,0,0,0,0,0,0,0,0,0,0,AY68,0,0,0,0,0,0,0)';
      PINUSE='POWER';
      NO_LOAD_CHECK='Both';
      NO_IO_CHECK='Both';
      NO_ASSERT_CHECK='TRUE';
      NO_DIR_CHECK='TRUE';
      ALLOW_CONNECT='TRUE';
    'VSS_AY71':
      PIN_NUMBER='(0,0,0,0,0,0,0,0,0,0,0,0,0,0,0,0,0,0,0,0,0,0,0,0,0,0,0,0,0,0,0,0,AY71,0,0,0,0,0,0,0)';
      PINUSE='POWER';
      NO_LOAD_CHECK='Both';
      NO_IO_CHECK='Both';
      NO_ASSERT_CHECK='TRUE';
      NO_DIR_CHECK='TRUE';
      ALLOW_CONNECT='TRUE';
    'VSS_AY73':
      PIN_NUMBER='(0,0,0,0,0,0,0,0,0,0,0,0,0,0,0,0,0,0,0,0,0,0,0,0,0,0,0,0,0,0,0,0,AY73,0,0,0,0,0,0,0)';
      PINUSE='POWER';
      NO_LOAD_CHECK='Both';
      NO_IO_CHECK='Both';
      NO_ASSERT_CHECK='TRUE';
      NO_DIR_CHECK='TRUE';
      ALLOW_CONNECT='TRUE';
    'VSS_BA1':
      PIN_NUMBER='(0,0,0,0,0,0,0,0,0,0,0,0,0,0,0,0,0,0,0,0,0,0,0,0,0,0,0,0,0,0,0,0,BA1,0,0,0,0,0,0,0)';
      PINUSE='POWER';
      NO_LOAD_CHECK='Both';
      NO_IO_CHECK='Both';
      NO_ASSERT_CHECK='TRUE';
      NO_DIR_CHECK='TRUE';
      ALLOW_CONNECT='TRUE';
    'VSS_BA6':
      PIN_NUMBER='(0,0,0,0,0,0,0,0,0,0,0,0,0,0,0,0,0,0,0,0,0,0,0,0,0,0,0,0,0,0,0,0,BA6,0,0,0,0,0,0,0)';
      PINUSE='POWER';
      NO_LOAD_CHECK='Both';
      NO_IO_CHECK='Both';
      NO_ASSERT_CHECK='TRUE';
      NO_DIR_CHECK='TRUE';
      ALLOW_CONNECT='TRUE';
    'VSS_BA8':
      PIN_NUMBER='(0,0,0,0,0,0,0,0,0,0,0,0,0,0,0,0,0,0,0,0,0,0,0,0,0,0,0,0,0,0,0,0,BA8,0,0,0,0,0,0,0)';
      PINUSE='POWER';
      NO_LOAD_CHECK='Both';
      NO_IO_CHECK='Both';
      NO_ASSERT_CHECK='TRUE';
      NO_DIR_CHECK='TRUE';
      ALLOW_CONNECT='TRUE';
    'VSS_BA13':
      PIN_NUMBER='(0,0,0,0,0,0,0,0,0,0,0,0,0,0,0,0,0,0,0,0,0,0,0,0,0,0,0,0,0,0,0,0,BA13,0,0,0,0,0,0,0)';
      PINUSE='POWER';
      NO_LOAD_CHECK='Both';
      NO_IO_CHECK='Both';
      NO_ASSERT_CHECK='TRUE';
      NO_DIR_CHECK='TRUE';
      ALLOW_CONNECT='TRUE';
    'VSS_BA15':
      PIN_NUMBER='(0,0,0,0,0,0,0,0,0,0,0,0,0,0,0,0,0,0,0,0,0,0,0,0,0,0,0,0,0,0,0,0,BA15,0,0,0,0,0,0,0)';
      PINUSE='POWER';
      NO_LOAD_CHECK='Both';
      NO_IO_CHECK='Both';
      NO_ASSERT_CHECK='TRUE';
      NO_DIR_CHECK='TRUE';
      ALLOW_CONNECT='TRUE';
    'VSS_BA20':
      PIN_NUMBER='(0,0,0,0,0,0,0,0,0,0,0,0,0,0,0,0,0,0,0,0,0,0,0,0,0,0,0,0,0,0,0,0,BA20,0,0,0,0,0,0,0)';
      PINUSE='POWER';
      NO_LOAD_CHECK='Both';
      NO_IO_CHECK='Both';
      NO_ASSERT_CHECK='TRUE';
      NO_DIR_CHECK='TRUE';
      ALLOW_CONNECT='TRUE';
    'VSS_BA22':
      PIN_NUMBER='(0,0,0,0,0,0,0,0,0,0,0,0,0,0,0,0,0,0,0,0,0,0,0,0,0,0,0,0,0,0,0,0,BA22,0,0,0,0,0,0,0)';
      PINUSE='POWER';
      NO_LOAD_CHECK='Both';
      NO_IO_CHECK='Both';
      NO_ASSERT_CHECK='TRUE';
      NO_DIR_CHECK='TRUE';
      ALLOW_CONNECT='TRUE';
    'VSS_BA24':
      PIN_NUMBER='(0,0,0,0,0,0,0,0,0,0,0,0,0,0,0,0,0,0,0,0,0,0,0,0,0,0,0,0,0,0,0,0,BA24,0,0,0,0,0,0,0)';
      PINUSE='POWER';
      NO_LOAD_CHECK='Both';
      NO_IO_CHECK='Both';
      NO_ASSERT_CHECK='TRUE';
      NO_DIR_CHECK='TRUE';
      ALLOW_CONNECT='TRUE';
    'VSS_BA26':
      PIN_NUMBER='(0,0,0,0,0,0,0,0,0,0,0,0,0,0,0,0,0,0,0,0,0,0,0,0,0,0,0,0,0,0,0,0,BA26,0,0,0,0,0,0,0)';
      PINUSE='POWER';
      NO_LOAD_CHECK='Both';
      NO_IO_CHECK='Both';
      NO_ASSERT_CHECK='TRUE';
      NO_DIR_CHECK='TRUE';
      ALLOW_CONNECT='TRUE';
    'VSS_BA28':
      PIN_NUMBER='(0,0,0,0,0,0,0,0,0,0,0,0,0,0,0,0,0,0,0,0,0,0,0,0,0,0,0,0,0,0,0,0,BA28,0,0,0,0,0,0,0)';
      PINUSE='POWER';
      NO_LOAD_CHECK='Both';
      NO_IO_CHECK='Both';
      NO_ASSERT_CHECK='TRUE';
      NO_DIR_CHECK='TRUE';
      ALLOW_CONNECT='TRUE';
    'VSS_BA49':
      PIN_NUMBER='(0,0,0,0,0,0,0,0,0,0,0,0,0,0,0,0,0,0,0,0,0,0,0,0,0,0,0,0,0,0,0,0,BA49,0,0,0,0,0,0,0)';
      PINUSE='POWER';
      NO_LOAD_CHECK='Both';
      NO_IO_CHECK='Both';
      NO_ASSERT_CHECK='TRUE';
      NO_DIR_CHECK='TRUE';
      ALLOW_CONNECT='TRUE';
    'VSS_BA51':
      PIN_NUMBER='(0,0,0,0,0,0,0,0,0,0,0,0,0,0,0,0,0,0,0,0,0,0,0,0,0,0,0,0,0,0,0,0,BA51,0,0,0,0,0,0,0)';
      PINUSE='POWER';
      NO_LOAD_CHECK='Both';
      NO_IO_CHECK='Both';
      NO_ASSERT_CHECK='TRUE';
      NO_DIR_CHECK='TRUE';
      ALLOW_CONNECT='TRUE';
    'VSS_BA53':
      PIN_NUMBER='(0,0,0,0,0,0,0,0,0,0,0,0,0,0,0,0,0,0,0,0,0,0,0,0,0,0,0,0,0,0,0,0,BA53,0,0,0,0,0,0,0)';
      PINUSE='POWER';
      NO_LOAD_CHECK='Both';
      NO_IO_CHECK='Both';
      NO_ASSERT_CHECK='TRUE';
      NO_DIR_CHECK='TRUE';
      ALLOW_CONNECT='TRUE';
    'VSS_BA56':
      PIN_NUMBER='(0,0,0,0,0,0,0,0,0,0,0,0,0,0,0,0,0,0,0,0,0,0,0,0,0,0,0,0,0,0,0,0,BA56,0,0,0,0,0,0,0)';
      PINUSE='POWER';
      NO_LOAD_CHECK='Both';
      NO_IO_CHECK='Both';
      NO_ASSERT_CHECK='TRUE';
      NO_DIR_CHECK='TRUE';
      ALLOW_CONNECT='TRUE';
    'VSS_BA61':
      PIN_NUMBER='(0,0,0,0,0,0,0,0,0,0,0,0,0,0,0,0,0,0,0,0,0,0,0,0,0,0,0,0,0,0,0,0,BA61,0,0,0,0,0,0,0)';
      PINUSE='POWER';
      NO_LOAD_CHECK='Both';
      NO_IO_CHECK='Both';
      NO_ASSERT_CHECK='TRUE';
      NO_DIR_CHECK='TRUE';
      ALLOW_CONNECT='TRUE';
    'VSS_BA63':
      PIN_NUMBER='(0,0,0,0,0,0,0,0,0,0,0,0,0,0,0,0,0,0,0,0,0,0,0,0,0,0,0,0,0,0,0,0,BA63,0,0,0,0,0,0,0)';
      PINUSE='POWER';
      NO_LOAD_CHECK='Both';
      NO_IO_CHECK='Both';
      NO_ASSERT_CHECK='TRUE';
      NO_DIR_CHECK='TRUE';
      ALLOW_CONNECT='TRUE';
    'VSS_BA68':
      PIN_NUMBER='(0,0,0,0,0,0,0,0,0,0,0,0,0,0,0,0,0,0,0,0,0,0,0,0,0,0,0,0,0,0,0,0,BA68,0,0,0,0,0,0,0)';
      PINUSE='POWER';
      NO_LOAD_CHECK='Both';
      NO_IO_CHECK='Both';
      NO_ASSERT_CHECK='TRUE';
      NO_DIR_CHECK='TRUE';
      ALLOW_CONNECT='TRUE';
    'VSS_BA70':
      PIN_NUMBER='(0,0,0,0,0,0,0,0,0,0,0,0,0,0,0,0,0,0,0,0,0,0,0,0,0,0,0,0,0,0,0,0,BA70,0,0,0,0,0,0,0)';
      PINUSE='POWER';
      NO_LOAD_CHECK='Both';
      NO_IO_CHECK='Both';
      NO_ASSERT_CHECK='TRUE';
      NO_DIR_CHECK='TRUE';
      ALLOW_CONNECT='TRUE';
    'VSS_BA75':
      PIN_NUMBER='(0,0,0,0,0,0,0,0,0,0,0,0,0,0,0,0,0,0,0,0,0,0,0,0,0,0,0,0,0,0,0,0,BA75,0,0,0,0,0,0,0)';
      PINUSE='POWER';
      NO_LOAD_CHECK='Both';
      NO_IO_CHECK='Both';
      NO_ASSERT_CHECK='TRUE';
      NO_DIR_CHECK='TRUE';
      ALLOW_CONNECT='TRUE';
    'VSS_BB3':
      PIN_NUMBER='(0,0,0,0,0,0,0,0,0,0,0,0,0,0,0,0,0,0,0,0,0,0,0,0,0,0,0,0,0,0,0,0,BB3,0,0,0,0,0,0,0)';
      PINUSE='POWER';
      NO_LOAD_CHECK='Both';
      NO_IO_CHECK='Both';
      NO_ASSERT_CHECK='TRUE';
      NO_DIR_CHECK='TRUE';
      ALLOW_CONNECT='TRUE';
    'VSS_BB5':
      PIN_NUMBER='(0,0,0,0,0,0,0,0,0,0,0,0,0,0,0,0,0,0,0,0,0,0,0,0,0,0,0,0,0,0,0,0,BB5,0,0,0,0,0,0,0)';
      PINUSE='POWER';
      NO_LOAD_CHECK='Both';
      NO_IO_CHECK='Both';
      NO_ASSERT_CHECK='TRUE';
      NO_DIR_CHECK='TRUE';
      ALLOW_CONNECT='TRUE';
    'VSS_BB8':
      PIN_NUMBER='(0,0,0,0,0,0,0,0,0,0,0,0,0,0,0,0,0,0,0,0,0,0,0,0,0,0,0,0,0,0,0,0,BB8,0,0,0,0,0,0,0)';
      PINUSE='POWER';
      NO_LOAD_CHECK='Both';
      NO_IO_CHECK='Both';
      NO_ASSERT_CHECK='TRUE';
      NO_DIR_CHECK='TRUE';
      ALLOW_CONNECT='TRUE';
    'VSS_BB10':
      PIN_NUMBER='(0,0,0,0,0,0,0,0,0,0,0,0,0,0,0,0,0,0,0,0,0,0,0,0,0,0,0,0,0,0,0,0,BB10,0,0,0,0,0,0,0)';
      PINUSE='POWER';
      NO_LOAD_CHECK='Both';
      NO_IO_CHECK='Both';
      NO_ASSERT_CHECK='TRUE';
      NO_DIR_CHECK='TRUE';
      ALLOW_CONNECT='TRUE';
    'VSS_BB12':
      PIN_NUMBER='(0,0,0,0,0,0,0,0,0,0,0,0,0,0,0,0,0,0,0,0,0,0,0,0,0,0,0,0,0,0,0,0,BB12,0,0,0,0,0,0,0)';
      PINUSE='POWER';
      NO_LOAD_CHECK='Both';
      NO_IO_CHECK='Both';
      NO_ASSERT_CHECK='TRUE';
      NO_DIR_CHECK='TRUE';
      ALLOW_CONNECT='TRUE';
    'VSS_BB15':
      PIN_NUMBER='(0,0,0,0,0,0,0,0,0,0,0,0,0,0,0,0,0,0,0,0,0,0,0,0,0,0,0,0,0,0,0,0,BB15,0,0,0,0,0,0,0)';
      PINUSE='POWER';
      NO_LOAD_CHECK='Both';
      NO_IO_CHECK='Both';
      NO_ASSERT_CHECK='TRUE';
      NO_DIR_CHECK='TRUE';
      ALLOW_CONNECT='TRUE';
    'VSS_BB17':
      PIN_NUMBER='(0,0,0,0,0,0,0,0,0,0,0,0,0,0,0,0,0,0,0,0,0,0,0,0,0,0,0,0,0,0,0,0,BB17,0,0,0,0,0,0,0)';
      PINUSE='POWER';
      NO_LOAD_CHECK='Both';
      NO_IO_CHECK='Both';
      NO_ASSERT_CHECK='TRUE';
      NO_DIR_CHECK='TRUE';
      ALLOW_CONNECT='TRUE';
    'VSS_BB19':
      PIN_NUMBER='(0,0,0,0,0,0,0,0,0,0,0,0,0,0,0,0,0,0,0,0,0,0,0,0,0,0,0,0,0,0,0,0,BB19,0,0,0,0,0,0,0)';
      PINUSE='POWER';
      NO_LOAD_CHECK='Both';
      NO_IO_CHECK='Both';
      NO_ASSERT_CHECK='TRUE';
      NO_DIR_CHECK='TRUE';
      ALLOW_CONNECT='TRUE';
    'VSS_BB23':
      PIN_NUMBER='(0,0,0,0,0,0,0,0,0,0,0,0,0,0,0,0,0,0,0,0,0,0,0,0,0,0,0,0,0,0,0,0,BB23,0,0,0,0,0,0,0)';
      PINUSE='POWER';
      NO_LOAD_CHECK='Both';
      NO_IO_CHECK='Both';
      NO_ASSERT_CHECK='TRUE';
      NO_DIR_CHECK='TRUE';
      ALLOW_CONNECT='TRUE';
    'VSS_BB25':
      PIN_NUMBER='(0,0,0,0,0,0,0,0,0,0,0,0,0,0,0,0,0,0,0,0,0,0,0,0,0,0,0,0,0,0,0,0,BB25,0,0,0,0,0,0,0)';
      PINUSE='POWER';
      NO_LOAD_CHECK='Both';
      NO_IO_CHECK='Both';
      NO_ASSERT_CHECK='TRUE';
      NO_DIR_CHECK='TRUE';
      ALLOW_CONNECT='TRUE';
    'VSS_BB27':
      PIN_NUMBER='(0,0,0,0,0,0,0,0,0,0,0,0,0,0,0,0,0,0,0,0,0,0,0,0,0,0,0,0,0,0,0,0,BB27,0,0,0,0,0,0,0)';
      PINUSE='POWER';
      NO_LOAD_CHECK='Both';
      NO_IO_CHECK='Both';
      NO_ASSERT_CHECK='TRUE';
      NO_DIR_CHECK='TRUE';
      ALLOW_CONNECT='TRUE';
    'VSS_BB48':
      PIN_NUMBER='(0,0,0,0,0,0,0,0,0,0,0,0,0,0,0,0,0,0,0,0,0,0,0,0,0,0,0,0,0,0,0,0,BB48,0,0,0,0,0,0,0)';
      PINUSE='POWER';
      NO_LOAD_CHECK='Both';
      NO_IO_CHECK='Both';
      NO_ASSERT_CHECK='TRUE';
      NO_DIR_CHECK='TRUE';
      ALLOW_CONNECT='TRUE';
    'VSS_BB50':
      PIN_NUMBER='(0,0,0,0,0,0,0,0,0,0,0,0,0,0,0,0,0,0,0,0,0,0,0,0,0,0,0,0,0,0,0,0,BB50,0,0,0,0,0,0,0)';
      PINUSE='POWER';
      NO_LOAD_CHECK='Both';
      NO_IO_CHECK='Both';
      NO_ASSERT_CHECK='TRUE';
      NO_DIR_CHECK='TRUE';
      ALLOW_CONNECT='TRUE';
    'VSS_BB52':
      PIN_NUMBER='(0,0,0,0,0,0,0,0,0,0,0,0,0,0,0,0,0,0,0,0,0,0,0,0,0,0,0,0,0,0,0,0,BB52,0,0,0,0,0,0,0)';
      PINUSE='POWER';
      NO_LOAD_CHECK='Both';
      NO_IO_CHECK='Both';
      NO_ASSERT_CHECK='TRUE';
      NO_DIR_CHECK='TRUE';
      ALLOW_CONNECT='TRUE';
    'VSS_BB54':
      PIN_NUMBER='(0,0,0,0,0,0,0,0,0,0,0,0,0,0,0,0,0,0,0,0,0,0,0,0,0,0,0,0,0,0,0,0,BB54,0,0,0,0,0,0,0)';
      PINUSE='POWER';
      NO_LOAD_CHECK='Both';
      NO_IO_CHECK='Both';
      NO_ASSERT_CHECK='TRUE';
      NO_DIR_CHECK='TRUE';
      ALLOW_CONNECT='TRUE';
    'VSS_BB57':
      PIN_NUMBER='(0,0,0,0,0,0,0,0,0,0,0,0,0,0,0,0,0,0,0,0,0,0,0,0,0,0,0,0,0,0,0,0,BB57,0,0,0,0,0,0,0)';
      PINUSE='POWER';
      NO_LOAD_CHECK='Both';
      NO_IO_CHECK='Both';
      NO_ASSERT_CHECK='TRUE';
      NO_DIR_CHECK='TRUE';
      ALLOW_CONNECT='TRUE';
    'VSS_BB59':
      PIN_NUMBER='(0,0,0,0,0,0,0,0,0,0,0,0,0,0,0,0,0,0,0,0,0,0,0,0,0,0,0,0,0,0,0,0,BB59,0,0,0,0,0,0,0)';
      PINUSE='POWER';
      NO_LOAD_CHECK='Both';
      NO_IO_CHECK='Both';
      NO_ASSERT_CHECK='TRUE';
      NO_DIR_CHECK='TRUE';
      ALLOW_CONNECT='TRUE';
    'VSS_BB61':
      PIN_NUMBER='(0,0,0,0,0,0,0,0,0,0,0,0,0,0,0,0,0,0,0,0,0,0,0,0,0,0,0,0,0,0,0,0,BB61,0,0,0,0,0,0,0)';
      PINUSE='POWER';
      NO_LOAD_CHECK='Both';
      NO_IO_CHECK='Both';
      NO_ASSERT_CHECK='TRUE';
      NO_DIR_CHECK='TRUE';
      ALLOW_CONNECT='TRUE';
    'VSS_BB64':
      PIN_NUMBER='(0,0,0,0,0,0,0,0,0,0,0,0,0,0,0,0,0,0,0,0,0,0,0,0,0,0,0,0,0,0,0,0,BB64,0,0,0,0,0,0,0)';
      PINUSE='POWER';
      NO_LOAD_CHECK='Both';
      NO_IO_CHECK='Both';
      NO_ASSERT_CHECK='TRUE';
      NO_DIR_CHECK='TRUE';
      ALLOW_CONNECT='TRUE';
    'VSS_BB66':
      PIN_NUMBER='(0,0,0,0,0,0,0,0,0,0,0,0,0,0,0,0,0,0,0,0,0,0,0,0,0,0,0,0,0,0,0,0,BB66,0,0,0,0,0,0,0)';
      PINUSE='POWER';
      NO_LOAD_CHECK='Both';
      NO_IO_CHECK='Both';
      NO_ASSERT_CHECK='TRUE';
      NO_DIR_CHECK='TRUE';
      ALLOW_CONNECT='TRUE';
    'VSS_BB68':
      PIN_NUMBER='(0,0,0,0,0,0,0,0,0,0,0,0,0,0,0,0,0,0,0,0,0,0,0,0,0,0,0,0,0,0,0,0,BB68,0,0,0,0,0,0,0)';
      PINUSE='POWER';
      NO_LOAD_CHECK='Both';
      NO_IO_CHECK='Both';
      NO_ASSERT_CHECK='TRUE';
      NO_DIR_CHECK='TRUE';
      ALLOW_CONNECT='TRUE';
    'VSS_BB71':
      PIN_NUMBER='(0,0,0,0,0,0,0,0,0,0,0,0,0,0,0,0,0,0,0,0,0,0,0,0,0,0,0,0,0,0,0,0,BB71,0,0,0,0,0,0,0)';
      PINUSE='POWER';
      NO_LOAD_CHECK='Both';
      NO_IO_CHECK='Both';
      NO_ASSERT_CHECK='TRUE';
      NO_DIR_CHECK='TRUE';
      ALLOW_CONNECT='TRUE';
    'VSS_BB73':
      PIN_NUMBER='(0,0,0,0,0,0,0,0,0,0,0,0,0,0,0,0,0,0,0,0,0,0,0,0,0,0,0,0,0,0,0,0,BB73,0,0,0,0,0,0,0)';
      PINUSE='POWER';
      NO_LOAD_CHECK='Both';
      NO_IO_CHECK='Both';
      NO_ASSERT_CHECK='TRUE';
      NO_DIR_CHECK='TRUE';
      ALLOW_CONNECT='TRUE';
    'VSS_BC1':
      PIN_NUMBER='(0,0,0,0,0,0,0,0,0,0,0,0,0,0,0,0,0,0,0,0,0,0,0,0,0,0,0,0,0,0,0,0,BC1,0,0,0,0,0,0,0)';
      PINUSE='POWER';
      NO_LOAD_CHECK='Both';
      NO_IO_CHECK='Both';
      NO_ASSERT_CHECK='TRUE';
      NO_DIR_CHECK='TRUE';
      ALLOW_CONNECT='TRUE';
    'VSS_BC4':
      PIN_NUMBER='(0,0,0,0,0,0,0,0,0,0,0,0,0,0,0,0,0,0,0,0,0,0,0,0,0,0,0,0,0,0,0,0,BC4,0,0,0,0,0,0,0)';
      PINUSE='POWER';
      NO_LOAD_CHECK='Both';
      NO_IO_CHECK='Both';
      NO_ASSERT_CHECK='TRUE';
      NO_DIR_CHECK='TRUE';
      ALLOW_CONNECT='TRUE';
    'VSS_BC6':
      PIN_NUMBER='(0,0,0,0,0,0,0,0,0,0,0,0,0,0,0,0,0,0,0,0,0,0,0,0,0,0,0,0,0,0,0,0,BC6,0,0,0,0,0,0,0)';
      PINUSE='POWER';
      NO_LOAD_CHECK='Both';
      NO_IO_CHECK='Both';
      NO_ASSERT_CHECK='TRUE';
      NO_DIR_CHECK='TRUE';
      ALLOW_CONNECT='TRUE';
    'VSS_BC8':
      PIN_NUMBER='(0,0,0,0,0,0,0,0,0,0,0,0,0,0,0,0,0,0,0,0,0,0,0,0,0,0,0,0,0,0,0,0,BC8,0,0,0,0,0,0,0)';
      PINUSE='POWER';
      NO_LOAD_CHECK='Both';
      NO_IO_CHECK='Both';
      NO_ASSERT_CHECK='TRUE';
      NO_DIR_CHECK='TRUE';
      ALLOW_CONNECT='TRUE';
    'VSS_BC11':
      PIN_NUMBER='(0,0,0,0,0,0,0,0,0,0,0,0,0,0,0,0,0,0,0,0,0,0,0,0,0,0,0,0,0,0,0,0,BC11,0,0,0,0,0,0,0)';
      PINUSE='POWER';
      NO_LOAD_CHECK='Both';
      NO_IO_CHECK='Both';
      NO_ASSERT_CHECK='TRUE';
      NO_DIR_CHECK='TRUE';
      ALLOW_CONNECT='TRUE';
    'VSS_BC13':
      PIN_NUMBER='(0,0,0,0,0,0,0,0,0,0,0,0,0,0,0,0,0,0,0,0,0,0,0,0,0,0,0,0,0,0,0,0,BC13,0,0,0,0,0,0,0)';
      PINUSE='POWER';
      NO_LOAD_CHECK='Both';
      NO_IO_CHECK='Both';
      NO_ASSERT_CHECK='TRUE';
      NO_DIR_CHECK='TRUE';
      ALLOW_CONNECT='TRUE';
    'VSS_BC15':
      PIN_NUMBER='(0,0,0,0,0,0,0,0,0,0,0,0,0,0,0,0,0,0,0,0,0,0,0,0,0,0,0,0,0,0,0,0,BC15,0,0,0,0,0,0,0)';
      PINUSE='POWER';
      NO_LOAD_CHECK='Both';
      NO_IO_CHECK='Both';
      NO_ASSERT_CHECK='TRUE';
      NO_DIR_CHECK='TRUE';
      ALLOW_CONNECT='TRUE';
    'VSS_BC18':
      PIN_NUMBER='(0,0,0,0,0,0,0,0,0,0,0,0,0,0,0,0,0,0,0,0,0,0,0,0,0,0,0,0,0,0,0,0,BC18,0,0,0,0,0,0,0)';
      PINUSE='POWER';
      NO_LOAD_CHECK='Both';
      NO_IO_CHECK='Both';
      NO_ASSERT_CHECK='TRUE';
      NO_DIR_CHECK='TRUE';
      ALLOW_CONNECT='TRUE';
    'VSS_BC20':
      PIN_NUMBER='(0,0,0,0,0,0,0,0,0,0,0,0,0,0,0,0,0,0,0,0,0,0,0,0,0,0,0,0,0,0,0,0,BC20,0,0,0,0,0,0,0)';
      PINUSE='POWER';
      NO_LOAD_CHECK='Both';
      NO_IO_CHECK='Both';
      NO_ASSERT_CHECK='TRUE';
      NO_DIR_CHECK='TRUE';
      ALLOW_CONNECT='TRUE';
    'VSS_BC22':
      PIN_NUMBER='(0,0,0,0,0,0,0,0,0,0,0,0,0,0,0,0,0,0,0,0,0,0,0,0,0,0,0,0,0,0,0,0,BC22,0,0,0,0,0,0,0)';
      PINUSE='POWER';
      NO_LOAD_CHECK='Both';
      NO_IO_CHECK='Both';
      NO_ASSERT_CHECK='TRUE';
      NO_DIR_CHECK='TRUE';
      ALLOW_CONNECT='TRUE';
    'VSS_BC24':
      PIN_NUMBER='(0,0,0,0,0,0,0,0,0,0,0,0,0,0,0,0,0,0,0,0,0,0,0,0,0,0,0,0,0,0,0,0,BC24,0,0,0,0,0,0,0)';
      PINUSE='POWER';
      NO_LOAD_CHECK='Both';
      NO_IO_CHECK='Both';
      NO_ASSERT_CHECK='TRUE';
      NO_DIR_CHECK='TRUE';
      ALLOW_CONNECT='TRUE';
    'VSS_BC26':
      PIN_NUMBER='(0,0,0,0,0,0,0,0,0,0,0,0,0,0,0,0,0,0,0,0,0,0,0,0,0,0,0,0,0,0,0,0,BC26,0,0,0,0,0,0,0)';
      PINUSE='POWER';
      NO_LOAD_CHECK='Both';
      NO_IO_CHECK='Both';
      NO_ASSERT_CHECK='TRUE';
      NO_DIR_CHECK='TRUE';
      ALLOW_CONNECT='TRUE';
    'VSS_BC28':
      PIN_NUMBER='(0,0,0,0,0,0,0,0,0,0,0,0,0,0,0,0,0,0,0,0,0,0,0,0,0,0,0,0,0,0,0,0,BC28,0,0,0,0,0,0,0)';
      PINUSE='POWER';
      NO_LOAD_CHECK='Both';
      NO_IO_CHECK='Both';
      NO_ASSERT_CHECK='TRUE';
      NO_DIR_CHECK='TRUE';
      ALLOW_CONNECT='TRUE';
    'VSS_BC49':
      PIN_NUMBER='(0,0,0,0,0,0,0,0,0,0,0,0,0,0,0,0,0,0,0,0,0,0,0,0,0,0,0,0,0,0,0,0,BC49,0,0,0,0,0,0,0)';
      PINUSE='POWER';
      NO_LOAD_CHECK='Both';
      NO_IO_CHECK='Both';
      NO_ASSERT_CHECK='TRUE';
      NO_DIR_CHECK='TRUE';
      ALLOW_CONNECT='TRUE';
    'VSS_BC50':
      PIN_NUMBER='(0,0,0,0,0,0,0,0,0,0,0,0,0,0,0,0,0,0,0,0,0,0,0,0,0,0,0,0,0,0,0,0,BC50,0,0,0,0,0,0,0)';
      PINUSE='POWER';
      NO_LOAD_CHECK='Both';
      NO_IO_CHECK='Both';
      NO_ASSERT_CHECK='TRUE';
      NO_DIR_CHECK='TRUE';
      ALLOW_CONNECT='TRUE';
    'VSS_BC51':
      PIN_NUMBER='(0,0,0,0,0,0,0,0,0,0,0,0,0,0,0,0,0,0,0,0,0,0,0,0,0,0,0,0,0,0,0,0,BC51,0,0,0,0,0,0,0)';
      PINUSE='POWER';
      NO_LOAD_CHECK='Both';
      NO_IO_CHECK='Both';
      NO_ASSERT_CHECK='TRUE';
      NO_DIR_CHECK='TRUE';
      ALLOW_CONNECT='TRUE';
    'VSS_BC53':
      PIN_NUMBER='(0,0,0,0,0,0,0,0,0,0,0,0,0,0,0,0,0,0,0,0,0,0,0,0,0,0,0,0,0,0,0,0,BC53,0,0,0,0,0,0,0)';
      PINUSE='POWER';
      NO_LOAD_CHECK='Both';
      NO_IO_CHECK='Both';
      NO_ASSERT_CHECK='TRUE';
      NO_DIR_CHECK='TRUE';
      ALLOW_CONNECT='TRUE';
    'VSS_BC56':
      PIN_NUMBER='(0,0,0,0,0,0,0,0,0,0,0,0,0,0,0,0,0,0,0,0,0,0,0,0,0,0,0,0,0,0,0,0,BC56,0,0,0,0,0,0,0)';
      PINUSE='POWER';
      NO_LOAD_CHECK='Both';
      NO_IO_CHECK='Both';
      NO_ASSERT_CHECK='TRUE';
      NO_DIR_CHECK='TRUE';
      ALLOW_CONNECT='TRUE';
    'VSS_BC58':
      PIN_NUMBER='(0,0,0,0,0,0,0,0,0,0,0,0,0,0,0,0,0,0,0,0,0,0,0,0,0,0,0,0,0,0,0,0,BC58,0,0,0,0,0,0,0)';
      PINUSE='POWER';
      NO_LOAD_CHECK='Both';
      NO_IO_CHECK='Both';
      NO_ASSERT_CHECK='TRUE';
      NO_DIR_CHECK='TRUE';
      ALLOW_CONNECT='TRUE';
    'VSS_BC61':
      PIN_NUMBER='(0,0,0,0,0,0,0,0,0,0,0,0,0,0,0,0,0,0,0,0,0,0,0,0,0,0,0,0,0,0,0,0,BC61,0,0,0,0,0,0,0)';
      PINUSE='POWER';
      NO_LOAD_CHECK='Both';
      NO_IO_CHECK='Both';
      NO_ASSERT_CHECK='TRUE';
      NO_DIR_CHECK='TRUE';
      ALLOW_CONNECT='TRUE';
    'VSS_BC63':
      PIN_NUMBER='(0,0,0,0,0,0,0,0,0,0,0,0,0,0,0,0,0,0,0,0,0,0,0,0,0,0,0,0,0,0,0,0,BC63,0,0,0,0,0,0,0)';
      PINUSE='POWER';
      NO_LOAD_CHECK='Both';
      NO_IO_CHECK='Both';
      NO_ASSERT_CHECK='TRUE';
      NO_DIR_CHECK='TRUE';
      ALLOW_CONNECT='TRUE';
    'VSS_BC65':
      PIN_NUMBER='(0,0,0,0,0,0,0,0,0,0,0,0,0,0,0,0,0,0,0,0,0,0,0,0,0,0,0,0,0,0,0,0,BC65,0,0,0,0,0,0,0)';
      PINUSE='POWER';
      NO_LOAD_CHECK='Both';
      NO_IO_CHECK='Both';
      NO_ASSERT_CHECK='TRUE';
      NO_DIR_CHECK='TRUE';
      ALLOW_CONNECT='TRUE';
    'VSS_BC68':
      PIN_NUMBER='(0,0,0,0,0,0,0,0,0,0,0,0,0,0,0,0,0,0,0,0,0,0,0,0,0,0,0,0,0,0,0,0,BC68,0,0,0,0,0,0,0)';
      PINUSE='POWER';
      NO_LOAD_CHECK='Both';
      NO_IO_CHECK='Both';
      NO_ASSERT_CHECK='TRUE';
      NO_DIR_CHECK='TRUE';
      ALLOW_CONNECT='TRUE';
    'VSS_BC70':
      PIN_NUMBER='(0,0,0,0,0,0,0,0,0,0,0,0,0,0,0,0,0,0,0,0,0,0,0,0,0,0,0,0,0,0,0,0,BC70,0,0,0,0,0,0,0)';
      PINUSE='POWER';
      NO_LOAD_CHECK='Both';
      NO_IO_CHECK='Both';
      NO_ASSERT_CHECK='TRUE';
      NO_DIR_CHECK='TRUE';
      ALLOW_CONNECT='TRUE';
    'VSS_BC72':
      PIN_NUMBER='(0,0,0,0,0,0,0,0,0,0,0,0,0,0,0,0,0,0,0,0,0,0,0,0,0,0,0,0,0,0,0,0,BC72,0,0,0,0,0,0,0)';
      PINUSE='POWER';
      NO_LOAD_CHECK='Both';
      NO_IO_CHECK='Both';
      NO_ASSERT_CHECK='TRUE';
      NO_DIR_CHECK='TRUE';
      ALLOW_CONNECT='TRUE';
    'VSS_BC75':
      PIN_NUMBER='(0,0,0,0,0,0,0,0,0,0,0,0,0,0,0,0,0,0,0,0,0,0,0,0,0,0,0,0,0,0,0,0,BC75,0,0,0,0,0,0,0)';
      PINUSE='POWER';
      NO_LOAD_CHECK='Both';
      NO_IO_CHECK='Both';
      NO_ASSERT_CHECK='TRUE';
      NO_DIR_CHECK='TRUE';
      ALLOW_CONNECT='TRUE';
    'VSS_BD3':
      PIN_NUMBER='(0,0,0,0,0,0,0,0,0,0,0,0,0,0,0,0,0,0,0,0,0,0,0,0,0,0,0,0,0,0,0,0,BD3,0,0,0,0,0,0,0)';
      PINUSE='POWER';
      NO_LOAD_CHECK='Both';
      NO_IO_CHECK='Both';
      NO_ASSERT_CHECK='TRUE';
      NO_DIR_CHECK='TRUE';
      ALLOW_CONNECT='TRUE';
    'VSS_BD8':
      PIN_NUMBER='(0,0,0,0,0,0,0,0,0,0,0,0,0,0,0,0,0,0,0,0,0,0,0,0,0,0,0,0,0,0,0,0,BD8,0,0,0,0,0,0,0)';
      PINUSE='POWER';
      NO_LOAD_CHECK='Both';
      NO_IO_CHECK='Both';
      NO_ASSERT_CHECK='TRUE';
      NO_DIR_CHECK='TRUE';
      ALLOW_CONNECT='TRUE';
    'VSS_BD10':
      PIN_NUMBER='(0,0,0,0,0,0,0,0,0,0,0,0,0,0,0,0,0,0,0,0,0,0,0,0,0,0,0,0,0,0,0,0,BD10,0,0,0,0,0,0,0)';
      PINUSE='POWER';
      NO_LOAD_CHECK='Both';
      NO_IO_CHECK='Both';
      NO_ASSERT_CHECK='TRUE';
      NO_DIR_CHECK='TRUE';
      ALLOW_CONNECT='TRUE';
    'VSS_BD15':
      PIN_NUMBER='(0,0,0,0,0,0,0,0,0,0,0,0,0,0,0,0,0,0,0,0,0,0,0,0,0,0,0,0,0,0,0,0,BD15,0,0,0,0,0,0,0)';
      PINUSE='POWER';
      NO_LOAD_CHECK='Both';
      NO_IO_CHECK='Both';
      NO_ASSERT_CHECK='TRUE';
      NO_DIR_CHECK='TRUE';
      ALLOW_CONNECT='TRUE';
    'VSS_BD17':
      PIN_NUMBER='(0,0,0,0,0,0,0,0,0,0,0,0,0,0,0,0,0,0,0,0,0,0,0,0,0,0,0,0,0,0,0,0,BD17,0,0,0,0,0,0,0)';
      PINUSE='POWER';
      NO_LOAD_CHECK='Both';
      NO_IO_CHECK='Both';
      NO_ASSERT_CHECK='TRUE';
      NO_DIR_CHECK='TRUE';
      ALLOW_CONNECT='TRUE';
    'VSS_BD23':
      PIN_NUMBER='(0,0,0,0,0,0,0,0,0,0,0,0,0,0,0,0,0,0,0,0,0,0,0,0,0,0,0,0,0,0,0,0,BD23,0,0,0,0,0,0,0)';
      PINUSE='POWER';
      NO_LOAD_CHECK='Both';
      NO_IO_CHECK='Both';
      NO_ASSERT_CHECK='TRUE';
      NO_DIR_CHECK='TRUE';
      ALLOW_CONNECT='TRUE';
    'VSS_BD25':
      PIN_NUMBER='(0,0,0,0,0,0,0,0,0,0,0,0,0,0,0,0,0,0,0,0,0,0,0,0,0,0,0,0,0,0,0,0,BD25,0,0,0,0,0,0,0)';
      PINUSE='POWER';
      NO_LOAD_CHECK='Both';
      NO_IO_CHECK='Both';
      NO_ASSERT_CHECK='TRUE';
      NO_DIR_CHECK='TRUE';
      ALLOW_CONNECT='TRUE';
    'VSS_BD27':
      PIN_NUMBER='(0,0,0,0,0,0,0,0,0,0,0,0,0,0,0,0,0,0,0,0,0,0,0,0,0,0,0,0,0,0,0,0,BD27,0,0,0,0,0,0,0)';
      PINUSE='POWER';
      NO_LOAD_CHECK='Both';
      NO_IO_CHECK='Both';
      NO_ASSERT_CHECK='TRUE';
      NO_DIR_CHECK='TRUE';
      ALLOW_CONNECT='TRUE';
    'VSS_BD49':
      PIN_NUMBER='(0,0,0,0,0,0,0,0,0,0,0,0,0,0,0,0,0,0,0,0,0,0,0,0,0,0,0,0,0,0,0,0,BD49,0,0,0,0,0,0,0)';
      PINUSE='POWER';
      NO_LOAD_CHECK='Both';
      NO_IO_CHECK='Both';
      NO_ASSERT_CHECK='TRUE';
      NO_DIR_CHECK='TRUE';
      ALLOW_CONNECT='TRUE';
    'VSS_BD51':
      PIN_NUMBER='(0,0,0,0,0,0,0,0,0,0,0,0,0,0,0,0,0,0,0,0,0,0,0,0,0,0,0,0,0,0,0,0,BD51,0,0,0,0,0,0,0)';
      PINUSE='POWER';
      NO_LOAD_CHECK='Both';
      NO_IO_CHECK='Both';
      NO_ASSERT_CHECK='TRUE';
      NO_DIR_CHECK='TRUE';
      ALLOW_CONNECT='TRUE';
    'VSS_BD53':
      PIN_NUMBER='(0,0,0,0,0,0,0,0,0,0,0,0,0,0,0,0,0,0,0,0,0,0,0,0,0,0,0,0,0,0,0,0,BD53,0,0,0,0,0,0,0)';
      PINUSE='POWER';
      NO_LOAD_CHECK='Both';
      NO_IO_CHECK='Both';
      NO_ASSERT_CHECK='TRUE';
      NO_DIR_CHECK='TRUE';
      ALLOW_CONNECT='TRUE';
    'VSS_BD57':
      PIN_NUMBER='(0,0,0,0,0,0,0,0,0,0,0,0,0,0,0,0,0,0,0,0,0,0,0,0,0,0,0,0,0,0,0,0,BD57,0,0,0,0,0,0,0)';
      PINUSE='POWER';
      NO_LOAD_CHECK='Both';
      NO_IO_CHECK='Both';
      NO_ASSERT_CHECK='TRUE';
      NO_DIR_CHECK='TRUE';
      ALLOW_CONNECT='TRUE';
    'VSS_BD59':
      PIN_NUMBER='(0,0,0,0,0,0,0,0,0,0,0,0,0,0,0,0,0,0,0,0,0,0,0,0,0,0,0,0,0,0,0,0,BD59,0,0,0,0,0,0,0)';
      PINUSE='POWER';
      NO_LOAD_CHECK='Both';
      NO_IO_CHECK='Both';
      NO_ASSERT_CHECK='TRUE';
      NO_DIR_CHECK='TRUE';
      ALLOW_CONNECT='TRUE';
    'VSS_BD61':
      PIN_NUMBER='(0,0,0,0,0,0,0,0,0,0,0,0,0,0,0,0,0,0,0,0,0,0,0,0,0,0,0,0,0,0,0,0,BD61,0,0,0,0,0,0,0)';
      PINUSE='POWER';
      NO_LOAD_CHECK='Both';
      NO_IO_CHECK='Both';
      NO_ASSERT_CHECK='TRUE';
      NO_DIR_CHECK='TRUE';
      ALLOW_CONNECT='TRUE';
    'VSS_BD64':
      PIN_NUMBER='(0,0,0,0,0,0,0,0,0,0,0,0,0,0,0,0,0,0,0,0,0,0,0,0,0,0,0,0,0,0,0,0,BD64,0,0,0,0,0,0,0)';
      PINUSE='POWER';
      NO_LOAD_CHECK='Both';
      NO_IO_CHECK='Both';
      NO_ASSERT_CHECK='TRUE';
      NO_DIR_CHECK='TRUE';
      ALLOW_CONNECT='TRUE';
    'VSS_BD66':
      PIN_NUMBER='(0,0,0,0,0,0,0,0,0,0,0,0,0,0,0,0,0,0,0,0,0,0,0,0,0,0,0,0,0,0,0,0,BD66,0,0,0,0,0,0,0)';
      PINUSE='POWER';
      NO_LOAD_CHECK='Both';
      NO_IO_CHECK='Both';
      NO_ASSERT_CHECK='TRUE';
      NO_DIR_CHECK='TRUE';
      ALLOW_CONNECT='TRUE';
    'VSS_BD68':
      PIN_NUMBER='(0,0,0,0,0,0,0,0,0,0,0,0,0,0,0,0,0,0,0,0,0,0,0,0,0,0,0,0,0,0,0,0,BD68,0,0,0,0,0,0,0)';
      PINUSE='POWER';
      NO_LOAD_CHECK='Both';
      NO_IO_CHECK='Both';
      NO_ASSERT_CHECK='TRUE';
      NO_DIR_CHECK='TRUE';
      ALLOW_CONNECT='TRUE';
    'VSS_BD71':
      PIN_NUMBER='(0,0,0,0,0,0,0,0,0,0,0,0,0,0,0,0,0,0,0,0,0,0,0,0,0,0,0,0,0,0,0,0,BD71,0,0,0,0,0,0,0)';
      PINUSE='POWER';
      NO_LOAD_CHECK='Both';
      NO_IO_CHECK='Both';
      NO_ASSERT_CHECK='TRUE';
      NO_DIR_CHECK='TRUE';
      ALLOW_CONNECT='TRUE';
    'VSS_BD73':
      PIN_NUMBER='(0,0,0,0,0,0,0,0,0,0,0,0,0,0,0,0,0,0,0,0,0,0,0,0,0,0,0,0,0,0,0,0,BD73,0,0,0,0,0,0,0)';
      PINUSE='POWER';
      NO_LOAD_CHECK='Both';
      NO_IO_CHECK='Both';
      NO_ASSERT_CHECK='TRUE';
      NO_DIR_CHECK='TRUE';
      ALLOW_CONNECT='TRUE';
    'VSS_BF3':
      PIN_NUMBER='(0,0,0,0,0,0,0,0,0,0,0,0,0,0,0,0,0,0,0,0,0,0,0,0,0,0,0,0,0,0,0,0,BF3,0,0,0,0,0,0,0)';
      PINUSE='POWER';
      NO_LOAD_CHECK='Both';
      NO_IO_CHECK='Both';
      NO_ASSERT_CHECK='TRUE';
      NO_DIR_CHECK='TRUE';
      ALLOW_CONNECT='TRUE';
    'VSS_BF5':
      PIN_NUMBER='(0,0,0,0,0,0,0,0,0,0,0,0,0,0,0,0,0,0,0,0,0,0,0,0,0,0,0,0,0,0,0,0,BF5,0,0,0,0,0,0,0)';
      PINUSE='POWER';
      NO_LOAD_CHECK='Both';
      NO_IO_CHECK='Both';
      NO_ASSERT_CHECK='TRUE';
      NO_DIR_CHECK='TRUE';
      ALLOW_CONNECT='TRUE';
    'VSS_BF8':
      PIN_NUMBER='(0,0,0,0,0,0,0,0,0,0,0,0,0,0,0,0,0,0,0,0,0,0,0,0,0,0,0,0,0,0,0,0,BF8,0,0,0,0,0,0,0)';
      PINUSE='POWER';
      NO_LOAD_CHECK='Both';
      NO_IO_CHECK='Both';
      NO_ASSERT_CHECK='TRUE';
      NO_DIR_CHECK='TRUE';
      ALLOW_CONNECT='TRUE';
    'VSS_BF10':
      PIN_NUMBER='(0,0,0,0,0,0,0,0,0,0,0,0,0,0,0,0,0,0,0,0,0,0,0,0,0,0,0,0,0,0,0,0,BF10,0,0,0,0,0,0,0)';
      PINUSE='POWER';
      NO_LOAD_CHECK='Both';
      NO_IO_CHECK='Both';
      NO_ASSERT_CHECK='TRUE';
      NO_DIR_CHECK='TRUE';
      ALLOW_CONNECT='TRUE';
    'VSS_BF12':
      PIN_NUMBER='(0,0,0,0,0,0,0,0,0,0,0,0,0,0,0,0,0,0,0,0,0,0,0,0,0,0,0,0,0,0,0,0,BF12,0,0,0,0,0,0,0)';
      PINUSE='POWER';
      NO_LOAD_CHECK='Both';
      NO_IO_CHECK='Both';
      NO_ASSERT_CHECK='TRUE';
      NO_DIR_CHECK='TRUE';
      ALLOW_CONNECT='TRUE';
    'VSS_BF15':
      PIN_NUMBER='(0,0,0,0,0,0,0,0,0,0,0,0,0,0,0,0,0,0,0,0,0,0,0,0,0,0,0,0,0,0,0,0,BF15,0,0,0,0,0,0,0)';
      PINUSE='POWER';
      NO_LOAD_CHECK='Both';
      NO_IO_CHECK='Both';
      NO_ASSERT_CHECK='TRUE';
      NO_DIR_CHECK='TRUE';
      ALLOW_CONNECT='TRUE';
    'VSS_BF17':
      PIN_NUMBER='(0,0,0,0,0,0,0,0,0,0,0,0,0,0,0,0,0,0,0,0,0,0,0,0,0,0,0,0,0,0,0,0,BF17,0,0,0,0,0,0,0)';
      PINUSE='POWER';
      NO_LOAD_CHECK='Both';
      NO_IO_CHECK='Both';
      NO_ASSERT_CHECK='TRUE';
      NO_DIR_CHECK='TRUE';
      ALLOW_CONNECT='TRUE';
    'VSS_BF19':
      PIN_NUMBER='(0,0,0,0,0,0,0,0,0,0,0,0,0,0,0,0,0,0,0,0,0,0,0,0,0,0,0,0,0,0,0,0,BF19,0,0,0,0,0,0,0)';
      PINUSE='POWER';
      NO_LOAD_CHECK='Both';
      NO_IO_CHECK='Both';
      NO_ASSERT_CHECK='TRUE';
      NO_DIR_CHECK='TRUE';
      ALLOW_CONNECT='TRUE';
    'VSS_BF22':
      PIN_NUMBER='(0,0,0,0,0,0,0,0,0,0,0,0,0,0,0,0,0,0,0,0,0,0,0,0,0,0,0,0,0,0,0,0,BF22,0,0,0,0,0,0,0)';
      PINUSE='POWER';
      NO_LOAD_CHECK='Both';
      NO_IO_CHECK='Both';
      NO_ASSERT_CHECK='TRUE';
      NO_DIR_CHECK='TRUE';
      ALLOW_CONNECT='TRUE';
    'VSS_BF24':
      PIN_NUMBER='(0,0,0,0,0,0,0,0,0,0,0,0,0,0,0,0,0,0,0,0,0,0,0,0,0,0,0,0,0,0,0,0,BF24,0,0,0,0,0,0,0)';
      PINUSE='POWER';
      NO_LOAD_CHECK='Both';
      NO_IO_CHECK='Both';
      NO_ASSERT_CHECK='TRUE';
      NO_DIR_CHECK='TRUE';
      ALLOW_CONNECT='TRUE';
    'VSS_BF26':
      PIN_NUMBER='(0,0,0,0,0,0,0,0,0,0,0,0,0,0,0,0,0,0,0,0,0,0,0,0,0,0,0,0,0,0,0,0,BF26,0,0,0,0,0,0,0)';
      PINUSE='POWER';
      NO_LOAD_CHECK='Both';
      NO_IO_CHECK='Both';
      NO_ASSERT_CHECK='TRUE';
      NO_DIR_CHECK='TRUE';
      ALLOW_CONNECT='TRUE';
    'VSS_BF28':
      PIN_NUMBER='(0,0,0,0,0,0,0,0,0,0,0,0,0,0,0,0,0,0,0,0,0,0,0,0,0,0,0,0,0,0,0,0,BF28,0,0,0,0,0,0,0)';
      PINUSE='POWER';
      NO_LOAD_CHECK='Both';
      NO_IO_CHECK='Both';
      NO_ASSERT_CHECK='TRUE';
      NO_DIR_CHECK='TRUE';
      ALLOW_CONNECT='TRUE';
    'VSS_BF49':
      PIN_NUMBER='(0,0,0,0,0,0,0,0,0,0,0,0,0,0,0,0,0,0,0,0,0,0,0,0,0,0,0,0,0,0,0,0,BF49,0,0,0,0,0,0,0)';
      PINUSE='POWER';
      NO_LOAD_CHECK='Both';
      NO_IO_CHECK='Both';
      NO_ASSERT_CHECK='TRUE';
      NO_DIR_CHECK='TRUE';
      ALLOW_CONNECT='TRUE';
    'VSS_BF50':
      PIN_NUMBER='(0,0,0,0,0,0,0,0,0,0,0,0,0,0,0,0,0,0,0,0,0,0,0,0,0,0,0,0,0,0,0,0,BF50,0,0,0,0,0,0,0)';
      PINUSE='POWER';
      NO_LOAD_CHECK='Both';
      NO_IO_CHECK='Both';
      NO_ASSERT_CHECK='TRUE';
      NO_DIR_CHECK='TRUE';
      ALLOW_CONNECT='TRUE';
    'VSS_BF52':
      PIN_NUMBER='(0,0,0,0,0,0,0,0,0,0,0,0,0,0,0,0,0,0,0,0,0,0,0,0,0,0,0,0,0,0,0,0,BF52,0,0,0,0,0,0,0)';
      PINUSE='POWER';
      NO_LOAD_CHECK='Both';
      NO_IO_CHECK='Both';
      NO_ASSERT_CHECK='TRUE';
      NO_DIR_CHECK='TRUE';
      ALLOW_CONNECT='TRUE';
    'VSS_BF54':
      PIN_NUMBER='(0,0,0,0,0,0,0,0,0,0,0,0,0,0,0,0,0,0,0,0,0,0,0,0,0,0,0,0,0,0,0,0,BF54,0,0,0,0,0,0,0)';
      PINUSE='POWER';
      NO_LOAD_CHECK='Both';
      NO_IO_CHECK='Both';
      NO_ASSERT_CHECK='TRUE';
      NO_DIR_CHECK='TRUE';
      ALLOW_CONNECT='TRUE';
    'VSS_BF59':
      PIN_NUMBER='(0,0,0,0,0,0,0,0,0,0,0,0,0,0,0,0,0,0,0,0,0,0,0,0,0,0,0,0,0,0,0,0,BF59,0,0,0,0,0,0,0)';
      PINUSE='POWER';
      NO_LOAD_CHECK='Both';
      NO_IO_CHECK='Both';
      NO_ASSERT_CHECK='TRUE';
      NO_DIR_CHECK='TRUE';
      ALLOW_CONNECT='TRUE';
    'VSS_BF61':
      PIN_NUMBER='(0,0,0,0,0,0,0,0,0,0,0,0,0,0,0,0,0,0,0,0,0,0,0,0,0,0,0,0,0,0,0,0,BF61,0,0,0,0,0,0,0)';
      PINUSE='POWER';
      NO_LOAD_CHECK='Both';
      NO_IO_CHECK='Both';
      NO_ASSERT_CHECK='TRUE';
      NO_DIR_CHECK='TRUE';
      ALLOW_CONNECT='TRUE';
    'VSS_BF66':
      PIN_NUMBER='(0,0,0,0,0,0,0,0,0,0,0,0,0,0,0,0,0,0,0,0,0,0,0,0,0,0,0,0,0,0,0,0,BF66,0,0,0,0,0,0,0)';
      PINUSE='POWER';
      NO_LOAD_CHECK='Both';
      NO_IO_CHECK='Both';
      NO_ASSERT_CHECK='TRUE';
      NO_DIR_CHECK='TRUE';
      ALLOW_CONNECT='TRUE';
    'VSS_BF68':
      PIN_NUMBER='(0,0,0,0,0,0,0,0,0,0,0,0,0,0,0,0,0,0,0,0,0,0,0,0,0,0,0,0,0,0,0,0,BF68,0,0,0,0,0,0,0)';
      PINUSE='POWER';
      NO_LOAD_CHECK='Both';
      NO_IO_CHECK='Both';
      NO_ASSERT_CHECK='TRUE';
      NO_DIR_CHECK='TRUE';
      ALLOW_CONNECT='TRUE';
    'VSS_BF73':
      PIN_NUMBER='(0,0,0,0,0,0,0,0,0,0,0,0,0,0,0,0,0,0,0,0,0,0,0,0,0,0,0,0,0,0,0,0,BF73,0,0,0,0,0,0,0)';
      PINUSE='POWER';
      NO_LOAD_CHECK='Both';
      NO_IO_CHECK='Both';
      NO_ASSERT_CHECK='TRUE';
      NO_DIR_CHECK='TRUE';
      ALLOW_CONNECT='TRUE';
    'VSS_BG1':
      PIN_NUMBER='(0,0,0,0,0,0,0,0,0,0,0,0,0,0,0,0,0,0,0,0,0,0,0,0,0,0,0,0,0,0,0,0,BG1,0,0,0,0,0,0,0)';
      PINUSE='POWER';
      NO_LOAD_CHECK='Both';
      NO_IO_CHECK='Both';
      NO_ASSERT_CHECK='TRUE';
      NO_DIR_CHECK='TRUE';
      ALLOW_CONNECT='TRUE';
    'VSS_BG4':
      PIN_NUMBER='(0,0,0,0,0,0,0,0,0,0,0,0,0,0,0,0,0,0,0,0,0,0,0,0,0,0,0,0,0,0,0,0,BG4,0,0,0,0,0,0,0)';
      PINUSE='POWER';
      NO_LOAD_CHECK='Both';
      NO_IO_CHECK='Both';
      NO_ASSERT_CHECK='TRUE';
      NO_DIR_CHECK='TRUE';
      ALLOW_CONNECT='TRUE';
    'VSS_BG6':
      PIN_NUMBER='(0,0,0,0,0,0,0,0,0,0,0,0,0,0,0,0,0,0,0,0,0,0,0,0,0,0,0,0,0,0,0,0,BG6,0,0,0,0,0,0,0)';
      PINUSE='POWER';
      NO_LOAD_CHECK='Both';
      NO_IO_CHECK='Both';
      NO_ASSERT_CHECK='TRUE';
      NO_DIR_CHECK='TRUE';
      ALLOW_CONNECT='TRUE';
    'VSS_BG8':
      PIN_NUMBER='(0,0,0,0,0,0,0,0,0,0,0,0,0,0,0,0,0,0,0,0,0,0,0,0,0,0,0,0,0,0,0,0,BG8,0,0,0,0,0,0,0)';
      PINUSE='POWER';
      NO_LOAD_CHECK='Both';
      NO_IO_CHECK='Both';
      NO_ASSERT_CHECK='TRUE';
      NO_DIR_CHECK='TRUE';
      ALLOW_CONNECT='TRUE';
    'VSS_BG11':
      PIN_NUMBER='(0,0,0,0,0,0,0,0,0,0,0,0,0,0,0,0,0,0,0,0,0,0,0,0,0,0,0,0,0,0,0,0,BG11,0,0,0,0,0,0,0)';
      PINUSE='POWER';
      NO_LOAD_CHECK='Both';
      NO_IO_CHECK='Both';
      NO_ASSERT_CHECK='TRUE';
      NO_DIR_CHECK='TRUE';
      ALLOW_CONNECT='TRUE';
    'VSS_BG13':
      PIN_NUMBER='(0,0,0,0,0,0,0,0,0,0,0,0,0,0,0,0,0,0,0,0,0,0,0,0,0,0,0,0,0,0,0,0,BG13,0,0,0,0,0,0,0)';
      PINUSE='POWER';
      NO_LOAD_CHECK='Both';
      NO_IO_CHECK='Both';
      NO_ASSERT_CHECK='TRUE';
      NO_DIR_CHECK='TRUE';
      ALLOW_CONNECT='TRUE';
    'VSS_BG15':
      PIN_NUMBER='(0,0,0,0,0,0,0,0,0,0,0,0,0,0,0,0,0,0,0,0,0,0,0,0,0,0,0,0,0,0,0,0,BG15,0,0,0,0,0,0,0)';
      PINUSE='POWER';
      NO_LOAD_CHECK='Both';
      NO_IO_CHECK='Both';
      NO_ASSERT_CHECK='TRUE';
      NO_DIR_CHECK='TRUE';
      ALLOW_CONNECT='TRUE';
    'VSS_BG18':
      PIN_NUMBER='(0,0,0,0,0,0,0,0,0,0,0,0,0,0,0,0,0,0,0,0,0,0,0,0,0,0,0,0,0,0,0,0,BG18,0,0,0,0,0,0,0)';
      PINUSE='POWER';
      NO_LOAD_CHECK='Both';
      NO_IO_CHECK='Both';
      NO_ASSERT_CHECK='TRUE';
      NO_DIR_CHECK='TRUE';
      ALLOW_CONNECT='TRUE';
    'VSS_BG20':
      PIN_NUMBER='(0,0,0,0,0,0,0,0,0,0,0,0,0,0,0,0,0,0,0,0,0,0,0,0,0,0,0,0,0,0,0,0,BG20,0,0,0,0,0,0,0)';
      PINUSE='POWER';
      NO_LOAD_CHECK='Both';
      NO_IO_CHECK='Both';
      NO_ASSERT_CHECK='TRUE';
      NO_DIR_CHECK='TRUE';
      ALLOW_CONNECT='TRUE';
    'VSS_BG23':
      PIN_NUMBER='(0,0,0,0,0,0,0,0,0,0,0,0,0,0,0,0,0,0,0,0,0,0,0,0,0,0,0,0,0,0,0,0,BG23,0,0,0,0,0,0,0)';
      PINUSE='POWER';
      NO_LOAD_CHECK='Both';
      NO_IO_CHECK='Both';
      NO_ASSERT_CHECK='TRUE';
      NO_DIR_CHECK='TRUE';
      ALLOW_CONNECT='TRUE';
    'VSS_BG25':
      PIN_NUMBER='(0,0,0,0,0,0,0,0,0,0,0,0,0,0,0,0,0,0,0,0,0,0,0,0,0,0,0,0,0,0,0,0,BG25,0,0,0,0,0,0,0)';
      PINUSE='POWER';
      NO_LOAD_CHECK='Both';
      NO_IO_CHECK='Both';
      NO_ASSERT_CHECK='TRUE';
      NO_DIR_CHECK='TRUE';
      ALLOW_CONNECT='TRUE';
    'VSS_BG27':
      PIN_NUMBER='(0,0,0,0,0,0,0,0,0,0,0,0,0,0,0,0,0,0,0,0,0,0,0,0,0,0,0,0,0,0,0,0,BG27,0,0,0,0,0,0,0)';
      PINUSE='POWER';
      NO_LOAD_CHECK='Both';
      NO_IO_CHECK='Both';
      NO_ASSERT_CHECK='TRUE';
      NO_DIR_CHECK='TRUE';
      ALLOW_CONNECT='TRUE';
    'VSS_BG49':
      PIN_NUMBER='(0,0,0,0,0,0,0,0,0,0,0,0,0,0,0,0,0,0,0,0,0,0,0,0,0,0,0,0,0,0,0,0,BG49,0,0,0,0,0,0,0)';
      PINUSE='POWER';
      NO_LOAD_CHECK='Both';
      NO_IO_CHECK='Both';
      NO_ASSERT_CHECK='TRUE';
      NO_DIR_CHECK='TRUE';
      ALLOW_CONNECT='TRUE';
    'VSS_BG51':
      PIN_NUMBER='(0,0,0,0,0,0,0,0,0,0,0,0,0,0,0,0,0,0,0,0,0,0,0,0,0,0,0,0,0,0,0,0,BG51,0,0,0,0,0,0,0)';
      PINUSE='POWER';
      NO_LOAD_CHECK='Both';
      NO_IO_CHECK='Both';
      NO_ASSERT_CHECK='TRUE';
      NO_DIR_CHECK='TRUE';
      ALLOW_CONNECT='TRUE';
    'VSS_BG53':
      PIN_NUMBER='(0,0,0,0,0,0,0,0,0,0,0,0,0,0,0,0,0,0,0,0,0,0,0,0,0,0,0,0,0,0,0,0,BG53,0,0,0,0,0,0,0)';
      PINUSE='POWER';
      NO_LOAD_CHECK='Both';
      NO_IO_CHECK='Both';
      NO_ASSERT_CHECK='TRUE';
      NO_DIR_CHECK='TRUE';
      ALLOW_CONNECT='TRUE';
    'VSS_BG56':
      PIN_NUMBER='(0,0,0,0,0,0,0,0,0,0,0,0,0,0,0,0,0,0,0,0,0,0,0,0,0,0,0,0,0,0,0,0,BG56,0,0,0,0,0,0,0)';
      PINUSE='POWER';
      NO_LOAD_CHECK='Both';
      NO_IO_CHECK='Both';
      NO_ASSERT_CHECK='TRUE';
      NO_DIR_CHECK='TRUE';
      ALLOW_CONNECT='TRUE';
    'VSS_BG58':
      PIN_NUMBER='(0,0,0,0,0,0,0,0,0,0,0,0,0,0,0,0,0,0,0,0,0,0,0,0,0,0,0,0,0,0,0,0,BG58,0,0,0,0,0,0,0)';
      PINUSE='POWER';
      NO_LOAD_CHECK='Both';
      NO_IO_CHECK='Both';
      NO_ASSERT_CHECK='TRUE';
      NO_DIR_CHECK='TRUE';
      ALLOW_CONNECT='TRUE';
    'VSS_BG61':
      PIN_NUMBER='(0,0,0,0,0,0,0,0,0,0,0,0,0,0,0,0,0,0,0,0,0,0,0,0,0,0,0,0,0,0,0,0,BG61,0,0,0,0,0,0,0)';
      PINUSE='POWER';
      NO_LOAD_CHECK='Both';
      NO_IO_CHECK='Both';
      NO_ASSERT_CHECK='TRUE';
      NO_DIR_CHECK='TRUE';
      ALLOW_CONNECT='TRUE';
    'VSS_BG63':
      PIN_NUMBER='(0,0,0,0,0,0,0,0,0,0,0,0,0,0,0,0,0,0,0,0,0,0,0,0,0,0,0,0,0,0,0,0,BG63,0,0,0,0,0,0,0)';
      PINUSE='POWER';
      NO_LOAD_CHECK='Both';
      NO_IO_CHECK='Both';
      NO_ASSERT_CHECK='TRUE';
      NO_DIR_CHECK='TRUE';
      ALLOW_CONNECT='TRUE';
    'VSS_BG65':
      PIN_NUMBER='(0,0,0,0,0,0,0,0,0,0,0,0,0,0,0,0,0,0,0,0,0,0,0,0,0,0,0,0,0,0,0,0,BG65,0,0,0,0,0,0,0)';
      PINUSE='POWER';
      NO_LOAD_CHECK='Both';
      NO_IO_CHECK='Both';
      NO_ASSERT_CHECK='TRUE';
      NO_DIR_CHECK='TRUE';
      ALLOW_CONNECT='TRUE';
    'VSS_BG68':
      PIN_NUMBER='(0,0,0,0,0,0,0,0,0,0,0,0,0,0,0,0,0,0,0,0,0,0,0,0,0,0,0,0,0,0,0,0,BG68,0,0,0,0,0,0,0)';
      PINUSE='POWER';
      NO_LOAD_CHECK='Both';
      NO_IO_CHECK='Both';
      NO_ASSERT_CHECK='TRUE';
      NO_DIR_CHECK='TRUE';
      ALLOW_CONNECT='TRUE';
    'VSS_BG70':
      PIN_NUMBER='(0,0,0,0,0,0,0,0,0,0,0,0,0,0,0,0,0,0,0,0,0,0,0,0,0,0,0,0,0,0,0,0,BG70,0,0,0,0,0,0,0)';
      PINUSE='POWER';
      NO_LOAD_CHECK='Both';
      NO_IO_CHECK='Both';
      NO_ASSERT_CHECK='TRUE';
      NO_DIR_CHECK='TRUE';
      ALLOW_CONNECT='TRUE';
    'VSS_BG72':
      PIN_NUMBER='(0,0,0,0,0,0,0,0,0,0,0,0,0,0,0,0,0,0,0,0,0,0,0,0,0,0,0,0,0,0,0,0,BG72,0,0,0,0,0,0,0)';
      PINUSE='POWER';
      NO_LOAD_CHECK='Both';
      NO_IO_CHECK='Both';
      NO_ASSERT_CHECK='TRUE';
      NO_DIR_CHECK='TRUE';
      ALLOW_CONNECT='TRUE';
    'VSS_BG75':
      PIN_NUMBER='(0,0,0,0,0,0,0,0,0,0,0,0,0,0,0,0,0,0,0,0,0,0,0,0,0,0,0,0,0,0,0,0,BG75,0,0,0,0,0,0,0)';
      PINUSE='POWER';
      NO_LOAD_CHECK='Both';
      NO_IO_CHECK='Both';
      NO_ASSERT_CHECK='TRUE';
      NO_DIR_CHECK='TRUE';
      ALLOW_CONNECT='TRUE';
    'VSS_BH3':
      PIN_NUMBER='(0,0,0,0,0,0,0,0,0,0,0,0,0,0,0,0,0,0,0,0,0,0,0,0,0,0,0,0,0,0,0,0,BH3,0,0,0,0,0,0,0)';
      PINUSE='POWER';
      NO_LOAD_CHECK='Both';
      NO_IO_CHECK='Both';
      NO_ASSERT_CHECK='TRUE';
      NO_DIR_CHECK='TRUE';
      ALLOW_CONNECT='TRUE';
    'VSS_BH5':
      PIN_NUMBER='(0,0,0,0,0,0,0,0,0,0,0,0,0,0,0,0,0,0,0,0,0,0,0,0,0,0,0,0,0,0,0,0,BH5,0,0,0,0,0,0,0)';
      PINUSE='POWER';
      NO_LOAD_CHECK='Both';
      NO_IO_CHECK='Both';
      NO_ASSERT_CHECK='TRUE';
      NO_DIR_CHECK='TRUE';
      ALLOW_CONNECT='TRUE';
    'VSS_BH8':
      PIN_NUMBER='(0,0,0,0,0,0,0,0,0,0,0,0,0,0,0,0,0,0,0,0,0,0,0,0,0,0,0,0,0,0,0,0,BH8,0,0,0,0,0,0,0)';
      PINUSE='POWER';
      NO_LOAD_CHECK='Both';
      NO_IO_CHECK='Both';
      NO_ASSERT_CHECK='TRUE';
      NO_DIR_CHECK='TRUE';
      ALLOW_CONNECT='TRUE';
    'VSS_BH10':
      PIN_NUMBER='(0,0,0,0,0,0,0,0,0,0,0,0,0,0,0,0,0,0,0,0,0,0,0,0,0,0,0,0,0,0,0,0,BH10,0,0,0,0,0,0,0)';
      PINUSE='POWER';
      NO_LOAD_CHECK='Both';
      NO_IO_CHECK='Both';
      NO_ASSERT_CHECK='TRUE';
      NO_DIR_CHECK='TRUE';
      ALLOW_CONNECT='TRUE';
    'VSS_BH12':
      PIN_NUMBER='(0,0,0,0,0,0,0,0,0,0,0,0,0,0,0,0,0,0,0,0,0,0,0,0,0,0,0,0,0,0,0,0,BH12,0,0,0,0,0,0,0)';
      PINUSE='POWER';
      NO_LOAD_CHECK='Both';
      NO_IO_CHECK='Both';
      NO_ASSERT_CHECK='TRUE';
      NO_DIR_CHECK='TRUE';
      ALLOW_CONNECT='TRUE';
    'VSS_BH15':
      PIN_NUMBER='(0,0,0,0,0,0,0,0,0,0,0,0,0,0,0,0,0,0,0,0,0,0,0,0,0,0,0,0,0,0,0,0,BH15,0,0,0,0,0,0,0)';
      PINUSE='POWER';
      NO_LOAD_CHECK='Both';
      NO_IO_CHECK='Both';
      NO_ASSERT_CHECK='TRUE';
      NO_DIR_CHECK='TRUE';
      ALLOW_CONNECT='TRUE';
    'VSS_BH17':
      PIN_NUMBER='(0,0,0,0,0,0,0,0,0,0,0,0,0,0,0,0,0,0,0,0,0,0,0,0,0,0,0,0,0,0,0,0,BH17,0,0,0,0,0,0,0)';
      PINUSE='POWER';
      NO_LOAD_CHECK='Both';
      NO_IO_CHECK='Both';
      NO_ASSERT_CHECK='TRUE';
      NO_DIR_CHECK='TRUE';
      ALLOW_CONNECT='TRUE';
    'VSS_BH19':
      PIN_NUMBER='(0,0,0,0,0,0,0,0,0,0,0,0,0,0,0,0,0,0,0,0,0,0,0,0,0,0,0,0,0,0,0,0,BH19,0,0,0,0,0,0,0)';
      PINUSE='POWER';
      NO_LOAD_CHECK='Both';
      NO_IO_CHECK='Both';
      NO_ASSERT_CHECK='TRUE';
      NO_DIR_CHECK='TRUE';
      ALLOW_CONNECT='TRUE';
    'VSS_BH22':
      PIN_NUMBER='(0,0,0,0,0,0,0,0,0,0,0,0,0,0,0,0,0,0,0,0,0,0,0,0,0,0,0,0,0,0,0,0,BH22,0,0,0,0,0,0,0)';
      PINUSE='POWER';
      NO_LOAD_CHECK='Both';
      NO_IO_CHECK='Both';
      NO_ASSERT_CHECK='TRUE';
      NO_DIR_CHECK='TRUE';
      ALLOW_CONNECT='TRUE';
    'VSS_BH24':
      PIN_NUMBER='(0,0,0,0,0,0,0,0,0,0,0,0,0,0,0,0,0,0,0,0,0,0,0,0,0,0,0,0,0,0,0,0,BH24,0,0,0,0,0,0,0)';
      PINUSE='POWER';
      NO_LOAD_CHECK='Both';
      NO_IO_CHECK='Both';
      NO_ASSERT_CHECK='TRUE';
      NO_DIR_CHECK='TRUE';
      ALLOW_CONNECT='TRUE';
    'VSS_BH26':
      PIN_NUMBER='(0,0,0,0,0,0,0,0,0,0,0,0,0,0,0,0,0,0,0,0,0,0,0,0,0,0,0,0,0,0,0,0,BH26,0,0,0,0,0,0,0)';
      PINUSE='POWER';
      NO_LOAD_CHECK='Both';
      NO_IO_CHECK='Both';
      NO_ASSERT_CHECK='TRUE';
      NO_DIR_CHECK='TRUE';
      ALLOW_CONNECT='TRUE';
    'VSS_BH28':
      PIN_NUMBER='(0,0,0,0,0,0,0,0,0,0,0,0,0,0,0,0,0,0,0,0,0,0,0,0,0,0,0,0,0,0,0,0,BH28,0,0,0,0,0,0,0)';
      PINUSE='POWER';
      NO_LOAD_CHECK='Both';
      NO_IO_CHECK='Both';
      NO_ASSERT_CHECK='TRUE';
      NO_DIR_CHECK='TRUE';
      ALLOW_CONNECT='TRUE';
    'VSS_BH49':
      PIN_NUMBER='(0,0,0,0,0,0,0,0,0,0,0,0,0,0,0,0,0,0,0,0,0,0,0,0,0,0,0,0,0,0,0,0,BH49,0,0,0,0,0,0,0)';
      PINUSE='POWER';
      NO_LOAD_CHECK='Both';
      NO_IO_CHECK='Both';
      NO_ASSERT_CHECK='TRUE';
      NO_DIR_CHECK='TRUE';
      ALLOW_CONNECT='TRUE';
    'VSS_BH50':
      PIN_NUMBER='(0,0,0,0,0,0,0,0,0,0,0,0,0,0,0,0,0,0,0,0,0,0,0,0,0,0,0,0,0,0,0,0,BH50,0,0,0,0,0,0,0)';
      PINUSE='POWER';
      NO_LOAD_CHECK='Both';
      NO_IO_CHECK='Both';
      NO_ASSERT_CHECK='TRUE';
      NO_DIR_CHECK='TRUE';
      ALLOW_CONNECT='TRUE';
    'VSS_BH52':
      PIN_NUMBER='(0,0,0,0,0,0,0,0,0,0,0,0,0,0,0,0,0,0,0,0,0,0,0,0,0,0,0,0,0,0,0,0,BH52,0,0,0,0,0,0,0)';
      PINUSE='POWER';
      NO_LOAD_CHECK='Both';
      NO_IO_CHECK='Both';
      NO_ASSERT_CHECK='TRUE';
      NO_DIR_CHECK='TRUE';
      ALLOW_CONNECT='TRUE';
    'VSS_BH54':
      PIN_NUMBER='(0,0,0,0,0,0,0,0,0,0,0,0,0,0,0,0,0,0,0,0,0,0,0,0,0,0,0,0,0,0,0,0,BH54,0,0,0,0,0,0,0)';
      PINUSE='POWER';
      NO_LOAD_CHECK='Both';
      NO_IO_CHECK='Both';
      NO_ASSERT_CHECK='TRUE';
      NO_DIR_CHECK='TRUE';
      ALLOW_CONNECT='TRUE';
    'VSS_BH57':
      PIN_NUMBER='(0,0,0,0,0,0,0,0,0,0,0,0,0,0,0,0,0,0,0,0,0,0,0,0,0,0,0,0,0,0,0,0,BH57,0,0,0,0,0,0,0)';
      PINUSE='POWER';
      NO_LOAD_CHECK='Both';
      NO_IO_CHECK='Both';
      NO_ASSERT_CHECK='TRUE';
      NO_DIR_CHECK='TRUE';
      ALLOW_CONNECT='TRUE';
    'VSS_BH59':
      PIN_NUMBER='(0,0,0,0,0,0,0,0,0,0,0,0,0,0,0,0,0,0,0,0,0,0,0,0,0,0,0,0,0,0,0,0,BH59,0,0,0,0,0,0,0)';
      PINUSE='POWER';
      NO_LOAD_CHECK='Both';
      NO_IO_CHECK='Both';
      NO_ASSERT_CHECK='TRUE';
      NO_DIR_CHECK='TRUE';
      ALLOW_CONNECT='TRUE';
    'VSS_BH61':
      PIN_NUMBER='(0,0,0,0,0,0,0,0,0,0,0,0,0,0,0,0,0,0,0,0,0,0,0,0,0,0,0,0,0,0,0,0,BH61,0,0,0,0,0,0,0)';
      PINUSE='POWER';
      NO_LOAD_CHECK='Both';
      NO_IO_CHECK='Both';
      NO_ASSERT_CHECK='TRUE';
      NO_DIR_CHECK='TRUE';
      ALLOW_CONNECT='TRUE';
    'VSS_BH64':
      PIN_NUMBER='(0,0,0,0,0,0,0,0,0,0,0,0,0,0,0,0,0,0,0,0,0,0,0,0,0,0,0,0,0,0,0,0,BH64,0,0,0,0,0,0,0)';
      PINUSE='POWER';
      NO_LOAD_CHECK='Both';
      NO_IO_CHECK='Both';
      NO_ASSERT_CHECK='TRUE';
      NO_DIR_CHECK='TRUE';
      ALLOW_CONNECT='TRUE';
    'VSS_BH66':
      PIN_NUMBER='(0,0,0,0,0,0,0,0,0,0,0,0,0,0,0,0,0,0,0,0,0,0,0,0,0,0,0,0,0,0,0,0,BH66,0,0,0,0,0,0,0)';
      PINUSE='POWER';
      NO_LOAD_CHECK='Both';
      NO_IO_CHECK='Both';
      NO_ASSERT_CHECK='TRUE';
      NO_DIR_CHECK='TRUE';
      ALLOW_CONNECT='TRUE';
    'VSS_BH68':
      PIN_NUMBER='(0,0,0,0,0,0,0,0,0,0,0,0,0,0,0,0,0,0,0,0,0,0,0,0,0,0,0,0,0,0,0,0,BH68,0,0,0,0,0,0,0)';
      PINUSE='POWER';
      NO_LOAD_CHECK='Both';
      NO_IO_CHECK='Both';
      NO_ASSERT_CHECK='TRUE';
      NO_DIR_CHECK='TRUE';
      ALLOW_CONNECT='TRUE';
    'VSS_BH71':
      PIN_NUMBER='(0,0,0,0,0,0,0,0,0,0,0,0,0,0,0,0,0,0,0,0,0,0,0,0,0,0,0,0,0,0,0,0,BH71,0,0,0,0,0,0,0)';
      PINUSE='POWER';
      NO_LOAD_CHECK='Both';
      NO_IO_CHECK='Both';
      NO_ASSERT_CHECK='TRUE';
      NO_DIR_CHECK='TRUE';
      ALLOW_CONNECT='TRUE';
    'VSS_BH73':
      PIN_NUMBER='(0,0,0,0,0,0,0,0,0,0,0,0,0,0,0,0,0,0,0,0,0,0,0,0,0,0,0,0,0,0,0,0,BH73,0,0,0,0,0,0,0)';
      PINUSE='POWER';
      NO_LOAD_CHECK='Both';
      NO_IO_CHECK='Both';
      NO_ASSERT_CHECK='TRUE';
      NO_DIR_CHECK='TRUE';
      ALLOW_CONNECT='TRUE';
    'VSS_BJ1':
      PIN_NUMBER='(0,0,0,0,0,0,0,0,0,0,0,0,0,0,0,0,0,0,0,0,0,0,0,0,0,0,0,0,0,0,0,0,BJ1,0,0,0,0,0,0,0)';
      PINUSE='POWER';
      NO_LOAD_CHECK='Both';
      NO_IO_CHECK='Both';
      NO_ASSERT_CHECK='TRUE';
      NO_DIR_CHECK='TRUE';
      ALLOW_CONNECT='TRUE';
    'VSS_BJ6':
      PIN_NUMBER='(0,0,0,0,0,0,0,0,0,0,0,0,0,0,0,0,0,0,0,0,0,0,0,0,0,0,0,0,0,0,0,0,BJ6,0,0,0,0,0,0,0)';
      PINUSE='POWER';
      NO_LOAD_CHECK='Both';
      NO_IO_CHECK='Both';
      NO_ASSERT_CHECK='TRUE';
      NO_DIR_CHECK='TRUE';
      ALLOW_CONNECT='TRUE';
    'VSS_BJ8':
      PIN_NUMBER='(0,0,0,0,0,0,0,0,0,0,0,0,0,0,0,0,0,0,0,0,0,0,0,0,0,0,0,0,0,0,0,0,BJ8,0,0,0,0,0,0,0)';
      PINUSE='POWER';
      NO_LOAD_CHECK='Both';
      NO_IO_CHECK='Both';
      NO_ASSERT_CHECK='TRUE';
      NO_DIR_CHECK='TRUE';
      ALLOW_CONNECT='TRUE';
    'VSS_BJ13':
      PIN_NUMBER='(0,0,0,0,0,0,0,0,0,0,0,0,0,0,0,0,0,0,0,0,0,0,0,0,0,0,0,0,0,0,0,0,BJ13,0,0,0,0,0,0,0)';
      PINUSE='POWER';
      NO_LOAD_CHECK='Both';
      NO_IO_CHECK='Both';
      NO_ASSERT_CHECK='TRUE';
      NO_DIR_CHECK='TRUE';
      ALLOW_CONNECT='TRUE';
    'VSS_BJ15':
      PIN_NUMBER='(0,0,0,0,0,0,0,0,0,0,0,0,0,0,0,0,0,0,0,0,0,0,0,0,0,0,0,0,0,0,0,0,BJ15,0,0,0,0,0,0,0)';
      PINUSE='POWER';
      NO_LOAD_CHECK='Both';
      NO_IO_CHECK='Both';
      NO_ASSERT_CHECK='TRUE';
      NO_DIR_CHECK='TRUE';
      ALLOW_CONNECT='TRUE';
    'VSS_BJ20':
      PIN_NUMBER='(0,0,0,0,0,0,0,0,0,0,0,0,0,0,0,0,0,0,0,0,0,0,0,0,0,0,0,0,0,0,0,0,BJ20,0,0,0,0,0,0,0)';
      PINUSE='POWER';
      NO_LOAD_CHECK='Both';
      NO_IO_CHECK='Both';
      NO_ASSERT_CHECK='TRUE';
      NO_DIR_CHECK='TRUE';
      ALLOW_CONNECT='TRUE';
    'VSS_BJ22':
      PIN_NUMBER='(0,0,0,0,0,0,0,0,0,0,0,0,0,0,0,0,0,0,0,0,0,0,0,0,0,0,0,0,0,0,0,0,BJ22,0,0,0,0,0,0,0)';
      PINUSE='POWER';
      NO_LOAD_CHECK='Both';
      NO_IO_CHECK='Both';
      NO_ASSERT_CHECK='TRUE';
      NO_DIR_CHECK='TRUE';
      ALLOW_CONNECT='TRUE';
    'VSS_BJ24':
      PIN_NUMBER='(0,0,0,0,0,0,0,0,0,0,0,0,0,0,0,0,0,0,0,0,0,0,0,0,0,0,0,0,0,0,0,0,BJ24,0,0,0,0,0,0,0)';
      PINUSE='POWER';
      NO_LOAD_CHECK='Both';
      NO_IO_CHECK='Both';
      NO_ASSERT_CHECK='TRUE';
      NO_DIR_CHECK='TRUE';
      ALLOW_CONNECT='TRUE';
    'VSS_BJ26':
      PIN_NUMBER='(0,0,0,0,0,0,0,0,0,0,0,0,0,0,0,0,0,0,0,0,0,0,0,0,0,0,0,0,0,0,0,0,BJ26,0,0,0,0,0,0,0)';
      PINUSE='POWER';
      NO_LOAD_CHECK='Both';
      NO_IO_CHECK='Both';
      NO_ASSERT_CHECK='TRUE';
      NO_DIR_CHECK='TRUE';
      ALLOW_CONNECT='TRUE';
    'VSS_BJ28':
      PIN_NUMBER='(0,0,0,0,0,0,0,0,0,0,0,0,0,0,0,0,0,0,0,0,0,0,0,0,0,0,0,0,0,0,0,0,BJ28,0,0,0,0,0,0,0)';
      PINUSE='POWER';
      NO_LOAD_CHECK='Both';
      NO_IO_CHECK='Both';
      NO_ASSERT_CHECK='TRUE';
      NO_DIR_CHECK='TRUE';
      ALLOW_CONNECT='TRUE';
    'VSS_BJ49':
      PIN_NUMBER='(0,0,0,0,0,0,0,0,0,0,0,0,0,0,0,0,0,0,0,0,0,0,0,0,0,0,0,0,0,0,0,0,BJ49,0,0,0,0,0,0,0)';
      PINUSE='POWER';
      NO_LOAD_CHECK='Both';
      NO_IO_CHECK='Both';
      NO_ASSERT_CHECK='TRUE';
      NO_DIR_CHECK='TRUE';
      ALLOW_CONNECT='TRUE';
    'VSS_BJ51':
      PIN_NUMBER='(0,0,0,0,0,0,0,0,0,0,0,0,0,0,0,0,0,0,0,0,0,0,0,0,0,0,0,0,0,0,0,0,BJ51,0,0,0,0,0,0,0)';
      PINUSE='POWER';
      NO_LOAD_CHECK='Both';
      NO_IO_CHECK='Both';
      NO_ASSERT_CHECK='TRUE';
      NO_DIR_CHECK='TRUE';
      ALLOW_CONNECT='TRUE';
    'VSS_BJ53':
      PIN_NUMBER='(0,0,0,0,0,0,0,0,0,0,0,0,0,0,0,0,0,0,0,0,0,0,0,0,0,0,0,0,0,0,0,0,BJ53,0,0,0,0,0,0,0)';
      PINUSE='POWER';
      NO_LOAD_CHECK='Both';
      NO_IO_CHECK='Both';
      NO_ASSERT_CHECK='TRUE';
      NO_DIR_CHECK='TRUE';
      ALLOW_CONNECT='TRUE';
    'VSS_BJ56':
      PIN_NUMBER='(0,0,0,0,0,0,0,0,0,0,0,0,0,0,0,0,0,0,0,0,0,0,0,0,0,0,0,0,0,0,0,0,BJ56,0,0,0,0,0,0,0)';
      PINUSE='POWER';
      NO_LOAD_CHECK='Both';
      NO_IO_CHECK='Both';
      NO_ASSERT_CHECK='TRUE';
      NO_DIR_CHECK='TRUE';
      ALLOW_CONNECT='TRUE';
    'VSS_BJ61':
      PIN_NUMBER='(0,0,0,0,0,0,0,0,0,0,0,0,0,0,0,0,0,0,0,0,0,0,0,0,0,0,0,0,0,0,0,0,BJ61,0,0,0,0,0,0,0)';
      PINUSE='POWER';
      NO_LOAD_CHECK='Both';
      NO_IO_CHECK='Both';
      NO_ASSERT_CHECK='TRUE';
      NO_DIR_CHECK='TRUE';
      ALLOW_CONNECT='TRUE';
    'VSS_BJ63':
      PIN_NUMBER='(0,0,0,0,0,0,0,0,0,0,0,0,0,0,0,0,0,0,0,0,0,0,0,0,0,0,0,0,0,0,0,0,BJ63,0,0,0,0,0,0,0)';
      PINUSE='POWER';
      NO_LOAD_CHECK='Both';
      NO_IO_CHECK='Both';
      NO_ASSERT_CHECK='TRUE';
      NO_DIR_CHECK='TRUE';
      ALLOW_CONNECT='TRUE';
    'VSS_BJ68':
      PIN_NUMBER='(0,0,0,0,0,0,0,0,0,0,0,0,0,0,0,0,0,0,0,0,0,0,0,0,0,0,0,0,0,0,0,0,BJ68,0,0,0,0,0,0,0)';
      PINUSE='POWER';
      NO_LOAD_CHECK='Both';
      NO_IO_CHECK='Both';
      NO_ASSERT_CHECK='TRUE';
      NO_DIR_CHECK='TRUE';
      ALLOW_CONNECT='TRUE';
    'VSS_BJ70':
      PIN_NUMBER='(0,0,0,0,0,0,0,0,0,0,0,0,0,0,0,0,0,0,0,0,0,0,0,0,0,0,0,0,0,0,0,0,BJ70,0,0,0,0,0,0,0)';
      PINUSE='POWER';
      NO_LOAD_CHECK='Both';
      NO_IO_CHECK='Both';
      NO_ASSERT_CHECK='TRUE';
      NO_DIR_CHECK='TRUE';
      ALLOW_CONNECT='TRUE';
    'VSS_BJ75':
      PIN_NUMBER='(0,0,0,0,0,0,0,0,0,0,0,0,0,0,0,0,0,0,0,0,0,0,0,0,0,0,0,0,0,0,0,0,BJ75,0,0,0,0,0,0,0)';
      PINUSE='POWER';
      NO_LOAD_CHECK='Both';
      NO_IO_CHECK='Both';
      NO_ASSERT_CHECK='TRUE';
      NO_DIR_CHECK='TRUE';
      ALLOW_CONNECT='TRUE';
    'VSS_BK3':
      PIN_NUMBER='(0,0,0,0,0,0,0,0,0,0,0,0,0,0,0,0,0,0,0,0,0,0,0,0,0,0,0,0,0,0,0,0,BK3,0,0,0,0,0,0,0)';
      PINUSE='POWER';
      NO_LOAD_CHECK='Both';
      NO_IO_CHECK='Both';
      NO_ASSERT_CHECK='TRUE';
      NO_DIR_CHECK='TRUE';
      ALLOW_CONNECT='TRUE';
    'VSS_BK5':
      PIN_NUMBER='(0,0,0,0,0,0,0,0,0,0,0,0,0,0,0,0,0,0,0,0,0,0,0,0,0,0,0,0,0,0,0,0,BK5,0,0,0,0,0,0,0)';
      PINUSE='POWER';
      NO_LOAD_CHECK='Both';
      NO_IO_CHECK='Both';
      NO_ASSERT_CHECK='TRUE';
      NO_DIR_CHECK='TRUE';
      ALLOW_CONNECT='TRUE';
    'VSS_BK8':
      PIN_NUMBER='(0,0,0,0,0,0,0,0,0,0,0,0,0,0,0,0,0,0,0,0,0,0,0,0,0,0,0,0,0,0,0,0,BK8,0,0,0,0,0,0,0)';
      PINUSE='POWER';
      NO_LOAD_CHECK='Both';
      NO_IO_CHECK='Both';
      NO_ASSERT_CHECK='TRUE';
      NO_DIR_CHECK='TRUE';
      ALLOW_CONNECT='TRUE';
    'VSS_BK10':
      PIN_NUMBER='(0,0,0,0,0,0,0,0,0,0,0,0,0,0,0,0,0,0,0,0,0,0,0,0,0,0,0,0,0,0,0,0,BK10,0,0,0,0,0,0,0)';
      PINUSE='POWER';
      NO_LOAD_CHECK='Both';
      NO_IO_CHECK='Both';
      NO_ASSERT_CHECK='TRUE';
      NO_DIR_CHECK='TRUE';
      ALLOW_CONNECT='TRUE';
    'VSS_BK12':
      PIN_NUMBER='(0,0,0,0,0,0,0,0,0,0,0,0,0,0,0,0,0,0,0,0,0,0,0,0,0,0,0,0,0,0,0,0,BK12,0,0,0,0,0,0,0)';
      PINUSE='POWER';
      NO_LOAD_CHECK='Both';
      NO_IO_CHECK='Both';
      NO_ASSERT_CHECK='TRUE';
      NO_DIR_CHECK='TRUE';
      ALLOW_CONNECT='TRUE';
    'VSS_BK15':
      PIN_NUMBER='(0,0,0,0,0,0,0,0,0,0,0,0,0,0,0,0,0,0,0,0,0,0,0,0,0,0,0,0,0,0,0,0,BK15,0,0,0,0,0,0,0)';
      PINUSE='POWER';
      NO_LOAD_CHECK='Both';
      NO_IO_CHECK='Both';
      NO_ASSERT_CHECK='TRUE';
      NO_DIR_CHECK='TRUE';
      ALLOW_CONNECT='TRUE';
    'VSS_BK17':
      PIN_NUMBER='(0,0,0,0,0,0,0,0,0,0,0,0,0,0,0,0,0,0,0,0,0,0,0,0,0,0,0,0,0,0,0,0,BK17,0,0,0,0,0,0,0)';
      PINUSE='POWER';
      NO_LOAD_CHECK='Both';
      NO_IO_CHECK='Both';
      NO_ASSERT_CHECK='TRUE';
      NO_DIR_CHECK='TRUE';
      ALLOW_CONNECT='TRUE';
    'VSS_BK19':
      PIN_NUMBER='(0,0,0,0,0,0,0,0,0,0,0,0,0,0,0,0,0,0,0,0,0,0,0,0,0,0,0,0,0,0,0,0,BK19,0,0,0,0,0,0,0)';
      PINUSE='POWER';
      NO_LOAD_CHECK='Both';
      NO_IO_CHECK='Both';
      NO_ASSERT_CHECK='TRUE';
      NO_DIR_CHECK='TRUE';
      ALLOW_CONNECT='TRUE';
    'VSS_BK23':
      PIN_NUMBER='(0,0,0,0,0,0,0,0,0,0,0,0,0,0,0,0,0,0,0,0,0,0,0,0,0,0,0,0,0,0,0,0,BK23,0,0,0,0,0,0,0)';
      PINUSE='POWER';
      NO_LOAD_CHECK='Both';
      NO_IO_CHECK='Both';
      NO_ASSERT_CHECK='TRUE';
      NO_DIR_CHECK='TRUE';
      ALLOW_CONNECT='TRUE';
    'VSS_BK25':
      PIN_NUMBER='(0,0,0,0,0,0,0,0,0,0,0,0,0,0,0,0,0,0,0,0,0,0,0,0,0,0,0,0,0,0,0,0,BK25,0,0,0,0,0,0,0)';
      PINUSE='POWER';
      NO_LOAD_CHECK='Both';
      NO_IO_CHECK='Both';
      NO_ASSERT_CHECK='TRUE';
      NO_DIR_CHECK='TRUE';
      ALLOW_CONNECT='TRUE';
    'VSS_BK27':
      PIN_NUMBER='(0,0,0,0,0,0,0,0,0,0,0,0,0,0,0,0,0,0,0,0,0,0,0,0,0,0,0,0,0,0,0,0,BK27,0,0,0,0,0,0,0)';
      PINUSE='POWER';
      NO_LOAD_CHECK='Both';
      NO_IO_CHECK='Both';
      NO_ASSERT_CHECK='TRUE';
      NO_DIR_CHECK='TRUE';
      ALLOW_CONNECT='TRUE';
    'VSS_BK48':
      PIN_NUMBER='(0,0,0,0,0,0,0,0,0,0,0,0,0,0,0,0,0,0,0,0,0,0,0,0,0,0,0,0,0,0,0,0,BK48,0,0,0,0,0,0,0)';
      PINUSE='POWER';
      NO_LOAD_CHECK='Both';
      NO_IO_CHECK='Both';
      NO_ASSERT_CHECK='TRUE';
      NO_DIR_CHECK='TRUE';
      ALLOW_CONNECT='TRUE';
    'VSS_BK50':
      PIN_NUMBER='(0,0,0,0,0,0,0,0,0,0,0,0,0,0,0,0,0,0,0,0,0,0,0,0,0,0,0,0,0,0,0,0,BK50,0,0,0,0,0,0,0)';
      PINUSE='POWER';
      NO_LOAD_CHECK='Both';
      NO_IO_CHECK='Both';
      NO_ASSERT_CHECK='TRUE';
      NO_DIR_CHECK='TRUE';
      ALLOW_CONNECT='TRUE';
    'VSS_BK52':
      PIN_NUMBER='(0,0,0,0,0,0,0,0,0,0,0,0,0,0,0,0,0,0,0,0,0,0,0,0,0,0,0,0,0,0,0,0,BK52,0,0,0,0,0,0,0)';
      PINUSE='POWER';
      NO_LOAD_CHECK='Both';
      NO_IO_CHECK='Both';
      NO_ASSERT_CHECK='TRUE';
      NO_DIR_CHECK='TRUE';
      ALLOW_CONNECT='TRUE';
    'VSS_BK54':
      PIN_NUMBER='(0,0,0,0,0,0,0,0,0,0,0,0,0,0,0,0,0,0,0,0,0,0,0,0,0,0,0,0,0,0,0,0,BK54,0,0,0,0,0,0,0)';
      PINUSE='POWER';
      NO_LOAD_CHECK='Both';
      NO_IO_CHECK='Both';
      NO_ASSERT_CHECK='TRUE';
      NO_DIR_CHECK='TRUE';
      ALLOW_CONNECT='TRUE';
    'VSS_BK57':
      PIN_NUMBER='(0,0,0,0,0,0,0,0,0,0,0,0,0,0,0,0,0,0,0,0,0,0,0,0,0,0,0,0,0,0,0,0,BK57,0,0,0,0,0,0,0)';
      PINUSE='POWER';
      NO_LOAD_CHECK='Both';
      NO_IO_CHECK='Both';
      NO_ASSERT_CHECK='TRUE';
      NO_DIR_CHECK='TRUE';
      ALLOW_CONNECT='TRUE';
    'VSS_BK59':
      PIN_NUMBER='(0,0,0,0,0,0,0,0,0,0,0,0,0,0,0,0,0,0,0,0,0,0,0,0,0,0,0,0,0,0,0,0,BK59,0,0,0,0,0,0,0)';
      PINUSE='POWER';
      NO_LOAD_CHECK='Both';
      NO_IO_CHECK='Both';
      NO_ASSERT_CHECK='TRUE';
      NO_DIR_CHECK='TRUE';
      ALLOW_CONNECT='TRUE';
    'VSS_BK61':
      PIN_NUMBER='(0,0,0,0,0,0,0,0,0,0,0,0,0,0,0,0,0,0,0,0,0,0,0,0,0,0,0,0,0,0,0,0,BK61,0,0,0,0,0,0,0)';
      PINUSE='POWER';
      NO_LOAD_CHECK='Both';
      NO_IO_CHECK='Both';
      NO_ASSERT_CHECK='TRUE';
      NO_DIR_CHECK='TRUE';
      ALLOW_CONNECT='TRUE';
    'VSS_BK64':
      PIN_NUMBER='(0,0,0,0,0,0,0,0,0,0,0,0,0,0,0,0,0,0,0,0,0,0,0,0,0,0,0,0,0,0,0,0,BK64,0,0,0,0,0,0,0)';
      PINUSE='POWER';
      NO_LOAD_CHECK='Both';
      NO_IO_CHECK='Both';
      NO_ASSERT_CHECK='TRUE';
      NO_DIR_CHECK='TRUE';
      ALLOW_CONNECT='TRUE';
    'VSS_BK66':
      PIN_NUMBER='(0,0,0,0,0,0,0,0,0,0,0,0,0,0,0,0,0,0,0,0,0,0,0,0,0,0,0,0,0,0,0,0,BK66,0,0,0,0,0,0,0)';
      PINUSE='POWER';
      NO_LOAD_CHECK='Both';
      NO_IO_CHECK='Both';
      NO_ASSERT_CHECK='TRUE';
      NO_DIR_CHECK='TRUE';
      ALLOW_CONNECT='TRUE';
    'VSS_BK68':
      PIN_NUMBER='(0,0,0,0,0,0,0,0,0,0,0,0,0,0,0,0,0,0,0,0,0,0,0,0,0,0,0,0,0,0,0,0,BK68,0,0,0,0,0,0,0)';
      PINUSE='POWER';
      NO_LOAD_CHECK='Both';
      NO_IO_CHECK='Both';
      NO_ASSERT_CHECK='TRUE';
      NO_DIR_CHECK='TRUE';
      ALLOW_CONNECT='TRUE';
    'VSS_BK71':
      PIN_NUMBER='(0,0,0,0,0,0,0,0,0,0,0,0,0,0,0,0,0,0,0,0,0,0,0,0,0,0,0,0,0,0,0,0,BK71,0,0,0,0,0,0,0)';
      PINUSE='POWER';
      NO_LOAD_CHECK='Both';
      NO_IO_CHECK='Both';
      NO_ASSERT_CHECK='TRUE';
      NO_DIR_CHECK='TRUE';
      ALLOW_CONNECT='TRUE';
    'VSS_BK73':
      PIN_NUMBER='(0,0,0,0,0,0,0,0,0,0,0,0,0,0,0,0,0,0,0,0,0,0,0,0,0,0,0,0,0,0,0,0,BK73,0,0,0,0,0,0,0)';
      PINUSE='POWER';
      NO_LOAD_CHECK='Both';
      NO_IO_CHECK='Both';
      NO_ASSERT_CHECK='TRUE';
      NO_DIR_CHECK='TRUE';
      ALLOW_CONNECT='TRUE';
    'VSS_BL1':
      PIN_NUMBER='(0,0,0,0,0,0,0,0,0,0,0,0,0,0,0,0,0,0,0,0,0,0,0,0,0,0,0,0,0,0,0,0,BL1,0,0,0,0,0,0,0)';
      PINUSE='POWER';
      NO_LOAD_CHECK='Both';
      NO_IO_CHECK='Both';
      NO_ASSERT_CHECK='TRUE';
      NO_DIR_CHECK='TRUE';
      ALLOW_CONNECT='TRUE';
    'VSS_BL4':
      PIN_NUMBER='(0,0,0,0,0,0,0,0,0,0,0,0,0,0,0,0,0,0,0,0,0,0,0,0,0,0,0,0,0,0,0,0,BL4,0,0,0,0,0,0,0)';
      PINUSE='POWER';
      NO_LOAD_CHECK='Both';
      NO_IO_CHECK='Both';
      NO_ASSERT_CHECK='TRUE';
      NO_DIR_CHECK='TRUE';
      ALLOW_CONNECT='TRUE';
    'VSS_BL6':
      PIN_NUMBER='(0,0,0,0,0,0,0,0,0,0,0,0,0,0,0,0,0,0,0,0,0,0,0,0,0,0,0,0,0,0,0,0,BL6,0,0,0,0,0,0,0)';
      PINUSE='POWER';
      NO_LOAD_CHECK='Both';
      NO_IO_CHECK='Both';
      NO_ASSERT_CHECK='TRUE';
      NO_DIR_CHECK='TRUE';
      ALLOW_CONNECT='TRUE';
    'VSS_BL8':
      PIN_NUMBER='(0,0,0,0,0,0,0,0,0,0,0,0,0,0,0,0,0,0,0,0,0,0,0,0,0,0,0,0,0,0,0,0,BL8,0,0,0,0,0,0,0)';
      PINUSE='POWER';
      NO_LOAD_CHECK='Both';
      NO_IO_CHECK='Both';
      NO_ASSERT_CHECK='TRUE';
      NO_DIR_CHECK='TRUE';
      ALLOW_CONNECT='TRUE';
    'VSS_BL11':
      PIN_NUMBER='(0,0,0,0,0,0,0,0,0,0,0,0,0,0,0,0,0,0,0,0,0,0,0,0,0,0,0,0,0,0,0,0,BL11,0,0,0,0,0,0,0)';
      PINUSE='POWER';
      NO_LOAD_CHECK='Both';
      NO_IO_CHECK='Both';
      NO_ASSERT_CHECK='TRUE';
      NO_DIR_CHECK='TRUE';
      ALLOW_CONNECT='TRUE';
    'VSS_BL13':
      PIN_NUMBER='(0,0,0,0,0,0,0,0,0,0,0,0,0,0,0,0,0,0,0,0,0,0,0,0,0,0,0,0,0,0,0,0,BL13,0,0,0,0,0,0,0)';
      PINUSE='POWER';
      NO_LOAD_CHECK='Both';
      NO_IO_CHECK='Both';
      NO_ASSERT_CHECK='TRUE';
      NO_DIR_CHECK='TRUE';
      ALLOW_CONNECT='TRUE';
    'VSS_BL15':
      PIN_NUMBER='(0,0,0,0,0,0,0,0,0,0,0,0,0,0,0,0,0,0,0,0,0,0,0,0,0,0,0,0,0,0,0,0,BL15,0,0,0,0,0,0,0)';
      PINUSE='POWER';
      NO_LOAD_CHECK='Both';
      NO_IO_CHECK='Both';
      NO_ASSERT_CHECK='TRUE';
      NO_DIR_CHECK='TRUE';
      ALLOW_CONNECT='TRUE';
    'VSS_BL18':
      PIN_NUMBER='(0,0,0,0,0,0,0,0,0,0,0,0,0,0,0,0,0,0,0,0,0,0,0,0,0,0,0,0,0,0,0,0,BL18,0,0,0,0,0,0,0)';
      PINUSE='POWER';
      NO_LOAD_CHECK='Both';
      NO_IO_CHECK='Both';
      NO_ASSERT_CHECK='TRUE';
      NO_DIR_CHECK='TRUE';
      ALLOW_CONNECT='TRUE';
    'VSS_BL20':
      PIN_NUMBER='(0,0,0,0,0,0,0,0,0,0,0,0,0,0,0,0,0,0,0,0,0,0,0,0,0,0,0,0,0,0,0,0,BL20,0,0,0,0,0,0,0)';
      PINUSE='POWER';
      NO_LOAD_CHECK='Both';
      NO_IO_CHECK='Both';
      NO_ASSERT_CHECK='TRUE';
      NO_DIR_CHECK='TRUE';
      ALLOW_CONNECT='TRUE';
    'VSS_BL22':
      PIN_NUMBER='(0,0,0,0,0,0,0,0,0,0,0,0,0,0,0,0,0,0,0,0,0,0,0,0,0,0,0,0,0,0,0,0,BL22,0,0,0,0,0,0,0)';
      PINUSE='POWER';
      NO_LOAD_CHECK='Both';
      NO_IO_CHECK='Both';
      NO_ASSERT_CHECK='TRUE';
      NO_DIR_CHECK='TRUE';
      ALLOW_CONNECT='TRUE';
    'VSS_BL24':
      PIN_NUMBER='(0,0,0,0,0,0,0,0,0,0,0,0,0,0,0,0,0,0,0,0,0,0,0,0,0,0,0,0,0,0,0,0,BL24,0,0,0,0,0,0,0)';
      PINUSE='POWER';
      NO_LOAD_CHECK='Both';
      NO_IO_CHECK='Both';
      NO_ASSERT_CHECK='TRUE';
      NO_DIR_CHECK='TRUE';
      ALLOW_CONNECT='TRUE';
    'VSS_BV37':
      PIN_NUMBER='(0,0,0,0,0,0,0,0,0,0,0,0,0,0,0,0,0,0,0,0,0,0,0,0,0,0,0,0,0,0,0,0,0,BV37,0,0,0,0,0,0)';
      PINUSE='POWER';
      NO_LOAD_CHECK='Both';
      NO_IO_CHECK='Both';
      NO_ASSERT_CHECK='TRUE';
      NO_DIR_CHECK='TRUE';
      ALLOW_CONNECT='TRUE';
    'VSS_BL26':
      PIN_NUMBER='(0,0,0,0,0,0,0,0,0,0,0,0,0,0,0,0,0,0,0,0,0,0,0,0,0,0,0,0,0,0,0,0,0,BL26,0,0,0,0,0,0)';
      PINUSE='POWER';
      NO_LOAD_CHECK='Both';
      NO_IO_CHECK='Both';
      NO_ASSERT_CHECK='TRUE';
      NO_DIR_CHECK='TRUE';
      ALLOW_CONNECT='TRUE';
    'VSS_BL28':
      PIN_NUMBER='(0,0,0,0,0,0,0,0,0,0,0,0,0,0,0,0,0,0,0,0,0,0,0,0,0,0,0,0,0,0,0,0,0,BL28,0,0,0,0,0,0)';
      PINUSE='POWER';
      NO_LOAD_CHECK='Both';
      NO_IO_CHECK='Both';
      NO_ASSERT_CHECK='TRUE';
      NO_DIR_CHECK='TRUE';
      ALLOW_CONNECT='TRUE';
    'VSS_BL49':
      PIN_NUMBER='(0,0,0,0,0,0,0,0,0,0,0,0,0,0,0,0,0,0,0,0,0,0,0,0,0,0,0,0,0,0,0,0,0,BL49,0,0,0,0,0,0)';
      PINUSE='POWER';
      NO_LOAD_CHECK='Both';
      NO_IO_CHECK='Both';
      NO_ASSERT_CHECK='TRUE';
      NO_DIR_CHECK='TRUE';
      ALLOW_CONNECT='TRUE';
    'VSS_BL51':
      PIN_NUMBER='(0,0,0,0,0,0,0,0,0,0,0,0,0,0,0,0,0,0,0,0,0,0,0,0,0,0,0,0,0,0,0,0,0,BL51,0,0,0,0,0,0)';
      PINUSE='POWER';
      NO_LOAD_CHECK='Both';
      NO_IO_CHECK='Both';
      NO_ASSERT_CHECK='TRUE';
      NO_DIR_CHECK='TRUE';
      ALLOW_CONNECT='TRUE';
    'VSS_BL53':
      PIN_NUMBER='(0,0,0,0,0,0,0,0,0,0,0,0,0,0,0,0,0,0,0,0,0,0,0,0,0,0,0,0,0,0,0,0,0,BL53,0,0,0,0,0,0)';
      PINUSE='POWER';
      NO_LOAD_CHECK='Both';
      NO_IO_CHECK='Both';
      NO_ASSERT_CHECK='TRUE';
      NO_DIR_CHECK='TRUE';
      ALLOW_CONNECT='TRUE';
    'VSS_BL56':
      PIN_NUMBER='(0,0,0,0,0,0,0,0,0,0,0,0,0,0,0,0,0,0,0,0,0,0,0,0,0,0,0,0,0,0,0,0,0,BL56,0,0,0,0,0,0)';
      PINUSE='POWER';
      NO_LOAD_CHECK='Both';
      NO_IO_CHECK='Both';
      NO_ASSERT_CHECK='TRUE';
      NO_DIR_CHECK='TRUE';
      ALLOW_CONNECT='TRUE';
    'VSS_BL58':
      PIN_NUMBER='(0,0,0,0,0,0,0,0,0,0,0,0,0,0,0,0,0,0,0,0,0,0,0,0,0,0,0,0,0,0,0,0,0,BL58,0,0,0,0,0,0)';
      PINUSE='POWER';
      NO_LOAD_CHECK='Both';
      NO_IO_CHECK='Both';
      NO_ASSERT_CHECK='TRUE';
      NO_DIR_CHECK='TRUE';
      ALLOW_CONNECT='TRUE';
    'VSS_BL61':
      PIN_NUMBER='(0,0,0,0,0,0,0,0,0,0,0,0,0,0,0,0,0,0,0,0,0,0,0,0,0,0,0,0,0,0,0,0,0,BL61,0,0,0,0,0,0)';
      PINUSE='POWER';
      NO_LOAD_CHECK='Both';
      NO_IO_CHECK='Both';
      NO_ASSERT_CHECK='TRUE';
      NO_DIR_CHECK='TRUE';
      ALLOW_CONNECT='TRUE';
    'VSS_BL63':
      PIN_NUMBER='(0,0,0,0,0,0,0,0,0,0,0,0,0,0,0,0,0,0,0,0,0,0,0,0,0,0,0,0,0,0,0,0,0,BL63,0,0,0,0,0,0)';
      PINUSE='POWER';
      NO_LOAD_CHECK='Both';
      NO_IO_CHECK='Both';
      NO_ASSERT_CHECK='TRUE';
      NO_DIR_CHECK='TRUE';
      ALLOW_CONNECT='TRUE';
    'VSS_BL65':
      PIN_NUMBER='(0,0,0,0,0,0,0,0,0,0,0,0,0,0,0,0,0,0,0,0,0,0,0,0,0,0,0,0,0,0,0,0,0,BL65,0,0,0,0,0,0)';
      PINUSE='POWER';
      NO_LOAD_CHECK='Both';
      NO_IO_CHECK='Both';
      NO_ASSERT_CHECK='TRUE';
      NO_DIR_CHECK='TRUE';
      ALLOW_CONNECT='TRUE';
    'VSS_BL68':
      PIN_NUMBER='(0,0,0,0,0,0,0,0,0,0,0,0,0,0,0,0,0,0,0,0,0,0,0,0,0,0,0,0,0,0,0,0,0,BL68,0,0,0,0,0,0)';
      PINUSE='POWER';
      NO_LOAD_CHECK='Both';
      NO_IO_CHECK='Both';
      NO_ASSERT_CHECK='TRUE';
      NO_DIR_CHECK='TRUE';
      ALLOW_CONNECT='TRUE';
    'VSS_BL70':
      PIN_NUMBER='(0,0,0,0,0,0,0,0,0,0,0,0,0,0,0,0,0,0,0,0,0,0,0,0,0,0,0,0,0,0,0,0,0,BL70,0,0,0,0,0,0)';
      PINUSE='POWER';
      NO_LOAD_CHECK='Both';
      NO_IO_CHECK='Both';
      NO_ASSERT_CHECK='TRUE';
      NO_DIR_CHECK='TRUE';
      ALLOW_CONNECT='TRUE';
    'VSS_BL72':
      PIN_NUMBER='(0,0,0,0,0,0,0,0,0,0,0,0,0,0,0,0,0,0,0,0,0,0,0,0,0,0,0,0,0,0,0,0,0,BL72,0,0,0,0,0,0)';
      PINUSE='POWER';
      NO_LOAD_CHECK='Both';
      NO_IO_CHECK='Both';
      NO_ASSERT_CHECK='TRUE';
      NO_DIR_CHECK='TRUE';
      ALLOW_CONNECT='TRUE';
    'VSS_BL75':
      PIN_NUMBER='(0,0,0,0,0,0,0,0,0,0,0,0,0,0,0,0,0,0,0,0,0,0,0,0,0,0,0,0,0,0,0,0,0,BL75,0,0,0,0,0,0)';
      PINUSE='POWER';
      NO_LOAD_CHECK='Both';
      NO_IO_CHECK='Both';
      NO_ASSERT_CHECK='TRUE';
      NO_DIR_CHECK='TRUE';
      ALLOW_CONNECT='TRUE';
    'VSS_BM3':
      PIN_NUMBER='(0,0,0,0,0,0,0,0,0,0,0,0,0,0,0,0,0,0,0,0,0,0,0,0,0,0,0,0,0,0,0,0,0,BM3,0,0,0,0,0,0)';
      PINUSE='POWER';
      NO_LOAD_CHECK='Both';
      NO_IO_CHECK='Both';
      NO_ASSERT_CHECK='TRUE';
      NO_DIR_CHECK='TRUE';
      ALLOW_CONNECT='TRUE';
    'VSS_BM8':
      PIN_NUMBER='(0,0,0,0,0,0,0,0,0,0,0,0,0,0,0,0,0,0,0,0,0,0,0,0,0,0,0,0,0,0,0,0,0,BM8,0,0,0,0,0,0)';
      PINUSE='POWER';
      NO_LOAD_CHECK='Both';
      NO_IO_CHECK='Both';
      NO_ASSERT_CHECK='TRUE';
      NO_DIR_CHECK='TRUE';
      ALLOW_CONNECT='TRUE';
    'VSS_BM10':
      PIN_NUMBER='(0,0,0,0,0,0,0,0,0,0,0,0,0,0,0,0,0,0,0,0,0,0,0,0,0,0,0,0,0,0,0,0,0,BM10,0,0,0,0,0,0)';
      PINUSE='POWER';
      NO_LOAD_CHECK='Both';
      NO_IO_CHECK='Both';
      NO_ASSERT_CHECK='TRUE';
      NO_DIR_CHECK='TRUE';
      ALLOW_CONNECT='TRUE';
    'VSS_BM15':
      PIN_NUMBER='(0,0,0,0,0,0,0,0,0,0,0,0,0,0,0,0,0,0,0,0,0,0,0,0,0,0,0,0,0,0,0,0,0,BM15,0,0,0,0,0,0)';
      PINUSE='POWER';
      NO_LOAD_CHECK='Both';
      NO_IO_CHECK='Both';
      NO_ASSERT_CHECK='TRUE';
      NO_DIR_CHECK='TRUE';
      ALLOW_CONNECT='TRUE';
    'VSS_BM17':
      PIN_NUMBER='(0,0,0,0,0,0,0,0,0,0,0,0,0,0,0,0,0,0,0,0,0,0,0,0,0,0,0,0,0,0,0,0,0,BM17,0,0,0,0,0,0)';
      PINUSE='POWER';
      NO_LOAD_CHECK='Both';
      NO_IO_CHECK='Both';
      NO_ASSERT_CHECK='TRUE';
      NO_DIR_CHECK='TRUE';
      ALLOW_CONNECT='TRUE';
    'VSS_BM23':
      PIN_NUMBER='(0,0,0,0,0,0,0,0,0,0,0,0,0,0,0,0,0,0,0,0,0,0,0,0,0,0,0,0,0,0,0,0,0,BM23,0,0,0,0,0,0)';
      PINUSE='POWER';
      NO_LOAD_CHECK='Both';
      NO_IO_CHECK='Both';
      NO_ASSERT_CHECK='TRUE';
      NO_DIR_CHECK='TRUE';
      ALLOW_CONNECT='TRUE';
    'VSS_BM25':
      PIN_NUMBER='(0,0,0,0,0,0,0,0,0,0,0,0,0,0,0,0,0,0,0,0,0,0,0,0,0,0,0,0,0,0,0,0,0,BM25,0,0,0,0,0,0)';
      PINUSE='POWER';
      NO_LOAD_CHECK='Both';
      NO_IO_CHECK='Both';
      NO_ASSERT_CHECK='TRUE';
      NO_DIR_CHECK='TRUE';
      ALLOW_CONNECT='TRUE';
    'VSS_BM27':
      PIN_NUMBER='(0,0,0,0,0,0,0,0,0,0,0,0,0,0,0,0,0,0,0,0,0,0,0,0,0,0,0,0,0,0,0,0,0,BM27,0,0,0,0,0,0)';
      PINUSE='POWER';
      NO_LOAD_CHECK='Both';
      NO_IO_CHECK='Both';
      NO_ASSERT_CHECK='TRUE';
      NO_DIR_CHECK='TRUE';
      ALLOW_CONNECT='TRUE';
    'VSS_BM29':
      PIN_NUMBER='(0,0,0,0,0,0,0,0,0,0,0,0,0,0,0,0,0,0,0,0,0,0,0,0,0,0,0,0,0,0,0,0,0,BM29,0,0,0,0,0,0)';
      PINUSE='POWER';
      NO_LOAD_CHECK='Both';
      NO_IO_CHECK='Both';
      NO_ASSERT_CHECK='TRUE';
      NO_DIR_CHECK='TRUE';
      ALLOW_CONNECT='TRUE';
    'VSS_BM31':
      PIN_NUMBER='(0,0,0,0,0,0,0,0,0,0,0,0,0,0,0,0,0,0,0,0,0,0,0,0,0,0,0,0,0,0,0,0,0,BM31,0,0,0,0,0,0)';
      PINUSE='POWER';
      NO_LOAD_CHECK='Both';
      NO_IO_CHECK='Both';
      NO_ASSERT_CHECK='TRUE';
      NO_DIR_CHECK='TRUE';
      ALLOW_CONNECT='TRUE';
    'VSS_BM33':
      PIN_NUMBER='(0,0,0,0,0,0,0,0,0,0,0,0,0,0,0,0,0,0,0,0,0,0,0,0,0,0,0,0,0,0,0,0,0,BM33,0,0,0,0,0,0)';
      PINUSE='POWER';
      NO_LOAD_CHECK='Both';
      NO_IO_CHECK='Both';
      NO_ASSERT_CHECK='TRUE';
      NO_DIR_CHECK='TRUE';
      ALLOW_CONNECT='TRUE';
    'VSS_BM35':
      PIN_NUMBER='(0,0,0,0,0,0,0,0,0,0,0,0,0,0,0,0,0,0,0,0,0,0,0,0,0,0,0,0,0,0,0,0,0,BM35,0,0,0,0,0,0)';
      PINUSE='POWER';
      NO_LOAD_CHECK='Both';
      NO_IO_CHECK='Both';
      NO_ASSERT_CHECK='TRUE';
      NO_DIR_CHECK='TRUE';
      ALLOW_CONNECT='TRUE';
    'VSS_BM37':
      PIN_NUMBER='(0,0,0,0,0,0,0,0,0,0,0,0,0,0,0,0,0,0,0,0,0,0,0,0,0,0,0,0,0,0,0,0,0,BM37,0,0,0,0,0,0)';
      PINUSE='POWER';
      NO_LOAD_CHECK='Both';
      NO_IO_CHECK='Both';
      NO_ASSERT_CHECK='TRUE';
      NO_DIR_CHECK='TRUE';
      ALLOW_CONNECT='TRUE';
    'VSS_BM40':
      PIN_NUMBER='(0,0,0,0,0,0,0,0,0,0,0,0,0,0,0,0,0,0,0,0,0,0,0,0,0,0,0,0,0,0,0,0,0,BM40,0,0,0,0,0,0)';
      PINUSE='POWER';
      NO_LOAD_CHECK='Both';
      NO_IO_CHECK='Both';
      NO_ASSERT_CHECK='TRUE';
      NO_DIR_CHECK='TRUE';
      ALLOW_CONNECT='TRUE';
    'VSS_BM42':
      PIN_NUMBER='(0,0,0,0,0,0,0,0,0,0,0,0,0,0,0,0,0,0,0,0,0,0,0,0,0,0,0,0,0,0,0,0,0,BM42,0,0,0,0,0,0)';
      PINUSE='POWER';
      NO_LOAD_CHECK='Both';
      NO_IO_CHECK='Both';
      NO_ASSERT_CHECK='TRUE';
      NO_DIR_CHECK='TRUE';
      ALLOW_CONNECT='TRUE';
    'VSS_BM44':
      PIN_NUMBER='(0,0,0,0,0,0,0,0,0,0,0,0,0,0,0,0,0,0,0,0,0,0,0,0,0,0,0,0,0,0,0,0,0,BM44,0,0,0,0,0,0)';
      PINUSE='POWER';
      NO_LOAD_CHECK='Both';
      NO_IO_CHECK='Both';
      NO_ASSERT_CHECK='TRUE';
      NO_DIR_CHECK='TRUE';
      ALLOW_CONNECT='TRUE';
    'VSS_BM46':
      PIN_NUMBER='(0,0,0,0,0,0,0,0,0,0,0,0,0,0,0,0,0,0,0,0,0,0,0,0,0,0,0,0,0,0,0,0,0,BM46,0,0,0,0,0,0)';
      PINUSE='POWER';
      NO_LOAD_CHECK='Both';
      NO_IO_CHECK='Both';
      NO_ASSERT_CHECK='TRUE';
      NO_DIR_CHECK='TRUE';
      ALLOW_CONNECT='TRUE';
    'VSS_BM48':
      PIN_NUMBER='(0,0,0,0,0,0,0,0,0,0,0,0,0,0,0,0,0,0,0,0,0,0,0,0,0,0,0,0,0,0,0,0,0,BM48,0,0,0,0,0,0)';
      PINUSE='POWER';
      NO_LOAD_CHECK='Both';
      NO_IO_CHECK='Both';
      NO_ASSERT_CHECK='TRUE';
      NO_DIR_CHECK='TRUE';
      ALLOW_CONNECT='TRUE';
    'VSS_BM50':
      PIN_NUMBER='(0,0,0,0,0,0,0,0,0,0,0,0,0,0,0,0,0,0,0,0,0,0,0,0,0,0,0,0,0,0,0,0,0,BM50,0,0,0,0,0,0)';
      PINUSE='POWER';
      NO_LOAD_CHECK='Both';
      NO_IO_CHECK='Both';
      NO_ASSERT_CHECK='TRUE';
      NO_DIR_CHECK='TRUE';
      ALLOW_CONNECT='TRUE';
    'VSS_BM52':
      PIN_NUMBER='(0,0,0,0,0,0,0,0,0,0,0,0,0,0,0,0,0,0,0,0,0,0,0,0,0,0,0,0,0,0,0,0,0,BM52,0,0,0,0,0,0)';
      PINUSE='POWER';
      NO_LOAD_CHECK='Both';
      NO_IO_CHECK='Both';
      NO_ASSERT_CHECK='TRUE';
      NO_DIR_CHECK='TRUE';
      ALLOW_CONNECT='TRUE';
    'VSS_BM54':
      PIN_NUMBER='(0,0,0,0,0,0,0,0,0,0,0,0,0,0,0,0,0,0,0,0,0,0,0,0,0,0,0,0,0,0,0,0,0,BM54,0,0,0,0,0,0)';
      PINUSE='POWER';
      NO_LOAD_CHECK='Both';
      NO_IO_CHECK='Both';
      NO_ASSERT_CHECK='TRUE';
      NO_DIR_CHECK='TRUE';
      ALLOW_CONNECT='TRUE';
    'VSS_BM59':
      PIN_NUMBER='(0,0,0,0,0,0,0,0,0,0,0,0,0,0,0,0,0,0,0,0,0,0,0,0,0,0,0,0,0,0,0,0,0,BM59,0,0,0,0,0,0)';
      PINUSE='POWER';
      NO_LOAD_CHECK='Both';
      NO_IO_CHECK='Both';
      NO_ASSERT_CHECK='TRUE';
      NO_DIR_CHECK='TRUE';
      ALLOW_CONNECT='TRUE';
    'VSS_BM61':
      PIN_NUMBER='(0,0,0,0,0,0,0,0,0,0,0,0,0,0,0,0,0,0,0,0,0,0,0,0,0,0,0,0,0,0,0,0,0,BM61,0,0,0,0,0,0)';
      PINUSE='POWER';
      NO_LOAD_CHECK='Both';
      NO_IO_CHECK='Both';
      NO_ASSERT_CHECK='TRUE';
      NO_DIR_CHECK='TRUE';
      ALLOW_CONNECT='TRUE';
    'VSS_BM66':
      PIN_NUMBER='(0,0,0,0,0,0,0,0,0,0,0,0,0,0,0,0,0,0,0,0,0,0,0,0,0,0,0,0,0,0,0,0,0,BM66,0,0,0,0,0,0)';
      PINUSE='POWER';
      NO_LOAD_CHECK='Both';
      NO_IO_CHECK='Both';
      NO_ASSERT_CHECK='TRUE';
      NO_DIR_CHECK='TRUE';
      ALLOW_CONNECT='TRUE';
    'VSS_BM68':
      PIN_NUMBER='(0,0,0,0,0,0,0,0,0,0,0,0,0,0,0,0,0,0,0,0,0,0,0,0,0,0,0,0,0,0,0,0,0,BM68,0,0,0,0,0,0)';
      PINUSE='POWER';
      NO_LOAD_CHECK='Both';
      NO_IO_CHECK='Both';
      NO_ASSERT_CHECK='TRUE';
      NO_DIR_CHECK='TRUE';
      ALLOW_CONNECT='TRUE';
    'VSS_BM73':
      PIN_NUMBER='(0,0,0,0,0,0,0,0,0,0,0,0,0,0,0,0,0,0,0,0,0,0,0,0,0,0,0,0,0,0,0,0,0,BM73,0,0,0,0,0,0)';
      PINUSE='POWER';
      NO_LOAD_CHECK='Both';
      NO_IO_CHECK='Both';
      NO_ASSERT_CHECK='TRUE';
      NO_DIR_CHECK='TRUE';
      ALLOW_CONNECT='TRUE';
    'VSS_BN1':
      PIN_NUMBER='(0,0,0,0,0,0,0,0,0,0,0,0,0,0,0,0,0,0,0,0,0,0,0,0,0,0,0,0,0,0,0,0,0,BN1,0,0,0,0,0,0)';
      PINUSE='POWER';
      NO_LOAD_CHECK='Both';
      NO_IO_CHECK='Both';
      NO_ASSERT_CHECK='TRUE';
      NO_DIR_CHECK='TRUE';
      ALLOW_CONNECT='TRUE';
    'VSS_BN4':
      PIN_NUMBER='(0,0,0,0,0,0,0,0,0,0,0,0,0,0,0,0,0,0,0,0,0,0,0,0,0,0,0,0,0,0,0,0,0,BN4,0,0,0,0,0,0)';
      PINUSE='POWER';
      NO_LOAD_CHECK='Both';
      NO_IO_CHECK='Both';
      NO_ASSERT_CHECK='TRUE';
      NO_DIR_CHECK='TRUE';
      ALLOW_CONNECT='TRUE';
    'VSS_BN6':
      PIN_NUMBER='(0,0,0,0,0,0,0,0,0,0,0,0,0,0,0,0,0,0,0,0,0,0,0,0,0,0,0,0,0,0,0,0,0,BN6,0,0,0,0,0,0)';
      PINUSE='POWER';
      NO_LOAD_CHECK='Both';
      NO_IO_CHECK='Both';
      NO_ASSERT_CHECK='TRUE';
      NO_DIR_CHECK='TRUE';
      ALLOW_CONNECT='TRUE';
    'VSS_BN8':
      PIN_NUMBER='(0,0,0,0,0,0,0,0,0,0,0,0,0,0,0,0,0,0,0,0,0,0,0,0,0,0,0,0,0,0,0,0,0,BN8,0,0,0,0,0,0)';
      PINUSE='POWER';
      NO_LOAD_CHECK='Both';
      NO_IO_CHECK='Both';
      NO_ASSERT_CHECK='TRUE';
      NO_DIR_CHECK='TRUE';
      ALLOW_CONNECT='TRUE';
    'VSS_BN11':
      PIN_NUMBER='(0,0,0,0,0,0,0,0,0,0,0,0,0,0,0,0,0,0,0,0,0,0,0,0,0,0,0,0,0,0,0,0,0,BN11,0,0,0,0,0,0)';
      PINUSE='POWER';
      NO_LOAD_CHECK='Both';
      NO_IO_CHECK='Both';
      NO_ASSERT_CHECK='TRUE';
      NO_DIR_CHECK='TRUE';
      ALLOW_CONNECT='TRUE';
    'VSS_BN13':
      PIN_NUMBER='(0,0,0,0,0,0,0,0,0,0,0,0,0,0,0,0,0,0,0,0,0,0,0,0,0,0,0,0,0,0,0,0,0,BN13,0,0,0,0,0,0)';
      PINUSE='POWER';
      NO_LOAD_CHECK='Both';
      NO_IO_CHECK='Both';
      NO_ASSERT_CHECK='TRUE';
      NO_DIR_CHECK='TRUE';
      ALLOW_CONNECT='TRUE';
    'VSS_BN15':
      PIN_NUMBER='(0,0,0,0,0,0,0,0,0,0,0,0,0,0,0,0,0,0,0,0,0,0,0,0,0,0,0,0,0,0,0,0,0,BN15,0,0,0,0,0,0)';
      PINUSE='POWER';
      NO_LOAD_CHECK='Both';
      NO_IO_CHECK='Both';
      NO_ASSERT_CHECK='TRUE';
      NO_DIR_CHECK='TRUE';
      ALLOW_CONNECT='TRUE';
    'VSS_BN18':
      PIN_NUMBER='(0,0,0,0,0,0,0,0,0,0,0,0,0,0,0,0,0,0,0,0,0,0,0,0,0,0,0,0,0,0,0,0,0,BN18,0,0,0,0,0,0)';
      PINUSE='POWER';
      NO_LOAD_CHECK='Both';
      NO_IO_CHECK='Both';
      NO_ASSERT_CHECK='TRUE';
      NO_DIR_CHECK='TRUE';
      ALLOW_CONNECT='TRUE';
    'VSS_BN20':
      PIN_NUMBER='(0,0,0,0,0,0,0,0,0,0,0,0,0,0,0,0,0,0,0,0,0,0,0,0,0,0,0,0,0,0,0,0,0,BN20,0,0,0,0,0,0)';
      PINUSE='POWER';
      NO_LOAD_CHECK='Both';
      NO_IO_CHECK='Both';
      NO_ASSERT_CHECK='TRUE';
      NO_DIR_CHECK='TRUE';
      ALLOW_CONNECT='TRUE';
    'VSS_BN22':
      PIN_NUMBER='(0,0,0,0,0,0,0,0,0,0,0,0,0,0,0,0,0,0,0,0,0,0,0,0,0,0,0,0,0,0,0,0,0,BN22,0,0,0,0,0,0)';
      PINUSE='POWER';
      NO_LOAD_CHECK='Both';
      NO_IO_CHECK='Both';
      NO_ASSERT_CHECK='TRUE';
      NO_DIR_CHECK='TRUE';
      ALLOW_CONNECT='TRUE';
    'VSS_BN24':
      PIN_NUMBER='(0,0,0,0,0,0,0,0,0,0,0,0,0,0,0,0,0,0,0,0,0,0,0,0,0,0,0,0,0,0,0,0,0,BN24,0,0,0,0,0,0)';
      PINUSE='POWER';
      NO_LOAD_CHECK='Both';
      NO_IO_CHECK='Both';
      NO_ASSERT_CHECK='TRUE';
      NO_DIR_CHECK='TRUE';
      ALLOW_CONNECT='TRUE';
    'VSS_BN26':
      PIN_NUMBER='(0,0,0,0,0,0,0,0,0,0,0,0,0,0,0,0,0,0,0,0,0,0,0,0,0,0,0,0,0,0,0,0,0,BN26,0,0,0,0,0,0)';
      PINUSE='POWER';
      NO_LOAD_CHECK='Both';
      NO_IO_CHECK='Both';
      NO_ASSERT_CHECK='TRUE';
      NO_DIR_CHECK='TRUE';
      ALLOW_CONNECT='TRUE';
    'VSS_BN28':
      PIN_NUMBER='(0,0,0,0,0,0,0,0,0,0,0,0,0,0,0,0,0,0,0,0,0,0,0,0,0,0,0,0,0,0,0,0,0,BN28,0,0,0,0,0,0)';
      PINUSE='POWER';
      NO_LOAD_CHECK='Both';
      NO_IO_CHECK='Both';
      NO_ASSERT_CHECK='TRUE';
      NO_DIR_CHECK='TRUE';
      ALLOW_CONNECT='TRUE';
    'VSS_BN30':
      PIN_NUMBER='(0,0,0,0,0,0,0,0,0,0,0,0,0,0,0,0,0,0,0,0,0,0,0,0,0,0,0,0,0,0,0,0,0,BN30,0,0,0,0,0,0)';
      PINUSE='POWER';
      NO_LOAD_CHECK='Both';
      NO_IO_CHECK='Both';
      NO_ASSERT_CHECK='TRUE';
      NO_DIR_CHECK='TRUE';
      ALLOW_CONNECT='TRUE';
    'VSS_BN32':
      PIN_NUMBER='(0,0,0,0,0,0,0,0,0,0,0,0,0,0,0,0,0,0,0,0,0,0,0,0,0,0,0,0,0,0,0,0,0,BN32,0,0,0,0,0,0)';
      PINUSE='POWER';
      NO_LOAD_CHECK='Both';
      NO_IO_CHECK='Both';
      NO_ASSERT_CHECK='TRUE';
      NO_DIR_CHECK='TRUE';
      ALLOW_CONNECT='TRUE';
    'VSS_BN34':
      PIN_NUMBER='(0,0,0,0,0,0,0,0,0,0,0,0,0,0,0,0,0,0,0,0,0,0,0,0,0,0,0,0,0,0,0,0,0,BN34,0,0,0,0,0,0)';
      PINUSE='POWER';
      NO_LOAD_CHECK='Both';
      NO_IO_CHECK='Both';
      NO_ASSERT_CHECK='TRUE';
      NO_DIR_CHECK='TRUE';
      ALLOW_CONNECT='TRUE';
    'VSS_BN36':
      PIN_NUMBER='(0,0,0,0,0,0,0,0,0,0,0,0,0,0,0,0,0,0,0,0,0,0,0,0,0,0,0,0,0,0,0,0,0,BN36,0,0,0,0,0,0)';
      PINUSE='POWER';
      NO_LOAD_CHECK='Both';
      NO_IO_CHECK='Both';
      NO_ASSERT_CHECK='TRUE';
      NO_DIR_CHECK='TRUE';
      ALLOW_CONNECT='TRUE';
    'VSS_BN41':
      PIN_NUMBER='(0,0,0,0,0,0,0,0,0,0,0,0,0,0,0,0,0,0,0,0,0,0,0,0,0,0,0,0,0,0,0,0,0,BN41,0,0,0,0,0,0)';
      PINUSE='POWER';
      NO_LOAD_CHECK='Both';
      NO_IO_CHECK='Both';
      NO_ASSERT_CHECK='TRUE';
      NO_DIR_CHECK='TRUE';
      ALLOW_CONNECT='TRUE';
    'VSS_BN43':
      PIN_NUMBER='(0,0,0,0,0,0,0,0,0,0,0,0,0,0,0,0,0,0,0,0,0,0,0,0,0,0,0,0,0,0,0,0,0,BN43,0,0,0,0,0,0)';
      PINUSE='POWER';
      NO_LOAD_CHECK='Both';
      NO_IO_CHECK='Both';
      NO_ASSERT_CHECK='TRUE';
      NO_DIR_CHECK='TRUE';
      ALLOW_CONNECT='TRUE';
    'VSS_BN45':
      PIN_NUMBER='(0,0,0,0,0,0,0,0,0,0,0,0,0,0,0,0,0,0,0,0,0,0,0,0,0,0,0,0,0,0,0,0,0,BN45,0,0,0,0,0,0)';
      PINUSE='POWER';
      NO_LOAD_CHECK='Both';
      NO_IO_CHECK='Both';
      NO_ASSERT_CHECK='TRUE';
      NO_DIR_CHECK='TRUE';
      ALLOW_CONNECT='TRUE';
    'VSS_BN47':
      PIN_NUMBER='(0,0,0,0,0,0,0,0,0,0,0,0,0,0,0,0,0,0,0,0,0,0,0,0,0,0,0,0,0,0,0,0,0,BN47,0,0,0,0,0,0)';
      PINUSE='POWER';
      NO_LOAD_CHECK='Both';
      NO_IO_CHECK='Both';
      NO_ASSERT_CHECK='TRUE';
      NO_DIR_CHECK='TRUE';
      ALLOW_CONNECT='TRUE';
    'VSS_BN49':
      PIN_NUMBER='(0,0,0,0,0,0,0,0,0,0,0,0,0,0,0,0,0,0,0,0,0,0,0,0,0,0,0,0,0,0,0,0,0,BN49,0,0,0,0,0,0)';
      PINUSE='POWER';
      NO_LOAD_CHECK='Both';
      NO_IO_CHECK='Both';
      NO_ASSERT_CHECK='TRUE';
      NO_DIR_CHECK='TRUE';
      ALLOW_CONNECT='TRUE';
    'VSS_BN51':
      PIN_NUMBER='(0,0,0,0,0,0,0,0,0,0,0,0,0,0,0,0,0,0,0,0,0,0,0,0,0,0,0,0,0,0,0,0,0,BN51,0,0,0,0,0,0)';
      PINUSE='POWER';
      NO_LOAD_CHECK='Both';
      NO_IO_CHECK='Both';
      NO_ASSERT_CHECK='TRUE';
      NO_DIR_CHECK='TRUE';
      ALLOW_CONNECT='TRUE';
    'VSS_BN53':
      PIN_NUMBER='(0,0,0,0,0,0,0,0,0,0,0,0,0,0,0,0,0,0,0,0,0,0,0,0,0,0,0,0,0,0,0,0,0,BN53,0,0,0,0,0,0)';
      PINUSE='POWER';
      NO_LOAD_CHECK='Both';
      NO_IO_CHECK='Both';
      NO_ASSERT_CHECK='TRUE';
      NO_DIR_CHECK='TRUE';
      ALLOW_CONNECT='TRUE';
    'VSS_BN56':
      PIN_NUMBER='(0,0,0,0,0,0,0,0,0,0,0,0,0,0,0,0,0,0,0,0,0,0,0,0,0,0,0,0,0,0,0,0,0,BN56,0,0,0,0,0,0)';
      PINUSE='POWER';
      NO_LOAD_CHECK='Both';
      NO_IO_CHECK='Both';
      NO_ASSERT_CHECK='TRUE';
      NO_DIR_CHECK='TRUE';
      ALLOW_CONNECT='TRUE';
    'VSS_BN58':
      PIN_NUMBER='(0,0,0,0,0,0,0,0,0,0,0,0,0,0,0,0,0,0,0,0,0,0,0,0,0,0,0,0,0,0,0,0,0,BN58,0,0,0,0,0,0)';
      PINUSE='POWER';
      NO_LOAD_CHECK='Both';
      NO_IO_CHECK='Both';
      NO_ASSERT_CHECK='TRUE';
      NO_DIR_CHECK='TRUE';
      ALLOW_CONNECT='TRUE';
    'VSS_BN61':
      PIN_NUMBER='(0,0,0,0,0,0,0,0,0,0,0,0,0,0,0,0,0,0,0,0,0,0,0,0,0,0,0,0,0,0,0,0,0,BN61,0,0,0,0,0,0)';
      PINUSE='POWER';
      NO_LOAD_CHECK='Both';
      NO_IO_CHECK='Both';
      NO_ASSERT_CHECK='TRUE';
      NO_DIR_CHECK='TRUE';
      ALLOW_CONNECT='TRUE';
    'VSS_BN63':
      PIN_NUMBER='(0,0,0,0,0,0,0,0,0,0,0,0,0,0,0,0,0,0,0,0,0,0,0,0,0,0,0,0,0,0,0,0,0,BN63,0,0,0,0,0,0)';
      PINUSE='POWER';
      NO_LOAD_CHECK='Both';
      NO_IO_CHECK='Both';
      NO_ASSERT_CHECK='TRUE';
      NO_DIR_CHECK='TRUE';
      ALLOW_CONNECT='TRUE';
    'VSS_BN65':
      PIN_NUMBER='(0,0,0,0,0,0,0,0,0,0,0,0,0,0,0,0,0,0,0,0,0,0,0,0,0,0,0,0,0,0,0,0,0,BN65,0,0,0,0,0,0)';
      PINUSE='POWER';
      NO_LOAD_CHECK='Both';
      NO_IO_CHECK='Both';
      NO_ASSERT_CHECK='TRUE';
      NO_DIR_CHECK='TRUE';
      ALLOW_CONNECT='TRUE';
    'VSS_BN68':
      PIN_NUMBER='(0,0,0,0,0,0,0,0,0,0,0,0,0,0,0,0,0,0,0,0,0,0,0,0,0,0,0,0,0,0,0,0,0,BN68,0,0,0,0,0,0)';
      PINUSE='POWER';
      NO_LOAD_CHECK='Both';
      NO_IO_CHECK='Both';
      NO_ASSERT_CHECK='TRUE';
      NO_DIR_CHECK='TRUE';
      ALLOW_CONNECT='TRUE';
    'VSS_BN70':
      PIN_NUMBER='(0,0,0,0,0,0,0,0,0,0,0,0,0,0,0,0,0,0,0,0,0,0,0,0,0,0,0,0,0,0,0,0,0,BN70,0,0,0,0,0,0)';
      PINUSE='POWER';
      NO_LOAD_CHECK='Both';
      NO_IO_CHECK='Both';
      NO_ASSERT_CHECK='TRUE';
      NO_DIR_CHECK='TRUE';
      ALLOW_CONNECT='TRUE';
    'VSS_BN72':
      PIN_NUMBER='(0,0,0,0,0,0,0,0,0,0,0,0,0,0,0,0,0,0,0,0,0,0,0,0,0,0,0,0,0,0,0,0,0,BN72,0,0,0,0,0,0)';
      PINUSE='POWER';
      NO_LOAD_CHECK='Both';
      NO_IO_CHECK='Both';
      NO_ASSERT_CHECK='TRUE';
      NO_DIR_CHECK='TRUE';
      ALLOW_CONNECT='TRUE';
    'VSS_BN75':
      PIN_NUMBER='(0,0,0,0,0,0,0,0,0,0,0,0,0,0,0,0,0,0,0,0,0,0,0,0,0,0,0,0,0,0,0,0,0,BN75,0,0,0,0,0,0)';
      PINUSE='POWER';
      NO_LOAD_CHECK='Both';
      NO_IO_CHECK='Both';
      NO_ASSERT_CHECK='TRUE';
      NO_DIR_CHECK='TRUE';
      ALLOW_CONNECT='TRUE';
    'VSS_BP3':
      PIN_NUMBER='(0,0,0,0,0,0,0,0,0,0,0,0,0,0,0,0,0,0,0,0,0,0,0,0,0,0,0,0,0,0,0,0,0,BP3,0,0,0,0,0,0)';
      PINUSE='POWER';
      NO_LOAD_CHECK='Both';
      NO_IO_CHECK='Both';
      NO_ASSERT_CHECK='TRUE';
      NO_DIR_CHECK='TRUE';
      ALLOW_CONNECT='TRUE';
    'VSS_BP5':
      PIN_NUMBER='(0,0,0,0,0,0,0,0,0,0,0,0,0,0,0,0,0,0,0,0,0,0,0,0,0,0,0,0,0,0,0,0,0,BP5,0,0,0,0,0,0)';
      PINUSE='POWER';
      NO_LOAD_CHECK='Both';
      NO_IO_CHECK='Both';
      NO_ASSERT_CHECK='TRUE';
      NO_DIR_CHECK='TRUE';
      ALLOW_CONNECT='TRUE';
    'VSS_BP8':
      PIN_NUMBER='(0,0,0,0,0,0,0,0,0,0,0,0,0,0,0,0,0,0,0,0,0,0,0,0,0,0,0,0,0,0,0,0,0,BP8,0,0,0,0,0,0)';
      PINUSE='POWER';
      NO_LOAD_CHECK='Both';
      NO_IO_CHECK='Both';
      NO_ASSERT_CHECK='TRUE';
      NO_DIR_CHECK='TRUE';
      ALLOW_CONNECT='TRUE';
    'VSS_BP10':
      PIN_NUMBER='(0,0,0,0,0,0,0,0,0,0,0,0,0,0,0,0,0,0,0,0,0,0,0,0,0,0,0,0,0,0,0,0,0,BP10,0,0,0,0,0,0)';
      PINUSE='POWER';
      NO_LOAD_CHECK='Both';
      NO_IO_CHECK='Both';
      NO_ASSERT_CHECK='TRUE';
      NO_DIR_CHECK='TRUE';
      ALLOW_CONNECT='TRUE';
    'VSS_BP12':
      PIN_NUMBER='(0,0,0,0,0,0,0,0,0,0,0,0,0,0,0,0,0,0,0,0,0,0,0,0,0,0,0,0,0,0,0,0,0,BP12,0,0,0,0,0,0)';
      PINUSE='POWER';
      NO_LOAD_CHECK='Both';
      NO_IO_CHECK='Both';
      NO_ASSERT_CHECK='TRUE';
      NO_DIR_CHECK='TRUE';
      ALLOW_CONNECT='TRUE';
    'VSS_BP15':
      PIN_NUMBER='(0,0,0,0,0,0,0,0,0,0,0,0,0,0,0,0,0,0,0,0,0,0,0,0,0,0,0,0,0,0,0,0,0,BP15,0,0,0,0,0,0)';
      PINUSE='POWER';
      NO_LOAD_CHECK='Both';
      NO_IO_CHECK='Both';
      NO_ASSERT_CHECK='TRUE';
      NO_DIR_CHECK='TRUE';
      ALLOW_CONNECT='TRUE';
    'VSS_BP17':
      PIN_NUMBER='(0,0,0,0,0,0,0,0,0,0,0,0,0,0,0,0,0,0,0,0,0,0,0,0,0,0,0,0,0,0,0,0,0,BP17,0,0,0,0,0,0)';
      PINUSE='POWER';
      NO_LOAD_CHECK='Both';
      NO_IO_CHECK='Both';
      NO_ASSERT_CHECK='TRUE';
      NO_DIR_CHECK='TRUE';
      ALLOW_CONNECT='TRUE';
    'VSS_BP19':
      PIN_NUMBER='(0,0,0,0,0,0,0,0,0,0,0,0,0,0,0,0,0,0,0,0,0,0,0,0,0,0,0,0,0,0,0,0,0,BP19,0,0,0,0,0,0)';
      PINUSE='POWER';
      NO_LOAD_CHECK='Both';
      NO_IO_CHECK='Both';
      NO_ASSERT_CHECK='TRUE';
      NO_DIR_CHECK='TRUE';
      ALLOW_CONNECT='TRUE';
    'VSS_BP23':
      PIN_NUMBER='(0,0,0,0,0,0,0,0,0,0,0,0,0,0,0,0,0,0,0,0,0,0,0,0,0,0,0,0,0,0,0,0,0,BP23,0,0,0,0,0,0)';
      PINUSE='POWER';
      NO_LOAD_CHECK='Both';
      NO_IO_CHECK='Both';
      NO_ASSERT_CHECK='TRUE';
      NO_DIR_CHECK='TRUE';
      ALLOW_CONNECT='TRUE';
    'VSS_BP25':
      PIN_NUMBER='(0,0,0,0,0,0,0,0,0,0,0,0,0,0,0,0,0,0,0,0,0,0,0,0,0,0,0,0,0,0,0,0,0,BP25,0,0,0,0,0,0)';
      PINUSE='POWER';
      NO_LOAD_CHECK='Both';
      NO_IO_CHECK='Both';
      NO_ASSERT_CHECK='TRUE';
      NO_DIR_CHECK='TRUE';
      ALLOW_CONNECT='TRUE';
    'VSS_BP27':
      PIN_NUMBER='(0,0,0,0,0,0,0,0,0,0,0,0,0,0,0,0,0,0,0,0,0,0,0,0,0,0,0,0,0,0,0,0,0,BP27,0,0,0,0,0,0)';
      PINUSE='POWER';
      NO_LOAD_CHECK='Both';
      NO_IO_CHECK='Both';
      NO_ASSERT_CHECK='TRUE';
      NO_DIR_CHECK='TRUE';
      ALLOW_CONNECT='TRUE';
    'VSS_BP29':
      PIN_NUMBER='(0,0,0,0,0,0,0,0,0,0,0,0,0,0,0,0,0,0,0,0,0,0,0,0,0,0,0,0,0,0,0,0,0,BP29,0,0,0,0,0,0)';
      PINUSE='POWER';
      NO_LOAD_CHECK='Both';
      NO_IO_CHECK='Both';
      NO_ASSERT_CHECK='TRUE';
      NO_DIR_CHECK='TRUE';
      ALLOW_CONNECT='TRUE';
    'VSS_BP31':
      PIN_NUMBER='(0,0,0,0,0,0,0,0,0,0,0,0,0,0,0,0,0,0,0,0,0,0,0,0,0,0,0,0,0,0,0,0,0,BP31,0,0,0,0,0,0)';
      PINUSE='POWER';
      NO_LOAD_CHECK='Both';
      NO_IO_CHECK='Both';
      NO_ASSERT_CHECK='TRUE';
      NO_DIR_CHECK='TRUE';
      ALLOW_CONNECT='TRUE';
    'VSS_BP33':
      PIN_NUMBER='(0,0,0,0,0,0,0,0,0,0,0,0,0,0,0,0,0,0,0,0,0,0,0,0,0,0,0,0,0,0,0,0,0,BP33,0,0,0,0,0,0)';
      PINUSE='POWER';
      NO_LOAD_CHECK='Both';
      NO_IO_CHECK='Both';
      NO_ASSERT_CHECK='TRUE';
      NO_DIR_CHECK='TRUE';
      ALLOW_CONNECT='TRUE';
    'VSS_BP35':
      PIN_NUMBER='(0,0,0,0,0,0,0,0,0,0,0,0,0,0,0,0,0,0,0,0,0,0,0,0,0,0,0,0,0,0,0,0,0,BP35,0,0,0,0,0,0)';
      PINUSE='POWER';
      NO_LOAD_CHECK='Both';
      NO_IO_CHECK='Both';
      NO_ASSERT_CHECK='TRUE';
      NO_DIR_CHECK='TRUE';
      ALLOW_CONNECT='TRUE';
    'VSS_BP37':
      PIN_NUMBER='(0,0,0,0,0,0,0,0,0,0,0,0,0,0,0,0,0,0,0,0,0,0,0,0,0,0,0,0,0,0,0,0,0,BP37,0,0,0,0,0,0)';
      PINUSE='POWER';
      NO_LOAD_CHECK='Both';
      NO_IO_CHECK='Both';
      NO_ASSERT_CHECK='TRUE';
      NO_DIR_CHECK='TRUE';
      ALLOW_CONNECT='TRUE';
    'VSS_BP40':
      PIN_NUMBER='(0,0,0,0,0,0,0,0,0,0,0,0,0,0,0,0,0,0,0,0,0,0,0,0,0,0,0,0,0,0,0,0,0,BP40,0,0,0,0,0,0)';
      PINUSE='POWER';
      NO_LOAD_CHECK='Both';
      NO_IO_CHECK='Both';
      NO_ASSERT_CHECK='TRUE';
      NO_DIR_CHECK='TRUE';
      ALLOW_CONNECT='TRUE';
    'VSS_BP42':
      PIN_NUMBER='(0,0,0,0,0,0,0,0,0,0,0,0,0,0,0,0,0,0,0,0,0,0,0,0,0,0,0,0,0,0,0,0,0,BP42,0,0,0,0,0,0)';
      PINUSE='POWER';
      NO_LOAD_CHECK='Both';
      NO_IO_CHECK='Both';
      NO_ASSERT_CHECK='TRUE';
      NO_DIR_CHECK='TRUE';
      ALLOW_CONNECT='TRUE';
    'VSS_BP44':
      PIN_NUMBER='(0,0,0,0,0,0,0,0,0,0,0,0,0,0,0,0,0,0,0,0,0,0,0,0,0,0,0,0,0,0,0,0,0,BP44,0,0,0,0,0,0)';
      PINUSE='POWER';
      NO_LOAD_CHECK='Both';
      NO_IO_CHECK='Both';
      NO_ASSERT_CHECK='TRUE';
      NO_DIR_CHECK='TRUE';
      ALLOW_CONNECT='TRUE';
    'VSS_BP46':
      PIN_NUMBER='(0,0,0,0,0,0,0,0,0,0,0,0,0,0,0,0,0,0,0,0,0,0,0,0,0,0,0,0,0,0,0,0,0,BP46,0,0,0,0,0,0)';
      PINUSE='POWER';
      NO_LOAD_CHECK='Both';
      NO_IO_CHECK='Both';
      NO_ASSERT_CHECK='TRUE';
      NO_DIR_CHECK='TRUE';
      ALLOW_CONNECT='TRUE';
    'VSS_BP48':
      PIN_NUMBER='(0,0,0,0,0,0,0,0,0,0,0,0,0,0,0,0,0,0,0,0,0,0,0,0,0,0,0,0,0,0,0,0,0,BP48,0,0,0,0,0,0)';
      PINUSE='POWER';
      NO_LOAD_CHECK='Both';
      NO_IO_CHECK='Both';
      NO_ASSERT_CHECK='TRUE';
      NO_DIR_CHECK='TRUE';
      ALLOW_CONNECT='TRUE';
    'VSS_BP50':
      PIN_NUMBER='(0,0,0,0,0,0,0,0,0,0,0,0,0,0,0,0,0,0,0,0,0,0,0,0,0,0,0,0,0,0,0,0,0,BP50,0,0,0,0,0,0)';
      PINUSE='POWER';
      NO_LOAD_CHECK='Both';
      NO_IO_CHECK='Both';
      NO_ASSERT_CHECK='TRUE';
      NO_DIR_CHECK='TRUE';
      ALLOW_CONNECT='TRUE';
    'VSS_BP52':
      PIN_NUMBER='(0,0,0,0,0,0,0,0,0,0,0,0,0,0,0,0,0,0,0,0,0,0,0,0,0,0,0,0,0,0,0,0,0,BP52,0,0,0,0,0,0)';
      PINUSE='POWER';
      NO_LOAD_CHECK='Both';
      NO_IO_CHECK='Both';
      NO_ASSERT_CHECK='TRUE';
      NO_DIR_CHECK='TRUE';
      ALLOW_CONNECT='TRUE';
    'VSS_BP54':
      PIN_NUMBER='(0,0,0,0,0,0,0,0,0,0,0,0,0,0,0,0,0,0,0,0,0,0,0,0,0,0,0,0,0,0,0,0,0,BP54,0,0,0,0,0,0)';
      PINUSE='POWER';
      NO_LOAD_CHECK='Both';
      NO_IO_CHECK='Both';
      NO_ASSERT_CHECK='TRUE';
      NO_DIR_CHECK='TRUE';
      ALLOW_CONNECT='TRUE';
    'VSS_BP57':
      PIN_NUMBER='(0,0,0,0,0,0,0,0,0,0,0,0,0,0,0,0,0,0,0,0,0,0,0,0,0,0,0,0,0,0,0,0,0,BP57,0,0,0,0,0,0)';
      PINUSE='POWER';
      NO_LOAD_CHECK='Both';
      NO_IO_CHECK='Both';
      NO_ASSERT_CHECK='TRUE';
      NO_DIR_CHECK='TRUE';
      ALLOW_CONNECT='TRUE';
    'VSS_BP59':
      PIN_NUMBER='(0,0,0,0,0,0,0,0,0,0,0,0,0,0,0,0,0,0,0,0,0,0,0,0,0,0,0,0,0,0,0,0,0,BP59,0,0,0,0,0,0)';
      PINUSE='POWER';
      NO_LOAD_CHECK='Both';
      NO_IO_CHECK='Both';
      NO_ASSERT_CHECK='TRUE';
      NO_DIR_CHECK='TRUE';
      ALLOW_CONNECT='TRUE';
    'VSS_BP61':
      PIN_NUMBER='(0,0,0,0,0,0,0,0,0,0,0,0,0,0,0,0,0,0,0,0,0,0,0,0,0,0,0,0,0,0,0,0,0,BP61,0,0,0,0,0,0)';
      PINUSE='POWER';
      NO_LOAD_CHECK='Both';
      NO_IO_CHECK='Both';
      NO_ASSERT_CHECK='TRUE';
      NO_DIR_CHECK='TRUE';
      ALLOW_CONNECT='TRUE';
    'VSS_BP64':
      PIN_NUMBER='(0,0,0,0,0,0,0,0,0,0,0,0,0,0,0,0,0,0,0,0,0,0,0,0,0,0,0,0,0,0,0,0,0,BP64,0,0,0,0,0,0)';
      PINUSE='POWER';
      NO_LOAD_CHECK='Both';
      NO_IO_CHECK='Both';
      NO_ASSERT_CHECK='TRUE';
      NO_DIR_CHECK='TRUE';
      ALLOW_CONNECT='TRUE';
    'VSS_BP66':
      PIN_NUMBER='(0,0,0,0,0,0,0,0,0,0,0,0,0,0,0,0,0,0,0,0,0,0,0,0,0,0,0,0,0,0,0,0,0,BP66,0,0,0,0,0,0)';
      PINUSE='POWER';
      NO_LOAD_CHECK='Both';
      NO_IO_CHECK='Both';
      NO_ASSERT_CHECK='TRUE';
      NO_DIR_CHECK='TRUE';
      ALLOW_CONNECT='TRUE';
    'VSS_BP68':
      PIN_NUMBER='(0,0,0,0,0,0,0,0,0,0,0,0,0,0,0,0,0,0,0,0,0,0,0,0,0,0,0,0,0,0,0,0,0,BP68,0,0,0,0,0,0)';
      PINUSE='POWER';
      NO_LOAD_CHECK='Both';
      NO_IO_CHECK='Both';
      NO_ASSERT_CHECK='TRUE';
      NO_DIR_CHECK='TRUE';
      ALLOW_CONNECT='TRUE';
    'VSS_BP71':
      PIN_NUMBER='(0,0,0,0,0,0,0,0,0,0,0,0,0,0,0,0,0,0,0,0,0,0,0,0,0,0,0,0,0,0,0,0,0,BP71,0,0,0,0,0,0)';
      PINUSE='POWER';
      NO_LOAD_CHECK='Both';
      NO_IO_CHECK='Both';
      NO_ASSERT_CHECK='TRUE';
      NO_DIR_CHECK='TRUE';
      ALLOW_CONNECT='TRUE';
    'VSS_BP73':
      PIN_NUMBER='(0,0,0,0,0,0,0,0,0,0,0,0,0,0,0,0,0,0,0,0,0,0,0,0,0,0,0,0,0,0,0,0,0,BP73,0,0,0,0,0,0)';
      PINUSE='POWER';
      NO_LOAD_CHECK='Both';
      NO_IO_CHECK='Both';
      NO_ASSERT_CHECK='TRUE';
      NO_DIR_CHECK='TRUE';
      ALLOW_CONNECT='TRUE';
    'VSS_BR1':
      PIN_NUMBER='(0,0,0,0,0,0,0,0,0,0,0,0,0,0,0,0,0,0,0,0,0,0,0,0,0,0,0,0,0,0,0,0,0,BR1,0,0,0,0,0,0)';
      PINUSE='POWER';
      NO_LOAD_CHECK='Both';
      NO_IO_CHECK='Both';
      NO_ASSERT_CHECK='TRUE';
      NO_DIR_CHECK='TRUE';
      ALLOW_CONNECT='TRUE';
    'VSS_BR3':
      PIN_NUMBER='(0,0,0,0,0,0,0,0,0,0,0,0,0,0,0,0,0,0,0,0,0,0,0,0,0,0,0,0,0,0,0,0,0,BR3,0,0,0,0,0,0)';
      PINUSE='POWER';
      NO_LOAD_CHECK='Both';
      NO_IO_CHECK='Both';
      NO_ASSERT_CHECK='TRUE';
      NO_DIR_CHECK='TRUE';
      ALLOW_CONNECT='TRUE';
    'VSS_BR6':
      PIN_NUMBER='(0,0,0,0,0,0,0,0,0,0,0,0,0,0,0,0,0,0,0,0,0,0,0,0,0,0,0,0,0,0,0,0,0,BR6,0,0,0,0,0,0)';
      PINUSE='POWER';
      NO_LOAD_CHECK='Both';
      NO_IO_CHECK='Both';
      NO_ASSERT_CHECK='TRUE';
      NO_DIR_CHECK='TRUE';
      ALLOW_CONNECT='TRUE';
    'VSS_BR7':
      PIN_NUMBER='(0,0,0,0,0,0,0,0,0,0,0,0,0,0,0,0,0,0,0,0,0,0,0,0,0,0,0,0,0,0,0,0,0,BR7,0,0,0,0,0,0)';
      PINUSE='POWER';
      NO_LOAD_CHECK='Both';
      NO_IO_CHECK='Both';
      NO_ASSERT_CHECK='TRUE';
      NO_DIR_CHECK='TRUE';
      ALLOW_CONNECT='TRUE';
    'VSS_BR8':
      PIN_NUMBER='(0,0,0,0,0,0,0,0,0,0,0,0,0,0,0,0,0,0,0,0,0,0,0,0,0,0,0,0,0,0,0,0,0,BR8,0,0,0,0,0,0)';
      PINUSE='POWER';
      NO_LOAD_CHECK='Both';
      NO_IO_CHECK='Both';
      NO_ASSERT_CHECK='TRUE';
      NO_DIR_CHECK='TRUE';
      ALLOW_CONNECT='TRUE';
    'VSS_BR10':
      PIN_NUMBER='(0,0,0,0,0,0,0,0,0,0,0,0,0,0,0,0,0,0,0,0,0,0,0,0,0,0,0,0,0,0,0,0,0,BR10,0,0,0,0,0,0)';
      PINUSE='POWER';
      NO_LOAD_CHECK='Both';
      NO_IO_CHECK='Both';
      NO_ASSERT_CHECK='TRUE';
      NO_DIR_CHECK='TRUE';
      ALLOW_CONNECT='TRUE';
    'VSS_BR13':
      PIN_NUMBER='(0,0,0,0,0,0,0,0,0,0,0,0,0,0,0,0,0,0,0,0,0,0,0,0,0,0,0,0,0,0,0,0,0,BR13,0,0,0,0,0,0)';
      PINUSE='POWER';
      NO_LOAD_CHECK='Both';
      NO_IO_CHECK='Both';
      NO_ASSERT_CHECK='TRUE';
      NO_DIR_CHECK='TRUE';
      ALLOW_CONNECT='TRUE';
    'VSS_BR14':
      PIN_NUMBER='(0,0,0,0,0,0,0,0,0,0,0,0,0,0,0,0,0,0,0,0,0,0,0,0,0,0,0,0,0,0,0,0,0,BR14,0,0,0,0,0,0)';
      PINUSE='POWER';
      NO_LOAD_CHECK='Both';
      NO_IO_CHECK='Both';
      NO_ASSERT_CHECK='TRUE';
      NO_DIR_CHECK='TRUE';
      ALLOW_CONNECT='TRUE';
    'VSS_BR15':
      PIN_NUMBER='(0,0,0,0,0,0,0,0,0,0,0,0,0,0,0,0,0,0,0,0,0,0,0,0,0,0,0,0,0,0,0,0,0,BR15,0,0,0,0,0,0)';
      PINUSE='POWER';
      NO_LOAD_CHECK='Both';
      NO_IO_CHECK='Both';
      NO_ASSERT_CHECK='TRUE';
      NO_DIR_CHECK='TRUE';
      ALLOW_CONNECT='TRUE';
    'VSS_BR17':
      PIN_NUMBER='(0,0,0,0,0,0,0,0,0,0,0,0,0,0,0,0,0,0,0,0,0,0,0,0,0,0,0,0,0,0,0,0,0,BR17,0,0,0,0,0,0)';
      PINUSE='POWER';
      NO_LOAD_CHECK='Both';
      NO_IO_CHECK='Both';
      NO_ASSERT_CHECK='TRUE';
      NO_DIR_CHECK='TRUE';
      ALLOW_CONNECT='TRUE';
    'VSS_BR20':
      PIN_NUMBER='(0,0,0,0,0,0,0,0,0,0,0,0,0,0,0,0,0,0,0,0,0,0,0,0,0,0,0,0,0,0,0,0,0,BR20,0,0,0,0,0,0)';
      PINUSE='POWER';
      NO_LOAD_CHECK='Both';
      NO_IO_CHECK='Both';
      NO_ASSERT_CHECK='TRUE';
      NO_DIR_CHECK='TRUE';
      ALLOW_CONNECT='TRUE';
    'VSS_BR21':
      PIN_NUMBER='(0,0,0,0,0,0,0,0,0,0,0,0,0,0,0,0,0,0,0,0,0,0,0,0,0,0,0,0,0,0,0,0,0,BR21,0,0,0,0,0,0)';
      PINUSE='POWER';
      NO_LOAD_CHECK='Both';
      NO_IO_CHECK='Both';
      NO_ASSERT_CHECK='TRUE';
      NO_DIR_CHECK='TRUE';
      ALLOW_CONNECT='TRUE';
    'VSS_BR22':
      PIN_NUMBER='(0,0,0,0,0,0,0,0,0,0,0,0,0,0,0,0,0,0,0,0,0,0,0,0,0,0,0,0,0,0,0,0,0,BR22,0,0,0,0,0,0)';
      PINUSE='POWER';
      NO_LOAD_CHECK='Both';
      NO_IO_CHECK='Both';
      NO_ASSERT_CHECK='TRUE';
      NO_DIR_CHECK='TRUE';
      ALLOW_CONNECT='TRUE';
    'VSS_BR24':
      PIN_NUMBER='(0,0,0,0,0,0,0,0,0,0,0,0,0,0,0,0,0,0,0,0,0,0,0,0,0,0,0,0,0,0,0,0,0,BR24,0,0,0,0,0,0)';
      PINUSE='POWER';
      NO_LOAD_CHECK='Both';
      NO_IO_CHECK='Both';
      NO_ASSERT_CHECK='TRUE';
      NO_DIR_CHECK='TRUE';
      ALLOW_CONNECT='TRUE';
    'VSS_BR26':
      PIN_NUMBER='(0,0,0,0,0,0,0,0,0,0,0,0,0,0,0,0,0,0,0,0,0,0,0,0,0,0,0,0,0,0,0,0,0,BR26,0,0,0,0,0,0)';
      PINUSE='POWER';
      NO_LOAD_CHECK='Both';
      NO_IO_CHECK='Both';
      NO_ASSERT_CHECK='TRUE';
      NO_DIR_CHECK='TRUE';
      ALLOW_CONNECT='TRUE';
    'VSS_BR28':
      PIN_NUMBER='(0,0,0,0,0,0,0,0,0,0,0,0,0,0,0,0,0,0,0,0,0,0,0,0,0,0,0,0,0,0,0,0,0,BR28,0,0,0,0,0,0)';
      PINUSE='POWER';
      NO_LOAD_CHECK='Both';
      NO_IO_CHECK='Both';
      NO_ASSERT_CHECK='TRUE';
      NO_DIR_CHECK='TRUE';
      ALLOW_CONNECT='TRUE';
    'VSS_BR30':
      PIN_NUMBER='(0,0,0,0,0,0,0,0,0,0,0,0,0,0,0,0,0,0,0,0,0,0,0,0,0,0,0,0,0,0,0,0,0,BR30,0,0,0,0,0,0)';
      PINUSE='POWER';
      NO_LOAD_CHECK='Both';
      NO_IO_CHECK='Both';
      NO_ASSERT_CHECK='TRUE';
      NO_DIR_CHECK='TRUE';
      ALLOW_CONNECT='TRUE';
    'VSS_BR32':
      PIN_NUMBER='(0,0,0,0,0,0,0,0,0,0,0,0,0,0,0,0,0,0,0,0,0,0,0,0,0,0,0,0,0,0,0,0,0,BR32,0,0,0,0,0,0)';
      PINUSE='POWER';
      NO_LOAD_CHECK='Both';
      NO_IO_CHECK='Both';
      NO_ASSERT_CHECK='TRUE';
      NO_DIR_CHECK='TRUE';
      ALLOW_CONNECT='TRUE';
    'VSS_BR34':
      PIN_NUMBER='(0,0,0,0,0,0,0,0,0,0,0,0,0,0,0,0,0,0,0,0,0,0,0,0,0,0,0,0,0,0,0,0,0,BR34,0,0,0,0,0,0)';
      PINUSE='POWER';
      NO_LOAD_CHECK='Both';
      NO_IO_CHECK='Both';
      NO_ASSERT_CHECK='TRUE';
      NO_DIR_CHECK='TRUE';
      ALLOW_CONNECT='TRUE';
    'VSS_BR36':
      PIN_NUMBER='(0,0,0,0,0,0,0,0,0,0,0,0,0,0,0,0,0,0,0,0,0,0,0,0,0,0,0,0,0,0,0,0,0,BR36,0,0,0,0,0,0)';
      PINUSE='POWER';
      NO_LOAD_CHECK='Both';
      NO_IO_CHECK='Both';
      NO_ASSERT_CHECK='TRUE';
      NO_DIR_CHECK='TRUE';
      ALLOW_CONNECT='TRUE';
    'VSS_BR41':
      PIN_NUMBER='(0,0,0,0,0,0,0,0,0,0,0,0,0,0,0,0,0,0,0,0,0,0,0,0,0,0,0,0,0,0,0,0,0,BR41,0,0,0,0,0,0)';
      PINUSE='POWER';
      NO_LOAD_CHECK='Both';
      NO_IO_CHECK='Both';
      NO_ASSERT_CHECK='TRUE';
      NO_DIR_CHECK='TRUE';
      ALLOW_CONNECT='TRUE';
    'VSS_BR43':
      PIN_NUMBER='(0,0,0,0,0,0,0,0,0,0,0,0,0,0,0,0,0,0,0,0,0,0,0,0,0,0,0,0,0,0,0,0,0,BR43,0,0,0,0,0,0)';
      PINUSE='POWER';
      NO_LOAD_CHECK='Both';
      NO_IO_CHECK='Both';
      NO_ASSERT_CHECK='TRUE';
      NO_DIR_CHECK='TRUE';
      ALLOW_CONNECT='TRUE';
    'VSS_BR45':
      PIN_NUMBER='(0,0,0,0,0,0,0,0,0,0,0,0,0,0,0,0,0,0,0,0,0,0,0,0,0,0,0,0,0,0,0,0,0,BR45,0,0,0,0,0,0)';
      PINUSE='POWER';
      NO_LOAD_CHECK='Both';
      NO_IO_CHECK='Both';
      NO_ASSERT_CHECK='TRUE';
      NO_DIR_CHECK='TRUE';
      ALLOW_CONNECT='TRUE';
    'VSS_BR47':
      PIN_NUMBER='(0,0,0,0,0,0,0,0,0,0,0,0,0,0,0,0,0,0,0,0,0,0,0,0,0,0,0,0,0,0,0,0,0,BR47,0,0,0,0,0,0)';
      PINUSE='POWER';
      NO_LOAD_CHECK='Both';
      NO_IO_CHECK='Both';
      NO_ASSERT_CHECK='TRUE';
      NO_DIR_CHECK='TRUE';
      ALLOW_CONNECT='TRUE';
    'VSS_BR49':
      PIN_NUMBER='(0,0,0,0,0,0,0,0,0,0,0,0,0,0,0,0,0,0,0,0,0,0,0,0,0,0,0,0,0,0,0,0,0,BR49,0,0,0,0,0,0)';
      PINUSE='POWER';
      NO_LOAD_CHECK='Both';
      NO_IO_CHECK='Both';
      NO_ASSERT_CHECK='TRUE';
      NO_DIR_CHECK='TRUE';
      ALLOW_CONNECT='TRUE';
    'VSS_BR51':
      PIN_NUMBER='(0,0,0,0,0,0,0,0,0,0,0,0,0,0,0,0,0,0,0,0,0,0,0,0,0,0,0,0,0,0,0,0,0,BR51,0,0,0,0,0,0)';
      PINUSE='POWER';
      NO_LOAD_CHECK='Both';
      NO_IO_CHECK='Both';
      NO_ASSERT_CHECK='TRUE';
      NO_DIR_CHECK='TRUE';
      ALLOW_CONNECT='TRUE';
    'VSS_BR55':
      PIN_NUMBER='(0,0,0,0,0,0,0,0,0,0,0,0,0,0,0,0,0,0,0,0,0,0,0,0,0,0,0,0,0,0,0,0,0,BR55,0,0,0,0,0,0)';
      PINUSE='POWER';
      NO_LOAD_CHECK='Both';
      NO_IO_CHECK='Both';
      NO_ASSERT_CHECK='TRUE';
      NO_DIR_CHECK='TRUE';
      ALLOW_CONNECT='TRUE';
    'VSS_BR56':
      PIN_NUMBER='(0,0,0,0,0,0,0,0,0,0,0,0,0,0,0,0,0,0,0,0,0,0,0,0,0,0,0,0,0,0,0,0,0,BR56,0,0,0,0,0,0)';
      PINUSE='POWER';
      NO_LOAD_CHECK='Both';
      NO_IO_CHECK='Both';
      NO_ASSERT_CHECK='TRUE';
      NO_DIR_CHECK='TRUE';
      ALLOW_CONNECT='TRUE';
    'VSS_BR59':
      PIN_NUMBER='(0,0,0,0,0,0,0,0,0,0,0,0,0,0,0,0,0,0,0,0,0,0,0,0,0,0,0,0,0,0,0,0,0,BR59,0,0,0,0,0,0)';
      PINUSE='POWER';
      NO_LOAD_CHECK='Both';
      NO_IO_CHECK='Both';
      NO_ASSERT_CHECK='TRUE';
      NO_DIR_CHECK='TRUE';
      ALLOW_CONNECT='TRUE';
    'VSS_BR61':
      PIN_NUMBER='(0,0,0,0,0,0,0,0,0,0,0,0,0,0,0,0,0,0,0,0,0,0,0,0,0,0,0,0,0,0,0,0,0,BR61,0,0,0,0,0,0)';
      PINUSE='POWER';
      NO_LOAD_CHECK='Both';
      NO_IO_CHECK='Both';
      NO_ASSERT_CHECK='TRUE';
      NO_DIR_CHECK='TRUE';
      ALLOW_CONNECT='TRUE';
    'VSS_BR62':
      PIN_NUMBER='(0,0,0,0,0,0,0,0,0,0,0,0,0,0,0,0,0,0,0,0,0,0,0,0,0,0,0,0,0,0,0,0,0,BR62,0,0,0,0,0,0)';
      PINUSE='POWER';
      NO_LOAD_CHECK='Both';
      NO_IO_CHECK='Both';
      NO_ASSERT_CHECK='TRUE';
      NO_DIR_CHECK='TRUE';
      ALLOW_CONNECT='TRUE';
    'VSS_BR63':
      PIN_NUMBER='(0,0,0,0,0,0,0,0,0,0,0,0,0,0,0,0,0,0,0,0,0,0,0,0,0,0,0,0,0,0,0,0,0,BR63,0,0,0,0,0,0)';
      PINUSE='POWER';
      NO_LOAD_CHECK='Both';
      NO_IO_CHECK='Both';
      NO_ASSERT_CHECK='TRUE';
      NO_DIR_CHECK='TRUE';
      ALLOW_CONNECT='TRUE';
    'VSS_BR66':
      PIN_NUMBER='(0,0,0,0,0,0,0,0,0,0,0,0,0,0,0,0,0,0,0,0,0,0,0,0,0,0,0,0,0,0,0,0,0,BR66,0,0,0,0,0,0)';
      PINUSE='POWER';
      NO_LOAD_CHECK='Both';
      NO_IO_CHECK='Both';
      NO_ASSERT_CHECK='TRUE';
      NO_DIR_CHECK='TRUE';
      ALLOW_CONNECT='TRUE';
    'VSS_BR68':
      PIN_NUMBER='(0,0,0,0,0,0,0,0,0,0,0,0,0,0,0,0,0,0,0,0,0,0,0,0,0,0,0,0,0,0,0,0,0,BR68,0,0,0,0,0,0)';
      PINUSE='POWER';
      NO_LOAD_CHECK='Both';
      NO_IO_CHECK='Both';
      NO_ASSERT_CHECK='TRUE';
      NO_DIR_CHECK='TRUE';
      ALLOW_CONNECT='TRUE';
    'VSS_BR69':
      PIN_NUMBER='(0,0,0,0,0,0,0,0,0,0,0,0,0,0,0,0,0,0,0,0,0,0,0,0,0,0,0,0,0,0,0,0,0,BR69,0,0,0,0,0,0)';
      PINUSE='POWER';
      NO_LOAD_CHECK='Both';
      NO_IO_CHECK='Both';
      NO_ASSERT_CHECK='TRUE';
      NO_DIR_CHECK='TRUE';
      ALLOW_CONNECT='TRUE';
    'VSS_BR70':
      PIN_NUMBER='(0,0,0,0,0,0,0,0,0,0,0,0,0,0,0,0,0,0,0,0,0,0,0,0,0,0,0,0,0,0,0,0,0,BR70,0,0,0,0,0,0)';
      PINUSE='POWER';
      NO_LOAD_CHECK='Both';
      NO_IO_CHECK='Both';
      NO_ASSERT_CHECK='TRUE';
      NO_DIR_CHECK='TRUE';
      ALLOW_CONNECT='TRUE';
    'VSS_BR73':
      PIN_NUMBER='(0,0,0,0,0,0,0,0,0,0,0,0,0,0,0,0,0,0,0,0,0,0,0,0,0,0,0,0,0,0,0,0,0,BR73,0,0,0,0,0,0)';
      PINUSE='POWER';
      NO_LOAD_CHECK='Both';
      NO_IO_CHECK='Both';
      NO_ASSERT_CHECK='TRUE';
      NO_DIR_CHECK='TRUE';
      ALLOW_CONNECT='TRUE';
    'VSS_BR75':
      PIN_NUMBER='(0,0,0,0,0,0,0,0,0,0,0,0,0,0,0,0,0,0,0,0,0,0,0,0,0,0,0,0,0,0,0,0,0,BR75,0,0,0,0,0,0)';
      PINUSE='POWER';
      NO_LOAD_CHECK='Both';
      NO_IO_CHECK='Both';
      NO_ASSERT_CHECK='TRUE';
      NO_DIR_CHECK='TRUE';
      ALLOW_CONNECT='TRUE';
    'VSS_BT3':
      PIN_NUMBER='(0,0,0,0,0,0,0,0,0,0,0,0,0,0,0,0,0,0,0,0,0,0,0,0,0,0,0,0,0,0,0,0,0,BT3,0,0,0,0,0,0)';
      PINUSE='POWER';
      NO_LOAD_CHECK='Both';
      NO_IO_CHECK='Both';
      NO_ASSERT_CHECK='TRUE';
      NO_DIR_CHECK='TRUE';
      ALLOW_CONNECT='TRUE';
    'VSS_BT4':
      PIN_NUMBER='(0,0,0,0,0,0,0,0,0,0,0,0,0,0,0,0,0,0,0,0,0,0,0,0,0,0,0,0,0,0,0,0,0,BT4,0,0,0,0,0,0)';
      PINUSE='POWER';
      NO_LOAD_CHECK='Both';
      NO_IO_CHECK='Both';
      NO_ASSERT_CHECK='TRUE';
      NO_DIR_CHECK='TRUE';
      ALLOW_CONNECT='TRUE';
    'VSS_BT5':
      PIN_NUMBER='(0,0,0,0,0,0,0,0,0,0,0,0,0,0,0,0,0,0,0,0,0,0,0,0,0,0,0,0,0,0,0,0,0,BT5,0,0,0,0,0,0)';
      PINUSE='POWER';
      NO_LOAD_CHECK='Both';
      NO_IO_CHECK='Both';
      NO_ASSERT_CHECK='TRUE';
      NO_DIR_CHECK='TRUE';
      ALLOW_CONNECT='TRUE';
    'VSS_BT7':
      PIN_NUMBER='(0,0,0,0,0,0,0,0,0,0,0,0,0,0,0,0,0,0,0,0,0,0,0,0,0,0,0,0,0,0,0,0,0,BT7,0,0,0,0,0,0)';
      PINUSE='POWER';
      NO_LOAD_CHECK='Both';
      NO_IO_CHECK='Both';
      NO_ASSERT_CHECK='TRUE';
      NO_DIR_CHECK='TRUE';
      ALLOW_CONNECT='TRUE';
    'VSS_BT8':
      PIN_NUMBER='(0,0,0,0,0,0,0,0,0,0,0,0,0,0,0,0,0,0,0,0,0,0,0,0,0,0,0,0,0,0,0,0,0,BT8,0,0,0,0,0,0)';
      PINUSE='POWER';
      NO_LOAD_CHECK='Both';
      NO_IO_CHECK='Both';
      NO_ASSERT_CHECK='TRUE';
      NO_DIR_CHECK='TRUE';
      ALLOW_CONNECT='TRUE';
    'VSS_BT10':
      PIN_NUMBER='(0,0,0,0,0,0,0,0,0,0,0,0,0,0,0,0,0,0,0,0,0,0,0,0,0,0,0,0,0,0,0,0,0,BT10,0,0,0,0,0,0)';
      PINUSE='POWER';
      NO_LOAD_CHECK='Both';
      NO_IO_CHECK='Both';
      NO_ASSERT_CHECK='TRUE';
      NO_DIR_CHECK='TRUE';
      ALLOW_CONNECT='TRUE';
    'VSS_BT11':
      PIN_NUMBER='(0,0,0,0,0,0,0,0,0,0,0,0,0,0,0,0,0,0,0,0,0,0,0,0,0,0,0,0,0,0,0,0,0,BT11,0,0,0,0,0,0)';
      PINUSE='POWER';
      NO_LOAD_CHECK='Both';
      NO_IO_CHECK='Both';
      NO_ASSERT_CHECK='TRUE';
      NO_DIR_CHECK='TRUE';
      ALLOW_CONNECT='TRUE';
    'VSS_BT12':
      PIN_NUMBER='(0,0,0,0,0,0,0,0,0,0,0,0,0,0,0,0,0,0,0,0,0,0,0,0,0,0,0,0,0,0,0,0,0,BT12,0,0,0,0,0,0)';
      PINUSE='POWER';
      NO_LOAD_CHECK='Both';
      NO_IO_CHECK='Both';
      NO_ASSERT_CHECK='TRUE';
      NO_DIR_CHECK='TRUE';
      ALLOW_CONNECT='TRUE';
    'VSS_BT14':
      PIN_NUMBER='(0,0,0,0,0,0,0,0,0,0,0,0,0,0,0,0,0,0,0,0,0,0,0,0,0,0,0,0,0,0,0,0,0,BT14,0,0,0,0,0,0)';
      PINUSE='POWER';
      NO_LOAD_CHECK='Both';
      NO_IO_CHECK='Both';
      NO_ASSERT_CHECK='TRUE';
      NO_DIR_CHECK='TRUE';
      ALLOW_CONNECT='TRUE';
    'VSS_BT15':
      PIN_NUMBER='(0,0,0,0,0,0,0,0,0,0,0,0,0,0,0,0,0,0,0,0,0,0,0,0,0,0,0,0,0,0,0,0,0,BT15,0,0,0,0,0,0)';
      PINUSE='POWER';
      NO_LOAD_CHECK='Both';
      NO_IO_CHECK='Both';
      NO_ASSERT_CHECK='TRUE';
      NO_DIR_CHECK='TRUE';
      ALLOW_CONNECT='TRUE';
    'VSS_BT17':
      PIN_NUMBER='(0,0,0,0,0,0,0,0,0,0,0,0,0,0,0,0,0,0,0,0,0,0,0,0,0,0,0,0,0,0,0,0,0,BT17,0,0,0,0,0,0)';
      PINUSE='POWER';
      NO_LOAD_CHECK='Both';
      NO_IO_CHECK='Both';
      NO_ASSERT_CHECK='TRUE';
      NO_DIR_CHECK='TRUE';
      ALLOW_CONNECT='TRUE';
    'VSS_BT18':
      PIN_NUMBER='(0,0,0,0,0,0,0,0,0,0,0,0,0,0,0,0,0,0,0,0,0,0,0,0,0,0,0,0,0,0,0,0,0,BT18,0,0,0,0,0,0)';
      PINUSE='POWER';
      NO_LOAD_CHECK='Both';
      NO_IO_CHECK='Both';
      NO_ASSERT_CHECK='TRUE';
      NO_DIR_CHECK='TRUE';
      ALLOW_CONNECT='TRUE';
    'VSS_BT19':
      PIN_NUMBER='(0,0,0,0,0,0,0,0,0,0,0,0,0,0,0,0,0,0,0,0,0,0,0,0,0,0,0,0,0,0,0,0,0,BT19,0,0,0,0,0,0)';
      PINUSE='POWER';
      NO_LOAD_CHECK='Both';
      NO_IO_CHECK='Both';
      NO_ASSERT_CHECK='TRUE';
      NO_DIR_CHECK='TRUE';
      ALLOW_CONNECT='TRUE';
    'VSS_BT21':
      PIN_NUMBER='(0,0,0,0,0,0,0,0,0,0,0,0,0,0,0,0,0,0,0,0,0,0,0,0,0,0,0,0,0,0,0,0,0,BT21,0,0,0,0,0,0)';
      PINUSE='POWER';
      NO_LOAD_CHECK='Both';
      NO_IO_CHECK='Both';
      NO_ASSERT_CHECK='TRUE';
      NO_DIR_CHECK='TRUE';
      ALLOW_CONNECT='TRUE';
    'VSS_BT22':
      PIN_NUMBER='(0,0,0,0,0,0,0,0,0,0,0,0,0,0,0,0,0,0,0,0,0,0,0,0,0,0,0,0,0,0,0,0,0,BT22,0,0,0,0,0,0)';
      PINUSE='POWER';
      NO_LOAD_CHECK='Both';
      NO_IO_CHECK='Both';
      NO_ASSERT_CHECK='TRUE';
      NO_DIR_CHECK='TRUE';
      ALLOW_CONNECT='TRUE';
    'VSS_BT25':
      PIN_NUMBER='(0,0,0,0,0,0,0,0,0,0,0,0,0,0,0,0,0,0,0,0,0,0,0,0,0,0,0,0,0,0,0,0,0,BT25,0,0,0,0,0,0)';
      PINUSE='POWER';
      NO_LOAD_CHECK='Both';
      NO_IO_CHECK='Both';
      NO_ASSERT_CHECK='TRUE';
      NO_DIR_CHECK='TRUE';
      ALLOW_CONNECT='TRUE';
    'VSS_BT28':
      PIN_NUMBER='(0,0,0,0,0,0,0,0,0,0,0,0,0,0,0,0,0,0,0,0,0,0,0,0,0,0,0,0,0,0,0,0,0,BT28,0,0,0,0,0,0)';
      PINUSE='POWER';
      NO_LOAD_CHECK='Both';
      NO_IO_CHECK='Both';
      NO_ASSERT_CHECK='TRUE';
      NO_DIR_CHECK='TRUE';
      ALLOW_CONNECT='TRUE';
    'VSS_BT31':
      PIN_NUMBER='(0,0,0,0,0,0,0,0,0,0,0,0,0,0,0,0,0,0,0,0,0,0,0,0,0,0,0,0,0,0,0,0,0,BT31,0,0,0,0,0,0)';
      PINUSE='POWER';
      NO_LOAD_CHECK='Both';
      NO_IO_CHECK='Both';
      NO_ASSERT_CHECK='TRUE';
      NO_DIR_CHECK='TRUE';
      ALLOW_CONNECT='TRUE';
    'VSS_BT34':
      PIN_NUMBER='(0,0,0,0,0,0,0,0,0,0,0,0,0,0,0,0,0,0,0,0,0,0,0,0,0,0,0,0,0,0,0,0,0,BT34,0,0,0,0,0,0)';
      PINUSE='POWER';
      NO_LOAD_CHECK='Both';
      NO_IO_CHECK='Both';
      NO_ASSERT_CHECK='TRUE';
      NO_DIR_CHECK='TRUE';
      ALLOW_CONNECT='TRUE';
    'VSS_BT37':
      PIN_NUMBER='(0,0,0,0,0,0,0,0,0,0,0,0,0,0,0,0,0,0,0,0,0,0,0,0,0,0,0,0,0,0,0,0,0,BT37,0,0,0,0,0,0)';
      PINUSE='POWER';
      NO_LOAD_CHECK='Both';
      NO_IO_CHECK='Both';
      NO_ASSERT_CHECK='TRUE';
      NO_DIR_CHECK='TRUE';
      ALLOW_CONNECT='TRUE';
    'VSS_BT39':
      PIN_NUMBER='(0,0,0,0,0,0,0,0,0,0,0,0,0,0,0,0,0,0,0,0,0,0,0,0,0,0,0,0,0,0,0,0,0,BT39,0,0,0,0,0,0)';
      PINUSE='POWER';
      NO_LOAD_CHECK='Both';
      NO_IO_CHECK='Both';
      NO_ASSERT_CHECK='TRUE';
      NO_DIR_CHECK='TRUE';
      ALLOW_CONNECT='TRUE';
    'VSS_BT42':
      PIN_NUMBER='(0,0,0,0,0,0,0,0,0,0,0,0,0,0,0,0,0,0,0,0,0,0,0,0,0,0,0,0,0,0,0,0,0,BT42,0,0,0,0,0,0)';
      PINUSE='POWER';
      NO_LOAD_CHECK='Both';
      NO_IO_CHECK='Both';
      NO_ASSERT_CHECK='TRUE';
      NO_DIR_CHECK='TRUE';
      ALLOW_CONNECT='TRUE';
    'VSS_BT45':
      PIN_NUMBER='(0,0,0,0,0,0,0,0,0,0,0,0,0,0,0,0,0,0,0,0,0,0,0,0,0,0,0,0,0,0,0,0,0,BT45,0,0,0,0,0,0)';
      PINUSE='POWER';
      NO_LOAD_CHECK='Both';
      NO_IO_CHECK='Both';
      NO_ASSERT_CHECK='TRUE';
      NO_DIR_CHECK='TRUE';
      ALLOW_CONNECT='TRUE';
    'VSS_BT48':
      PIN_NUMBER='(0,0,0,0,0,0,0,0,0,0,0,0,0,0,0,0,0,0,0,0,0,0,0,0,0,0,0,0,0,0,0,0,0,BT48,0,0,0,0,0,0)';
      PINUSE='POWER';
      NO_LOAD_CHECK='Both';
      NO_IO_CHECK='Both';
      NO_ASSERT_CHECK='TRUE';
      NO_DIR_CHECK='TRUE';
      ALLOW_CONNECT='TRUE';
    'VSS_BT51':
      PIN_NUMBER='(0,0,0,0,0,0,0,0,0,0,0,0,0,0,0,0,0,0,0,0,0,0,0,0,0,0,0,0,0,0,0,0,0,BT51,0,0,0,0,0,0)';
      PINUSE='POWER';
      NO_LOAD_CHECK='Both';
      NO_IO_CHECK='Both';
      NO_ASSERT_CHECK='TRUE';
      NO_DIR_CHECK='TRUE';
      ALLOW_CONNECT='TRUE';
    'VSS_BT54':
      PIN_NUMBER='(0,0,0,0,0,0,0,0,0,0,0,0,0,0,0,0,0,0,0,0,0,0,0,0,0,0,0,0,0,0,0,0,0,BT54,0,0,0,0,0,0)';
      PINUSE='POWER';
      NO_LOAD_CHECK='Both';
      NO_IO_CHECK='Both';
      NO_ASSERT_CHECK='TRUE';
      NO_DIR_CHECK='TRUE';
      ALLOW_CONNECT='TRUE';
    'VSS_BT55':
      PIN_NUMBER='(0,0,0,0,0,0,0,0,0,0,0,0,0,0,0,0,0,0,0,0,0,0,0,0,0,0,0,0,0,0,0,0,0,BT55,0,0,0,0,0,0)';
      PINUSE='POWER';
      NO_LOAD_CHECK='Both';
      NO_IO_CHECK='Both';
      NO_ASSERT_CHECK='TRUE';
      NO_DIR_CHECK='TRUE';
      ALLOW_CONNECT='TRUE';
    'VSS_BT57':
      PIN_NUMBER='(0,0,0,0,0,0,0,0,0,0,0,0,0,0,0,0,0,0,0,0,0,0,0,0,0,0,0,0,0,0,0,0,0,BT57,0,0,0,0,0,0)';
      PINUSE='POWER';
      NO_LOAD_CHECK='Both';
      NO_IO_CHECK='Both';
      NO_ASSERT_CHECK='TRUE';
      NO_DIR_CHECK='TRUE';
      ALLOW_CONNECT='TRUE';
    'VSS_BT58':
      PIN_NUMBER='(0,0,0,0,0,0,0,0,0,0,0,0,0,0,0,0,0,0,0,0,0,0,0,0,0,0,0,0,0,0,0,0,0,BT58,0,0,0,0,0,0)';
      PINUSE='POWER';
      NO_LOAD_CHECK='Both';
      NO_IO_CHECK='Both';
      NO_ASSERT_CHECK='TRUE';
      NO_DIR_CHECK='TRUE';
      ALLOW_CONNECT='TRUE';
    'VSS_BT59':
      PIN_NUMBER='(0,0,0,0,0,0,0,0,0,0,0,0,0,0,0,0,0,0,0,0,0,0,0,0,0,0,0,0,0,0,0,0,0,BT59,0,0,0,0,0,0)';
      PINUSE='POWER';
      NO_LOAD_CHECK='Both';
      NO_IO_CHECK='Both';
      NO_ASSERT_CHECK='TRUE';
      NO_DIR_CHECK='TRUE';
      ALLOW_CONNECT='TRUE';
    'VSS_BT61':
      PIN_NUMBER='(0,0,0,0,0,0,0,0,0,0,0,0,0,0,0,0,0,0,0,0,0,0,0,0,0,0,0,0,0,0,0,0,0,BT61,0,0,0,0,0,0)';
      PINUSE='POWER';
      NO_LOAD_CHECK='Both';
      NO_IO_CHECK='Both';
      NO_ASSERT_CHECK='TRUE';
      NO_DIR_CHECK='TRUE';
      ALLOW_CONNECT='TRUE';
    'VSS_BT62':
      PIN_NUMBER='(0,0,0,0,0,0,0,0,0,0,0,0,0,0,0,0,0,0,0,0,0,0,0,0,0,0,0,0,0,0,0,0,0,BT62,0,0,0,0,0,0)';
      PINUSE='POWER';
      NO_LOAD_CHECK='Both';
      NO_IO_CHECK='Both';
      NO_ASSERT_CHECK='TRUE';
      NO_DIR_CHECK='TRUE';
      ALLOW_CONNECT='TRUE';
    'VSS_BT64':
      PIN_NUMBER='(0,0,0,0,0,0,0,0,0,0,0,0,0,0,0,0,0,0,0,0,0,0,0,0,0,0,0,0,0,0,0,0,0,BT64,0,0,0,0,0,0)';
      PINUSE='POWER';
      NO_LOAD_CHECK='Both';
      NO_IO_CHECK='Both';
      NO_ASSERT_CHECK='TRUE';
      NO_DIR_CHECK='TRUE';
      ALLOW_CONNECT='TRUE';
    'VSS_BT65':
      PIN_NUMBER='(0,0,0,0,0,0,0,0,0,0,0,0,0,0,0,0,0,0,0,0,0,0,0,0,0,0,0,0,0,0,0,0,0,BT65,0,0,0,0,0,0)';
      PINUSE='POWER';
      NO_LOAD_CHECK='Both';
      NO_IO_CHECK='Both';
      NO_ASSERT_CHECK='TRUE';
      NO_DIR_CHECK='TRUE';
      ALLOW_CONNECT='TRUE';
    'VSS_BT66':
      PIN_NUMBER='(0,0,0,0,0,0,0,0,0,0,0,0,0,0,0,0,0,0,0,0,0,0,0,0,0,0,0,0,0,0,0,0,0,BT66,0,0,0,0,0,0)';
      PINUSE='POWER';
      NO_LOAD_CHECK='Both';
      NO_IO_CHECK='Both';
      NO_ASSERT_CHECK='TRUE';
      NO_DIR_CHECK='TRUE';
      ALLOW_CONNECT='TRUE';
    'VSS_BT68':
      PIN_NUMBER='(0,0,0,0,0,0,0,0,0,0,0,0,0,0,0,0,0,0,0,0,0,0,0,0,0,0,0,0,0,0,0,0,0,BT68,0,0,0,0,0,0)';
      PINUSE='POWER';
      NO_LOAD_CHECK='Both';
      NO_IO_CHECK='Both';
      NO_ASSERT_CHECK='TRUE';
      NO_DIR_CHECK='TRUE';
      ALLOW_CONNECT='TRUE';
    'VSS_BT69':
      PIN_NUMBER='(0,0,0,0,0,0,0,0,0,0,0,0,0,0,0,0,0,0,0,0,0,0,0,0,0,0,0,0,0,0,0,0,0,BT69,0,0,0,0,0,0)';
      PINUSE='POWER';
      NO_LOAD_CHECK='Both';
      NO_IO_CHECK='Both';
      NO_ASSERT_CHECK='TRUE';
      NO_DIR_CHECK='TRUE';
      ALLOW_CONNECT='TRUE';
    'VSS_BT71':
      PIN_NUMBER='(0,0,0,0,0,0,0,0,0,0,0,0,0,0,0,0,0,0,0,0,0,0,0,0,0,0,0,0,0,0,0,0,0,BT71,0,0,0,0,0,0)';
      PINUSE='POWER';
      NO_LOAD_CHECK='Both';
      NO_IO_CHECK='Both';
      NO_ASSERT_CHECK='TRUE';
      NO_DIR_CHECK='TRUE';
      ALLOW_CONNECT='TRUE';
    'VSS_BT72':
      PIN_NUMBER='(0,0,0,0,0,0,0,0,0,0,0,0,0,0,0,0,0,0,0,0,0,0,0,0,0,0,0,0,0,0,0,0,0,BT72,0,0,0,0,0,0)';
      PINUSE='POWER';
      NO_LOAD_CHECK='Both';
      NO_IO_CHECK='Both';
      NO_ASSERT_CHECK='TRUE';
      NO_DIR_CHECK='TRUE';
      ALLOW_CONNECT='TRUE';
    'VSS_BT73':
      PIN_NUMBER='(0,0,0,0,0,0,0,0,0,0,0,0,0,0,0,0,0,0,0,0,0,0,0,0,0,0,0,0,0,0,0,0,0,BT73,0,0,0,0,0,0)';
      PINUSE='POWER';
      NO_LOAD_CHECK='Both';
      NO_IO_CHECK='Both';
      NO_ASSERT_CHECK='TRUE';
      NO_DIR_CHECK='TRUE';
      ALLOW_CONNECT='TRUE';
    'VSS_BU1':
      PIN_NUMBER='(0,0,0,0,0,0,0,0,0,0,0,0,0,0,0,0,0,0,0,0,0,0,0,0,0,0,0,0,0,0,0,0,0,BU1,0,0,0,0,0,0)';
      PINUSE='POWER';
      NO_LOAD_CHECK='Both';
      NO_IO_CHECK='Both';
      NO_ASSERT_CHECK='TRUE';
      NO_DIR_CHECK='TRUE';
      ALLOW_CONNECT='TRUE';
    'VSS_BU4':
      PIN_NUMBER='(0,0,0,0,0,0,0,0,0,0,0,0,0,0,0,0,0,0,0,0,0,0,0,0,0,0,0,0,0,0,0,0,0,BU4,0,0,0,0,0,0)';
      PINUSE='POWER';
      NO_LOAD_CHECK='Both';
      NO_IO_CHECK='Both';
      NO_ASSERT_CHECK='TRUE';
      NO_DIR_CHECK='TRUE';
      ALLOW_CONNECT='TRUE';
    'VSS_BU6':
      PIN_NUMBER='(0,0,0,0,0,0,0,0,0,0,0,0,0,0,0,0,0,0,0,0,0,0,0,0,0,0,0,0,0,0,0,0,0,BU6,0,0,0,0,0,0)';
      PINUSE='POWER';
      NO_LOAD_CHECK='Both';
      NO_IO_CHECK='Both';
      NO_ASSERT_CHECK='TRUE';
      NO_DIR_CHECK='TRUE';
      ALLOW_CONNECT='TRUE';
    'VSS_BU8':
      PIN_NUMBER='(0,0,0,0,0,0,0,0,0,0,0,0,0,0,0,0,0,0,0,0,0,0,0,0,0,0,0,0,0,0,0,0,0,BU8,0,0,0,0,0,0)';
      PINUSE='POWER';
      NO_LOAD_CHECK='Both';
      NO_IO_CHECK='Both';
      NO_ASSERT_CHECK='TRUE';
      NO_DIR_CHECK='TRUE';
      ALLOW_CONNECT='TRUE';
    'VSS_BU11':
      PIN_NUMBER='(0,0,0,0,0,0,0,0,0,0,0,0,0,0,0,0,0,0,0,0,0,0,0,0,0,0,0,0,0,0,0,0,0,BU11,0,0,0,0,0,0)';
      PINUSE='POWER';
      NO_LOAD_CHECK='Both';
      NO_IO_CHECK='Both';
      NO_ASSERT_CHECK='TRUE';
      NO_DIR_CHECK='TRUE';
      ALLOW_CONNECT='TRUE';
    'VSS_BU13':
      PIN_NUMBER='(0,0,0,0,0,0,0,0,0,0,0,0,0,0,0,0,0,0,0,0,0,0,0,0,0,0,0,0,0,0,0,0,0,BU13,0,0,0,0,0,0)';
      PINUSE='POWER';
      NO_LOAD_CHECK='Both';
      NO_IO_CHECK='Both';
      NO_ASSERT_CHECK='TRUE';
      NO_DIR_CHECK='TRUE';
      ALLOW_CONNECT='TRUE';
    'VSS_BU15':
      PIN_NUMBER='(0,0,0,0,0,0,0,0,0,0,0,0,0,0,0,0,0,0,0,0,0,0,0,0,0,0,0,0,0,0,0,0,0,BU15,0,0,0,0,0,0)';
      PINUSE='POWER';
      NO_LOAD_CHECK='Both';
      NO_IO_CHECK='Both';
      NO_ASSERT_CHECK='TRUE';
      NO_DIR_CHECK='TRUE';
      ALLOW_CONNECT='TRUE';
    'VSS_BU18':
      PIN_NUMBER='(0,0,0,0,0,0,0,0,0,0,0,0,0,0,0,0,0,0,0,0,0,0,0,0,0,0,0,0,0,0,0,0,0,BU18,0,0,0,0,0,0)';
      PINUSE='POWER';
      NO_LOAD_CHECK='Both';
      NO_IO_CHECK='Both';
      NO_ASSERT_CHECK='TRUE';
      NO_DIR_CHECK='TRUE';
      ALLOW_CONNECT='TRUE';
    'VSS_BU20':
      PIN_NUMBER='(0,0,0,0,0,0,0,0,0,0,0,0,0,0,0,0,0,0,0,0,0,0,0,0,0,0,0,0,0,0,0,0,0,BU20,0,0,0,0,0,0)';
      PINUSE='POWER';
      NO_LOAD_CHECK='Both';
      NO_IO_CHECK='Both';
      NO_ASSERT_CHECK='TRUE';
      NO_DIR_CHECK='TRUE';
      ALLOW_CONNECT='TRUE';
    'VSS_BU22':
      PIN_NUMBER='(0,0,0,0,0,0,0,0,0,0,0,0,0,0,0,0,0,0,0,0,0,0,0,0,0,0,0,0,0,0,0,0,0,BU22,0,0,0,0,0,0)';
      PINUSE='POWER';
      NO_LOAD_CHECK='Both';
      NO_IO_CHECK='Both';
      NO_ASSERT_CHECK='TRUE';
      NO_DIR_CHECK='TRUE';
      ALLOW_CONNECT='TRUE';
    'VSS_BU25':
      PIN_NUMBER='(0,0,0,0,0,0,0,0,0,0,0,0,0,0,0,0,0,0,0,0,0,0,0,0,0,0,0,0,0,0,0,0,0,BU25,0,0,0,0,0,0)';
      PINUSE='POWER';
      NO_LOAD_CHECK='Both';
      NO_IO_CHECK='Both';
      NO_ASSERT_CHECK='TRUE';
      NO_DIR_CHECK='TRUE';
      ALLOW_CONNECT='TRUE';
    'VSS_BU28':
      PIN_NUMBER='(0,0,0,0,0,0,0,0,0,0,0,0,0,0,0,0,0,0,0,0,0,0,0,0,0,0,0,0,0,0,0,0,0,BU28,0,0,0,0,0,0)';
      PINUSE='POWER';
      NO_LOAD_CHECK='Both';
      NO_IO_CHECK='Both';
      NO_ASSERT_CHECK='TRUE';
      NO_DIR_CHECK='TRUE';
      ALLOW_CONNECT='TRUE';
    'VSS_BU31':
      PIN_NUMBER='(0,0,0,0,0,0,0,0,0,0,0,0,0,0,0,0,0,0,0,0,0,0,0,0,0,0,0,0,0,0,0,0,0,BU31,0,0,0,0,0,0)';
      PINUSE='POWER';
      NO_LOAD_CHECK='Both';
      NO_IO_CHECK='Both';
      NO_ASSERT_CHECK='TRUE';
      NO_DIR_CHECK='TRUE';
      ALLOW_CONNECT='TRUE';
    'VSS_BU34':
      PIN_NUMBER='(0,0,0,0,0,0,0,0,0,0,0,0,0,0,0,0,0,0,0,0,0,0,0,0,0,0,0,0,0,0,0,0,0,BU34,0,0,0,0,0,0)';
      PINUSE='POWER';
      NO_LOAD_CHECK='Both';
      NO_IO_CHECK='Both';
      NO_ASSERT_CHECK='TRUE';
      NO_DIR_CHECK='TRUE';
      ALLOW_CONNECT='TRUE';
    'VSS_BU35':
      PIN_NUMBER='(0,0,0,0,0,0,0,0,0,0,0,0,0,0,0,0,0,0,0,0,0,0,0,0,0,0,0,0,0,0,0,0,0,BU35,0,0,0,0,0,0)';
      PINUSE='POWER';
      NO_LOAD_CHECK='Both';
      NO_IO_CHECK='Both';
      NO_ASSERT_CHECK='TRUE';
      NO_DIR_CHECK='TRUE';
      ALLOW_CONNECT='TRUE';
    'VSS_BU36':
      PIN_NUMBER='(0,0,0,0,0,0,0,0,0,0,0,0,0,0,0,0,0,0,0,0,0,0,0,0,0,0,0,0,0,0,0,0,0,BU36,0,0,0,0,0,0)';
      PINUSE='POWER';
      NO_LOAD_CHECK='Both';
      NO_IO_CHECK='Both';
      NO_ASSERT_CHECK='TRUE';
      NO_DIR_CHECK='TRUE';
      ALLOW_CONNECT='TRUE';
    'VSS_BU40':
      PIN_NUMBER='(0,0,0,0,0,0,0,0,0,0,0,0,0,0,0,0,0,0,0,0,0,0,0,0,0,0,0,0,0,0,0,0,0,BU40,0,0,0,0,0,0)';
      PINUSE='POWER';
      NO_LOAD_CHECK='Both';
      NO_IO_CHECK='Both';
      NO_ASSERT_CHECK='TRUE';
      NO_DIR_CHECK='TRUE';
      ALLOW_CONNECT='TRUE';
    'VSS_BU41':
      PIN_NUMBER='(0,0,0,0,0,0,0,0,0,0,0,0,0,0,0,0,0,0,0,0,0,0,0,0,0,0,0,0,0,0,0,0,0,BU41,0,0,0,0,0,0)';
      PINUSE='POWER';
      NO_LOAD_CHECK='Both';
      NO_IO_CHECK='Both';
      NO_ASSERT_CHECK='TRUE';
      NO_DIR_CHECK='TRUE';
      ALLOW_CONNECT='TRUE';
    'VSS_BU42':
      PIN_NUMBER='(0,0,0,0,0,0,0,0,0,0,0,0,0,0,0,0,0,0,0,0,0,0,0,0,0,0,0,0,0,0,0,0,0,BU42,0,0,0,0,0,0)';
      PINUSE='POWER';
      NO_LOAD_CHECK='Both';
      NO_IO_CHECK='Both';
      NO_ASSERT_CHECK='TRUE';
      NO_DIR_CHECK='TRUE';
      ALLOW_CONNECT='TRUE';
    'VSS_BU45':
      PIN_NUMBER='(0,0,0,0,0,0,0,0,0,0,0,0,0,0,0,0,0,0,0,0,0,0,0,0,0,0,0,0,0,0,0,0,0,BU45,0,0,0,0,0,0)';
      PINUSE='POWER';
      NO_LOAD_CHECK='Both';
      NO_IO_CHECK='Both';
      NO_ASSERT_CHECK='TRUE';
      NO_DIR_CHECK='TRUE';
      ALLOW_CONNECT='TRUE';
    'VSS_BU48':
      PIN_NUMBER='(0,0,0,0,0,0,0,0,0,0,0,0,0,0,0,0,0,0,0,0,0,0,0,0,0,0,0,0,0,0,0,0,0,BU48,0,0,0,0,0,0)';
      PINUSE='POWER';
      NO_LOAD_CHECK='Both';
      NO_IO_CHECK='Both';
      NO_ASSERT_CHECK='TRUE';
      NO_DIR_CHECK='TRUE';
      ALLOW_CONNECT='TRUE';
    'VSS_BU51':
      PIN_NUMBER='(0,0,0,0,0,0,0,0,0,0,0,0,0,0,0,0,0,0,0,0,0,0,0,0,0,0,0,0,0,0,0,0,0,BU51,0,0,0,0,0,0)';
      PINUSE='POWER';
      NO_LOAD_CHECK='Both';
      NO_IO_CHECK='Both';
      NO_ASSERT_CHECK='TRUE';
      NO_DIR_CHECK='TRUE';
      ALLOW_CONNECT='TRUE';
    'VSS_BU54':
      PIN_NUMBER='(0,0,0,0,0,0,0,0,0,0,0,0,0,0,0,0,0,0,0,0,0,0,0,0,0,0,0,0,0,0,0,0,0,BU54,0,0,0,0,0,0)';
      PINUSE='POWER';
      NO_LOAD_CHECK='Both';
      NO_IO_CHECK='Both';
      NO_ASSERT_CHECK='TRUE';
      NO_DIR_CHECK='TRUE';
      ALLOW_CONNECT='TRUE';
    'VSS_BU56':
      PIN_NUMBER='(0,0,0,0,0,0,0,0,0,0,0,0,0,0,0,0,0,0,0,0,0,0,0,0,0,0,0,0,0,0,0,0,0,BU56,0,0,0,0,0,0)';
      PINUSE='POWER';
      NO_LOAD_CHECK='Both';
      NO_IO_CHECK='Both';
      NO_ASSERT_CHECK='TRUE';
      NO_DIR_CHECK='TRUE';
      ALLOW_CONNECT='TRUE';
    'VSS_BU58':
      PIN_NUMBER='(0,0,0,0,0,0,0,0,0,0,0,0,0,0,0,0,0,0,0,0,0,0,0,0,0,0,0,0,0,0,0,0,0,BU58,0,0,0,0,0,0)';
      PINUSE='POWER';
      NO_LOAD_CHECK='Both';
      NO_IO_CHECK='Both';
      NO_ASSERT_CHECK='TRUE';
      NO_DIR_CHECK='TRUE';
      ALLOW_CONNECT='TRUE';
    'VSS_BU61':
      PIN_NUMBER='(0,0,0,0,0,0,0,0,0,0,0,0,0,0,0,0,0,0,0,0,0,0,0,0,0,0,0,0,0,0,0,0,0,BU61,0,0,0,0,0,0)';
      PINUSE='POWER';
      NO_LOAD_CHECK='Both';
      NO_IO_CHECK='Both';
      NO_ASSERT_CHECK='TRUE';
      NO_DIR_CHECK='TRUE';
      ALLOW_CONNECT='TRUE';
    'VSS_BU63':
      PIN_NUMBER='(0,0,0,0,0,0,0,0,0,0,0,0,0,0,0,0,0,0,0,0,0,0,0,0,0,0,0,0,0,0,0,0,0,BU63,0,0,0,0,0,0)';
      PINUSE='POWER';
      NO_LOAD_CHECK='Both';
      NO_IO_CHECK='Both';
      NO_ASSERT_CHECK='TRUE';
      NO_DIR_CHECK='TRUE';
      ALLOW_CONNECT='TRUE';
    'VSS_BU65':
      PIN_NUMBER='(0,0,0,0,0,0,0,0,0,0,0,0,0,0,0,0,0,0,0,0,0,0,0,0,0,0,0,0,0,0,0,0,0,BU65,0,0,0,0,0,0)';
      PINUSE='POWER';
      NO_LOAD_CHECK='Both';
      NO_IO_CHECK='Both';
      NO_ASSERT_CHECK='TRUE';
      NO_DIR_CHECK='TRUE';
      ALLOW_CONNECT='TRUE';
    'VSS_BU68':
      PIN_NUMBER='(0,0,0,0,0,0,0,0,0,0,0,0,0,0,0,0,0,0,0,0,0,0,0,0,0,0,0,0,0,0,0,0,0,BU68,0,0,0,0,0,0)';
      PINUSE='POWER';
      NO_LOAD_CHECK='Both';
      NO_IO_CHECK='Both';
      NO_ASSERT_CHECK='TRUE';
      NO_DIR_CHECK='TRUE';
      ALLOW_CONNECT='TRUE';
    'VSS_BU70':
      PIN_NUMBER='(0,0,0,0,0,0,0,0,0,0,0,0,0,0,0,0,0,0,0,0,0,0,0,0,0,0,0,0,0,0,0,0,0,BU70,0,0,0,0,0,0)';
      PINUSE='POWER';
      NO_LOAD_CHECK='Both';
      NO_IO_CHECK='Both';
      NO_ASSERT_CHECK='TRUE';
      NO_DIR_CHECK='TRUE';
      ALLOW_CONNECT='TRUE';
    'VSS_BU72':
      PIN_NUMBER='(0,0,0,0,0,0,0,0,0,0,0,0,0,0,0,0,0,0,0,0,0,0,0,0,0,0,0,0,0,0,0,0,0,BU72,0,0,0,0,0,0)';
      PINUSE='POWER';
      NO_LOAD_CHECK='Both';
      NO_IO_CHECK='Both';
      NO_ASSERT_CHECK='TRUE';
      NO_DIR_CHECK='TRUE';
      ALLOW_CONNECT='TRUE';
    'VSS_BU75':
      PIN_NUMBER='(0,0,0,0,0,0,0,0,0,0,0,0,0,0,0,0,0,0,0,0,0,0,0,0,0,0,0,0,0,0,0,0,0,BU75,0,0,0,0,0,0)';
      PINUSE='POWER';
      NO_LOAD_CHECK='Both';
      NO_IO_CHECK='Both';
      NO_ASSERT_CHECK='TRUE';
      NO_DIR_CHECK='TRUE';
      ALLOW_CONNECT='TRUE';
    'VSS_BV3':
      PIN_NUMBER='(0,0,0,0,0,0,0,0,0,0,0,0,0,0,0,0,0,0,0,0,0,0,0,0,0,0,0,0,0,0,0,0,0,BV3,0,0,0,0,0,0)';
      PINUSE='POWER';
      NO_LOAD_CHECK='Both';
      NO_IO_CHECK='Both';
      NO_ASSERT_CHECK='TRUE';
      NO_DIR_CHECK='TRUE';
      ALLOW_CONNECT='TRUE';
    'VSS_BV8':
      PIN_NUMBER='(0,0,0,0,0,0,0,0,0,0,0,0,0,0,0,0,0,0,0,0,0,0,0,0,0,0,0,0,0,0,0,0,0,BV8,0,0,0,0,0,0)';
      PINUSE='POWER';
      NO_LOAD_CHECK='Both';
      NO_IO_CHECK='Both';
      NO_ASSERT_CHECK='TRUE';
      NO_DIR_CHECK='TRUE';
      ALLOW_CONNECT='TRUE';
    'VSS_BV10':
      PIN_NUMBER='(0,0,0,0,0,0,0,0,0,0,0,0,0,0,0,0,0,0,0,0,0,0,0,0,0,0,0,0,0,0,0,0,0,BV10,0,0,0,0,0,0)';
      PINUSE='POWER';
      NO_LOAD_CHECK='Both';
      NO_IO_CHECK='Both';
      NO_ASSERT_CHECK='TRUE';
      NO_DIR_CHECK='TRUE';
      ALLOW_CONNECT='TRUE';
    'VSS_BV15':
      PIN_NUMBER='(0,0,0,0,0,0,0,0,0,0,0,0,0,0,0,0,0,0,0,0,0,0,0,0,0,0,0,0,0,0,0,0,0,BV15,0,0,0,0,0,0)';
      PINUSE='POWER';
      NO_LOAD_CHECK='Both';
      NO_IO_CHECK='Both';
      NO_ASSERT_CHECK='TRUE';
      NO_DIR_CHECK='TRUE';
      ALLOW_CONNECT='TRUE';
    'VSS_BV17':
      PIN_NUMBER='(0,0,0,0,0,0,0,0,0,0,0,0,0,0,0,0,0,0,0,0,0,0,0,0,0,0,0,0,0,0,0,0,0,BV17,0,0,0,0,0,0)';
      PINUSE='POWER';
      NO_LOAD_CHECK='Both';
      NO_IO_CHECK='Both';
      NO_ASSERT_CHECK='TRUE';
      NO_DIR_CHECK='TRUE';
      ALLOW_CONNECT='TRUE';
    'VSS_BV23':
      PIN_NUMBER='(0,0,0,0,0,0,0,0,0,0,0,0,0,0,0,0,0,0,0,0,0,0,0,0,0,0,0,0,0,0,0,0,0,BV23,0,0,0,0,0,0)';
      PINUSE='POWER';
      NO_LOAD_CHECK='Both';
      NO_IO_CHECK='Both';
      NO_ASSERT_CHECK='TRUE';
      NO_DIR_CHECK='TRUE';
      ALLOW_CONNECT='TRUE';
    'VSS_BV24':
      PIN_NUMBER='(0,0,0,0,0,0,0,0,0,0,0,0,0,0,0,0,0,0,0,0,0,0,0,0,0,0,0,0,0,0,0,0,0,BV24,0,0,0,0,0,0)';
      PINUSE='POWER';
      NO_LOAD_CHECK='Both';
      NO_IO_CHECK='Both';
      NO_ASSERT_CHECK='TRUE';
      NO_DIR_CHECK='TRUE';
      ALLOW_CONNECT='TRUE';
    'VSS_BV25':
      PIN_NUMBER='(0,0,0,0,0,0,0,0,0,0,0,0,0,0,0,0,0,0,0,0,0,0,0,0,0,0,0,0,0,0,0,0,0,BV25,0,0,0,0,0,0)';
      PINUSE='POWER';
      NO_LOAD_CHECK='Both';
      NO_IO_CHECK='Both';
      NO_ASSERT_CHECK='TRUE';
      NO_DIR_CHECK='TRUE';
      ALLOW_CONNECT='TRUE';
    'VSS_BV26':
      PIN_NUMBER='(0,0,0,0,0,0,0,0,0,0,0,0,0,0,0,0,0,0,0,0,0,0,0,0,0,0,0,0,0,0,0,0,0,BV26,0,0,0,0,0,0)';
      PINUSE='POWER';
      NO_LOAD_CHECK='Both';
      NO_IO_CHECK='Both';
      NO_ASSERT_CHECK='TRUE';
      NO_DIR_CHECK='TRUE';
      ALLOW_CONNECT='TRUE';
    'VSS_BV27':
      PIN_NUMBER='(0,0,0,0,0,0,0,0,0,0,0,0,0,0,0,0,0,0,0,0,0,0,0,0,0,0,0,0,0,0,0,0,0,BV27,0,0,0,0,0,0)';
      PINUSE='POWER';
      NO_LOAD_CHECK='Both';
      NO_IO_CHECK='Both';
      NO_ASSERT_CHECK='TRUE';
      NO_DIR_CHECK='TRUE';
      ALLOW_CONNECT='TRUE';
    'VSS_BV28':
      PIN_NUMBER='(0,0,0,0,0,0,0,0,0,0,0,0,0,0,0,0,0,0,0,0,0,0,0,0,0,0,0,0,0,0,0,0,0,BV28,0,0,0,0,0,0)';
      PINUSE='POWER';
      NO_LOAD_CHECK='Both';
      NO_IO_CHECK='Both';
      NO_ASSERT_CHECK='TRUE';
      NO_DIR_CHECK='TRUE';
      ALLOW_CONNECT='TRUE';
    'VSS_BV29':
      PIN_NUMBER='(0,0,0,0,0,0,0,0,0,0,0,0,0,0,0,0,0,0,0,0,0,0,0,0,0,0,0,0,0,0,0,0,0,BV29,0,0,0,0,0,0)';
      PINUSE='POWER';
      NO_LOAD_CHECK='Both';
      NO_IO_CHECK='Both';
      NO_ASSERT_CHECK='TRUE';
      NO_DIR_CHECK='TRUE';
      ALLOW_CONNECT='TRUE';
    'VSS_BV30':
      PIN_NUMBER='(0,0,0,0,0,0,0,0,0,0,0,0,0,0,0,0,0,0,0,0,0,0,0,0,0,0,0,0,0,0,0,0,0,BV30,0,0,0,0,0,0)';
      PINUSE='POWER';
      NO_LOAD_CHECK='Both';
      NO_IO_CHECK='Both';
      NO_ASSERT_CHECK='TRUE';
      NO_DIR_CHECK='TRUE';
      ALLOW_CONNECT='TRUE';
    'VSS_BV31':
      PIN_NUMBER='(0,0,0,0,0,0,0,0,0,0,0,0,0,0,0,0,0,0,0,0,0,0,0,0,0,0,0,0,0,0,0,0,0,BV31,0,0,0,0,0,0)';
      PINUSE='POWER';
      NO_LOAD_CHECK='Both';
      NO_IO_CHECK='Both';
      NO_ASSERT_CHECK='TRUE';
      NO_DIR_CHECK='TRUE';
      ALLOW_CONNECT='TRUE';
    'VSS_BV32':
      PIN_NUMBER='(0,0,0,0,0,0,0,0,0,0,0,0,0,0,0,0,0,0,0,0,0,0,0,0,0,0,0,0,0,0,0,0,0,BV32,0,0,0,0,0,0)';
      PINUSE='POWER';
      NO_LOAD_CHECK='Both';
      NO_IO_CHECK='Both';
      NO_ASSERT_CHECK='TRUE';
      NO_DIR_CHECK='TRUE';
      ALLOW_CONNECT='TRUE';
    'VSS_BV33':
      PIN_NUMBER='(0,0,0,0,0,0,0,0,0,0,0,0,0,0,0,0,0,0,0,0,0,0,0,0,0,0,0,0,0,0,0,0,0,BV33,0,0,0,0,0,0)';
      PINUSE='POWER';
      NO_LOAD_CHECK='Both';
      NO_IO_CHECK='Both';
      NO_ASSERT_CHECK='TRUE';
      NO_DIR_CHECK='TRUE';
      ALLOW_CONNECT='TRUE';
    'VSS_BV34':
      PIN_NUMBER='(0,0,0,0,0,0,0,0,0,0,0,0,0,0,0,0,0,0,0,0,0,0,0,0,0,0,0,0,0,0,0,0,0,BV34,0,0,0,0,0,0)';
      PINUSE='POWER';
      NO_LOAD_CHECK='Both';
      NO_IO_CHECK='Both';
      NO_ASSERT_CHECK='TRUE';
      NO_DIR_CHECK='TRUE';
      ALLOW_CONNECT='TRUE';
    'VSS_BV39':
      PIN_NUMBER='(0,0,0,0,0,0,0,0,0,0,0,0,0,0,0,0,0,0,0,0,0,0,0,0,0,0,0,0,0,0,0,0,0,BV39,0,0,0,0,0,0)';
      PINUSE='POWER';
      NO_LOAD_CHECK='Both';
      NO_IO_CHECK='Both';
      NO_ASSERT_CHECK='TRUE';
      NO_DIR_CHECK='TRUE';
      ALLOW_CONNECT='TRUE';
    'VSS_BV43':
      PIN_NUMBER='(0,0,0,0,0,0,0,0,0,0,0,0,0,0,0,0,0,0,0,0,0,0,0,0,0,0,0,0,0,0,0,0,0,BV43,0,0,0,0,0,0)';
      PINUSE='POWER';
      NO_LOAD_CHECK='Both';
      NO_IO_CHECK='Both';
      NO_ASSERT_CHECK='TRUE';
      NO_DIR_CHECK='TRUE';
      ALLOW_CONNECT='TRUE';
    'VSS_BV44':
      PIN_NUMBER='(0,0,0,0,0,0,0,0,0,0,0,0,0,0,0,0,0,0,0,0,0,0,0,0,0,0,0,0,0,0,0,0,0,BV44,0,0,0,0,0,0)';
      PINUSE='POWER';
      NO_LOAD_CHECK='Both';
      NO_IO_CHECK='Both';
      NO_ASSERT_CHECK='TRUE';
      NO_DIR_CHECK='TRUE';
      ALLOW_CONNECT='TRUE';
    'VSS_BV45':
      PIN_NUMBER='(0,0,0,0,0,0,0,0,0,0,0,0,0,0,0,0,0,0,0,0,0,0,0,0,0,0,0,0,0,0,0,0,0,BV45,0,0,0,0,0,0)';
      PINUSE='POWER';
      NO_LOAD_CHECK='Both';
      NO_IO_CHECK='Both';
      NO_ASSERT_CHECK='TRUE';
      NO_DIR_CHECK='TRUE';
      ALLOW_CONNECT='TRUE';
    'MLB_DQS_L9':
      PIN_NUMBER='(0,0,0,0,0,0,0,0,0,0,0,0,0,0,0,0,0,0,0,0,0,0,0,0,0,0,0,0,0,0,0,0,0,0,BW9,0,0,0,0,0)';
      BIDIRECTIONAL='TRUE';
      INPUT_LOAD='(-0.01,0.01)';
      OUTPUT_LOAD='(1.0,-1.0)';
    'MLB_DQS_H5':
      PIN_NUMBER='(0,0,0,0,0,0,0,0,0,0,0,0,0,0,0,0,0,0,0,0,0,0,0,0,0,0,0,0,0,0,0,0,0,0,CF11,0,0,0,0,0)';
      BIDIRECTIONAL='TRUE';
      INPUT_LOAD='(-0.01,0.01)';
      OUTPUT_LOAD='(1.0,-1.0)';
    'MLB_DATA4':
      PIN_NUMBER='(0,0,0,0,0,0,0,0,0,0,0,0,0,0,0,0,0,0,0,0,0,0,0,0,0,0,0,0,0,0,0,0,0,0,CF9,0,0,0,0,0)';
      BIDIRECTIONAL='TRUE';
      INPUT_LOAD='(-0.01,0.01)';
      OUTPUT_LOAD='(1.0,-1.0)';
    'MLB_CA1':
      PIN_NUMBER='(0,0,0,0,0,0,0,0,0,0,0,0,0,0,0,0,0,0,0,0,0,0,0,0,0,0,0,0,0,0,0,0,0,0,BH11,0,0,0,0,0)';
      OUTPUT_LOAD='(1.0,-1.0)';
    'MLA_DATA22':
      PIN_NUMBER='(0,0,0,0,0,0,0,0,0,0,0,0,0,0,0,0,0,0,0,0,0,0,0,0,0,0,0,0,0,0,0,0,0,0,AB9,0,0,0,0,0)';
      BIDIRECTIONAL='TRUE';
      INPUT_LOAD='(-0.01,0.01)';
      OUTPUT_LOAD='(1.0,-1.0)';
    'MLA_DATA11':
      PIN_NUMBER='(0,0,0,0,0,0,0,0,0,0,0,0,0,0,0,0,0,0,0,0,0,0,0,0,0,0,0,0,0,0,0,0,0,0,N10,0,0,0,0,0)';
      BIDIRECTIONAL='TRUE';
      INPUT_LOAD='(-0.01,0.01)';
      OUTPUT_LOAD='(1.0,-1.0)';
    'MLA_DATA5':
      PIN_NUMBER='(0,0,0,0,0,0,0,0,0,0,0,0,0,0,0,0,0,0,0,0,0,0,0,0,0,0,0,0,0,0,0,0,0,0,K11,0,0,0,0,0)';
      BIDIRECTIONAL='TRUE';
      INPUT_LOAD='(-0.01,0.01)';
      OUTPUT_LOAD='(1.0,-1.0)';
    'MLA_CHECK2':
      PIN_NUMBER='(0,0,0,0,0,0,0,0,0,0,0,0,0,0,0,0,0,0,0,0,0,0,0,0,0,0,0,0,0,0,0,0,0,0,AK9,0,0,0,0,0)';
      BIDIRECTIONAL='TRUE';
      INPUT_LOAD='(-0.01,0.01)';
      OUTPUT_LOAD='(1.0,-1.0)';
    'MLA_CA2':
      PIN_NUMBER='(0,0,0,0,0,0,0,0,0,0,0,0,0,0,0,0,0,0,0,0,0,0,0,0,0,0,0,0,0,0,0,0,0,0,AY11,0,0,0,0,0)';
      OUTPUT_LOAD='(1.0,-1.0)';
    'ML_RESET_L':
      PIN_NUMBER='(0,0,0,0,0,0,0,0,0,0,0,0,0,0,0,0,0,0,0,0,0,0,0,0,0,0,0,0,0,0,0,0,0,0,AU10,0,0,0,0,0)';
      OUTPUT_LOAD='(1.0,-1.0)';
    'MLB_DQS_H6':
      PIN_NUMBER='(0,0,0,0,0,0,0,0,0,0,0,0,0,0,0,0,0,0,0,0,0,0,0,0,0,0,0,0,0,0,0,0,0,0,CM11,0,0,0,0,0)';
      BIDIRECTIONAL='TRUE';
      INPUT_LOAD='(-0.01,0.01)';
      OUTPUT_LOAD='(1.0,-1.0)';
    'MLB_DATA5':
      PIN_NUMBER='(0,0,0,0,0,0,0,0,0,0,0,0,0,0,0,0,0,0,0,0,0,0,0,0,0,0,0,0,0,0,0,0,0,0,CG10,0,0,0,0,0)';
      BIDIRECTIONAL='TRUE';
      INPUT_LOAD='(-0.01,0.01)';
      OUTPUT_LOAD='(1.0,-1.0)';
    'MLB_CA2':
      PIN_NUMBER='(0,0,0,0,0,0,0,0,0,0,0,0,0,0,0,0,0,0,0,0,0,0,0,0,0,0,0,0,0,0,0,0,0,0,BH9,0,0,0,0,0)';
      OUTPUT_LOAD='(1.0,-1.0)';
    'MLB0_CS_L0':
      PIN_NUMBER='(0,0,0,0,0,0,0,0,0,0,0,0,0,0,0,0,0,0,0,0,0,0,0,0,0,0,0,0,0,0,0,0,0,0,BM11,0,0,0,0,0)';
      OUTPUT_LOAD='(1.0,-1.0)';
    'MLA_DATA23':
      PIN_NUMBER='(0,0,0,0,0,0,0,0,0,0,0,0,0,0,0,0,0,0,0,0,0,0,0,0,0,0,0,0,0,0,0,0,0,0,AC10,0,0,0,0,0)';
      BIDIRECTIONAL='TRUE';
      INPUT_LOAD='(-0.01,0.01)';
      OUTPUT_LOAD='(1.0,-1.0)';
    'MLA_DATA12':
      PIN_NUMBER='(0,0,0,0,0,0,0,0,0,0,0,0,0,0,0,0,0,0,0,0,0,0,0,0,0,0,0,0,0,0,0,0,0,0,R9,0,0,0,0,0)';
      BIDIRECTIONAL='TRUE';
      INPUT_LOAD='(-0.01,0.01)';
      OUTPUT_LOAD='(1.0,-1.0)';
    'MLA_DATA6':
      PIN_NUMBER='(0,0,0,0,0,0,0,0,0,0,0,0,0,0,0,0,0,0,0,0,0,0,0,0,0,0,0,0,0,0,0,0,0,0,K9,0,0,0,0,0)';
      BIDIRECTIONAL='TRUE';
      INPUT_LOAD='(-0.01,0.01)';
      OUTPUT_LOAD='(1.0,-1.0)';
    'MLA_CHECK3':
      PIN_NUMBER='(0,0,0,0,0,0,0,0,0,0,0,0,0,0,0,0,0,0,0,0,0,0,0,0,0,0,0,0,0,0,0,0,0,0,AL10,0,0,0,0,0)';
      BIDIRECTIONAL='TRUE';
      INPUT_LOAD='(-0.01,0.01)';
      OUTPUT_LOAD='(1.0,-1.0)';
    'MLA_CA3':
      PIN_NUMBER='(0,0,0,0,0,0,0,0,0,0,0,0,0,0,0,0,0,0,0,0,0,0,0,0,0,0,0,0,0,0,0,0,0,0,BA10,0,0,0,0,0)';
      OUTPUT_LOAD='(1.0,-1.0)';
    'MLB_DQS_H7':
      PIN_NUMBER='(0,0,0,0,0,0,0,0,0,0,0,0,0,0,0,0,0,0,0,0,0,0,0,0,0,0,0,0,0,0,0,0,0,0,CV11,0,0,0,0,0)';
      BIDIRECTIONAL='TRUE';
      INPUT_LOAD='(-0.01,0.01)';
      OUTPUT_LOAD='(1.0,-1.0)';
    'MLB_DATA6':
      PIN_NUMBER='(0,0,0,0,0,0,0,0,0,0,0,0,0,0,0,0,0,0,0,0,0,0,0,0,0,0,0,0,0,0,0,0,0,0,CG9,0,0,0,0,0)';
      BIDIRECTIONAL='TRUE';
      INPUT_LOAD='(-0.01,0.01)';
      OUTPUT_LOAD='(1.0,-1.0)';
    'MLB_CA3':
      PIN_NUMBER='(0,0,0,0,0,0,0,0,0,0,0,0,0,0,0,0,0,0,0,0,0,0,0,0,0,0,0,0,0,0,0,0,0,0,BJ9,0,0,0,0,0)';
      OUTPUT_LOAD='(1.0,-1.0)';
    'MLB1_CS_L0':
      PIN_NUMBER='(0,0,0,0,0,0,0,0,0,0,0,0,0,0,0,0,0,0,0,0,0,0,0,0,0,0,0,0,0,0,0,0,0,0,BL9,0,0,0,0,0)';
      OUTPUT_LOAD='(1.0,-1.0)';
    'MLB0_CS_L1':
      PIN_NUMBER='(0,0,0,0,0,0,0,0,0,0,0,0,0,0,0,0,0,0,0,0,0,0,0,0,0,0,0,0,0,0,0,0,0,0,BN9,0,0,0,0,0)';
      OUTPUT_LOAD='(1.0,-1.0)';
    'MLA_DQS_L0':
      PIN_NUMBER='(0,0,0,0,0,0,0,0,0,0,0,0,0,0,0,0,0,0,0,0,0,0,0,0,0,0,0,0,0,0,0,0,0,0,H9,0,0,0,0,0)';
      BIDIRECTIONAL='TRUE';
      INPUT_LOAD='(-0.01,0.01)';
      OUTPUT_LOAD='(1.0,-1.0)';
    'MLA_DATA24':
      PIN_NUMBER='(0,0,0,0,0,0,0,0,0,0,0,0,0,0,0,0,0,0,0,0,0,0,0,0,0,0,0,0,0,0,0,0,0,0,AC9,0,0,0,0,0)';
      BIDIRECTIONAL='TRUE';
      INPUT_LOAD='(-0.01,0.01)';
      OUTPUT_LOAD='(1.0,-1.0)';
    'MLA_DATA13':
      PIN_NUMBER='(0,0,0,0,0,0,0,0,0,0,0,0,0,0,0,0,0,0,0,0,0,0,0,0,0,0,0,0,0,0,0,0,0,0,T11,0,0,0,0,0)';
      BIDIRECTIONAL='TRUE';
      INPUT_LOAD='(-0.01,0.01)';
      OUTPUT_LOAD='(1.0,-1.0)';
    'MLA_DATA7':
      PIN_NUMBER='(0,0,0,0,0,0,0,0,0,0,0,0,0,0,0,0,0,0,0,0,0,0,0,0,0,0,0,0,0,0,0,0,0,0,L10,0,0,0,0,0)';
      BIDIRECTIONAL='TRUE';
      INPUT_LOAD='(-0.01,0.01)';
      OUTPUT_LOAD='(1.0,-1.0)';
    'MLA_CHECK4':
      PIN_NUMBER='(0,0,0,0,0,0,0,0,0,0,0,0,0,0,0,0,0,0,0,0,0,0,0,0,0,0,0,0,0,0,0,0,0,0,AN9,0,0,0,0,0)';
      BIDIRECTIONAL='TRUE';
      INPUT_LOAD='(-0.01,0.01)';
      OUTPUT_LOAD='(1.0,-1.0)';
    'MLA_CA4':
      PIN_NUMBER='(0,0,0,0,0,0,0,0,0,0,0,0,0,0,0,0,0,0,0,0,0,0,0,0,0,0,0,0,0,0,0,0,0,0,BA9,0,0,0,0,0)';
      OUTPUT_LOAD='(1.0,-1.0)';
    'MLB_DQS_H8':
      PIN_NUMBER='(0,0,0,0,0,0,0,0,0,0,0,0,0,0,0,0,0,0,0,0,0,0,0,0,0,0,0,0,0,0,0,0,0,0,DD11,0,0,0,0,0)';
      BIDIRECTIONAL='TRUE';
      INPUT_LOAD='(-0.01,0.01)';
      OUTPUT_LOAD='(1.0,-1.0)';
    'MLB_DATA30':
      PIN_NUMBER='(0,0,0,0,0,0,0,0,0,0,0,0,0,0,0,0,0,0,0,0,0,0,0,0,0,0,0,0,0,0,0,0,0,0,DE9,0,0,0,0,0)';
      BIDIRECTIONAL='TRUE';
      INPUT_LOAD='(-0.01,0.01)';
      OUTPUT_LOAD='(1.0,-1.0)';
    'MLB_DATA7':
      PIN_NUMBER='(0,0,0,0,0,0,0,0,0,0,0,0,0,0,0,0,0,0,0,0,0,0,0,0,0,0,0,0,0,0,0,0,0,0,CH11,0,0,0,0,0)';
      BIDIRECTIONAL='TRUE';
      INPUT_LOAD='(-0.01,0.01)';
      OUTPUT_LOAD='(1.0,-1.0)';
    'MLB_CA4':
      PIN_NUMBER='(0,0,0,0,0,0,0,0,0,0,0,0,0,0,0,0,0,0,0,0,0,0,0,0,0,0,0,0,0,0,0,0,0,0,BJ10,0,0,0,0,0)';
      OUTPUT_LOAD='(1.0,-1.0)';
    'MLB1_CS_L1':
      PIN_NUMBER='(0,0,0,0,0,0,0,0,0,0,0,0,0,0,0,0,0,0,0,0,0,0,0,0,0,0,0,0,0,0,0,0,0,0,BM9,0,0,0,0,0)';
      OUTPUT_LOAD='(1.0,-1.0)';
    'MLA_DQS_L1':
      PIN_NUMBER='(0,0,0,0,0,0,0,0,0,0,0,0,0,0,0,0,0,0,0,0,0,0,0,0,0,0,0,0,0,0,0,0,0,0,P9,0,0,0,0,0)';
      BIDIRECTIONAL='TRUE';
      INPUT_LOAD='(-0.01,0.01)';
      OUTPUT_LOAD='(1.0,-1.0)';
    'MLA_DATA25':
      PIN_NUMBER='(0,0,0,0,0,0,0,0,0,0,0,0,0,0,0,0,0,0,0,0,0,0,0,0,0,0,0,0,0,0,0,0,0,0,AD11,0,0,0,0,0)';
      BIDIRECTIONAL='TRUE';
      INPUT_LOAD='(-0.01,0.01)';
      OUTPUT_LOAD='(1.0,-1.0)';
    'MLA_DATA14':
      PIN_NUMBER='(0,0,0,0,0,0,0,0,0,0,0,0,0,0,0,0,0,0,0,0,0,0,0,0,0,0,0,0,0,0,0,0,0,0,T9,0,0,0,0,0)';
      BIDIRECTIONAL='TRUE';
      INPUT_LOAD='(-0.01,0.01)';
      OUTPUT_LOAD='(1.0,-1.0)';
    'MLA_DATA8':
      PIN_NUMBER='(0,0,0,0,0,0,0,0,0,0,0,0,0,0,0,0,0,0,0,0,0,0,0,0,0,0,0,0,0,0,0,0,0,0,L9,0,0,0,0,0)';
      BIDIRECTIONAL='TRUE';
      INPUT_LOAD='(-0.01,0.01)';
      OUTPUT_LOAD='(1.0,-1.0)';
    'MLA_CHECK5':
      PIN_NUMBER='(0,0,0,0,0,0,0,0,0,0,0,0,0,0,0,0,0,0,0,0,0,0,0,0,0,0,0,0,0,0,0,0,0,0,AP11,0,0,0,0,0)';
      BIDIRECTIONAL='TRUE';
      INPUT_LOAD='(-0.01,0.01)';
      OUTPUT_LOAD='(1.0,-1.0)';
    'MLA_CA5':
      PIN_NUMBER='(0,0,0,0,0,0,0,0,0,0,0,0,0,0,0,0,0,0,0,0,0,0,0,0,0,0,0,0,0,0,0,0,0,0,BB9,0,0,0,0,0)';
      OUTPUT_LOAD='(1.0,-1.0)';
    'MLB_DQS_H9':
      PIN_NUMBER='(0,0,0,0,0,0,0,0,0,0,0,0,0,0,0,0,0,0,0,0,0,0,0,0,0,0,0,0,0,0,0,0,0,0,BV9,0,0,0,0,0)';
      BIDIRECTIONAL='TRUE';
      INPUT_LOAD='(-0.01,0.01)';
      OUTPUT_LOAD='(1.0,-1.0)';
    'MLB_DATA31':
      PIN_NUMBER='(0,0,0,0,0,0,0,0,0,0,0,0,0,0,0,0,0,0,0,0,0,0,0,0,0,0,0,0,0,0,0,0,0,0,DF9,0,0,0,0,0)';
      BIDIRECTIONAL='TRUE';
      INPUT_LOAD='(-0.01,0.01)';
      OUTPUT_LOAD='(1.0,-1.0)';
    'MLB_DATA20':
      PIN_NUMBER='(0,0,0,0,0,0,0,0,0,0,0,0,0,0,0,0,0,0,0,0,0,0,0,0,0,0,0,0,0,0,0,0,0,0,CV9,0,0,0,0,0)';
      BIDIRECTIONAL='TRUE';
      INPUT_LOAD='(-0.01,0.01)';
      OUTPUT_LOAD='(1.0,-1.0)';
    'MLB_DATA8':
      PIN_NUMBER='(0,0,0,0,0,0,0,0,0,0,0,0,0,0,0,0,0,0,0,0,0,0,0,0,0,0,0,0,0,0,0,0,0,0,CH9,0,0,0,0,0)';
      BIDIRECTIONAL='TRUE';
      INPUT_LOAD='(-0.01,0.01)';
      OUTPUT_LOAD='(1.0,-1.0)';
    'MLB_CHECK0':
      PIN_NUMBER='(0,0,0,0,0,0,0,0,0,0,0,0,0,0,0,0,0,0,0,0,0,0,0,0,0,0,0,0,0,0,0,0,0,0,BY9,0,0,0,0,0)';
      BIDIRECTIONAL='TRUE';
      INPUT_LOAD='(-0.01,0.01)';
      OUTPUT_LOAD='(1.0,-1.0)';
    'MLB_CA5':
      PIN_NUMBER='(0,0,0,0,0,0,0,0,0,0,0,0,0,0,0,0,0,0,0,0,0,0,0,0,0,0,0,0,0,0,0,0,0,0,BK11,0,0,0,0,0)';
      OUTPUT_LOAD='(1.0,-1.0)';
    'MLA_DQS_L2':
      PIN_NUMBER='(0,0,0,0,0,0,0,0,0,0,0,0,0,0,0,0,0,0,0,0,0,0,0,0,0,0,0,0,0,0,0,0,0,0,Y9,0,0,0,0,0)';
      BIDIRECTIONAL='TRUE';
      INPUT_LOAD='(-0.01,0.01)';
      OUTPUT_LOAD='(1.0,-1.0)';
    'MLA_DATA26':
      PIN_NUMBER='(0,0,0,0,0,0,0,0,0,0,0,0,0,0,0,0,0,0,0,0,0,0,0,0,0,0,0,0,0,0,0,0,0,0,AD9,0,0,0,0,0)';
      BIDIRECTIONAL='TRUE';
      INPUT_LOAD='(-0.01,0.01)';
      OUTPUT_LOAD='(1.0,-1.0)';
    'MLA_DATA15':
      PIN_NUMBER='(0,0,0,0,0,0,0,0,0,0,0,0,0,0,0,0,0,0,0,0,0,0,0,0,0,0,0,0,0,0,0,0,0,0,U10,0,0,0,0,0)';
      BIDIRECTIONAL='TRUE';
      INPUT_LOAD='(-0.01,0.01)';
      OUTPUT_LOAD='(1.0,-1.0)';
    'MLA_DATA9':
      PIN_NUMBER='(0,0,0,0,0,0,0,0,0,0,0,0,0,0,0,0,0,0,0,0,0,0,0,0,0,0,0,0,0,0,0,0,0,0,M11,0,0,0,0,0)';
      BIDIRECTIONAL='TRUE';
      INPUT_LOAD='(-0.01,0.01)';
      OUTPUT_LOAD='(1.0,-1.0)';
    'MLA_CHECK6':
      PIN_NUMBER='(0,0,0,0,0,0,0,0,0,0,0,0,0,0,0,0,0,0,0,0,0,0,0,0,0,0,0,0,0,0,0,0,0,0,AP9,0,0,0,0,0)';
      BIDIRECTIONAL='TRUE';
      INPUT_LOAD='(-0.01,0.01)';
      OUTPUT_LOAD='(1.0,-1.0)';
    'MLA_CA6':
      PIN_NUMBER='(0,0,0,0,0,0,0,0,0,0,0,0,0,0,0,0,0,0,0,0,0,0,0,0,0,0,0,0,0,0,0,0,0,0,BB11,0,0,0,0,0)';
      OUTPUT_LOAD='(1.0,-1.0)';
    'MLA0_RSP_L':
      PIN_NUMBER='(0,0,0,0,0,0,0,0,0,0,0,0,0,0,0,0,0,0,0,0,0,0,0,0,0,0,0,0,0,0,0,0,0,0,BN10,0,0,0,0,0)';
      INPUT_LOAD='(-0.01,0.01)';
    'MLB_DATA21':
      PIN_NUMBER='(0,0,0,0,0,0,0,0,0,0,0,0,0,0,0,0,0,0,0,0,0,0,0,0,0,0,0,0,0,0,0,0,0,0,CW10,0,0,0,0,0)';
      BIDIRECTIONAL='TRUE';
      INPUT_LOAD='(-0.01,0.01)';
      OUTPUT_LOAD='(1.0,-1.0)';
    'MLB_DATA10':
      PIN_NUMBER='(0,0,0,0,0,0,0,0,0,0,0,0,0,0,0,0,0,0,0,0,0,0,0,0,0,0,0,0,0,0,0,0,0,0,CJ9,0,0,0,0,0)';
      BIDIRECTIONAL='TRUE';
      INPUT_LOAD='(-0.01,0.01)';
      OUTPUT_LOAD='(1.0,-1.0)';
    'MLB_DATA9':
      PIN_NUMBER='(0,0,0,0,0,0,0,0,0,0,0,0,0,0,0,0,0,0,0,0,0,0,0,0,0,0,0,0,0,0,0,0,0,0,CJ10,0,0,0,0,0)';
      BIDIRECTIONAL='TRUE';
      INPUT_LOAD='(-0.01,0.01)';
      OUTPUT_LOAD='(1.0,-1.0)';
    'MLB_CHECK1':
      PIN_NUMBER='(0,0,0,0,0,0,0,0,0,0,0,0,0,0,0,0,0,0,0,0,0,0,0,0,0,0,0,0,0,0,0,0,0,0,CA10,0,0,0,0,0)';
      BIDIRECTIONAL='TRUE';
      INPUT_LOAD='(-0.01,0.01)';
      OUTPUT_LOAD='(1.0,-1.0)';
    'MLB_CA6':
      PIN_NUMBER='(0,0,0,0,0,0,0,0,0,0,0,0,0,0,0,0,0,0,0,0,0,0,0,0,0,0,0,0,0,0,0,0,0,0,BK9,0,0,0,0,0)';
      OUTPUT_LOAD='(1.0,-1.0)';
    'MLA_DQS_L3':
      PIN_NUMBER='(0,0,0,0,0,0,0,0,0,0,0,0,0,0,0,0,0,0,0,0,0,0,0,0,0,0,0,0,0,0,0,0,0,0,AF9,0,0,0,0,0)';
      BIDIRECTIONAL='TRUE';
      INPUT_LOAD='(-0.01,0.01)';
      OUTPUT_LOAD='(1.0,-1.0)';
    'MLA_DATA27':
      PIN_NUMBER='(0,0,0,0,0,0,0,0,0,0,0,0,0,0,0,0,0,0,0,0,0,0,0,0,0,0,0,0,0,0,0,0,0,0,AE10,0,0,0,0,0)';
      BIDIRECTIONAL='TRUE';
      INPUT_LOAD='(-0.01,0.01)';
      OUTPUT_LOAD='(1.0,-1.0)';
    'MLA_DATA16':
      PIN_NUMBER='(0,0,0,0,0,0,0,0,0,0,0,0,0,0,0,0,0,0,0,0,0,0,0,0,0,0,0,0,0,0,0,0,0,0,U9,0,0,0,0,0)';
      BIDIRECTIONAL='TRUE';
      INPUT_LOAD='(-0.01,0.01)';
      OUTPUT_LOAD='(1.0,-1.0)';
    'MLA_CHECK7':
      PIN_NUMBER='(0,0,0,0,0,0,0,0,0,0,0,0,0,0,0,0,0,0,0,0,0,0,0,0,0,0,0,0,0,0,0,0,0,0,AR10,0,0,0,0,0)';
      BIDIRECTIONAL='TRUE';
      INPUT_LOAD='(-0.01,0.01)';
      OUTPUT_LOAD='(1.0,-1.0)';
    'MLA1_RSP_L':
      PIN_NUMBER='(0,0,0,0,0,0,0,0,0,0,0,0,0,0,0,0,0,0,0,0,0,0,0,0,0,0,0,0,0,0,0,0,0,0,BP11,0,0,0,0,0)';
      INPUT_LOAD='(-0.01,0.01)';
    'ML_ALERT_L':
      PIN_NUMBER='(0,0,0,0,0,0,0,0,0,0,0,0,0,0,0,0,0,0,0,0,0,0,0,0,0,0,0,0,0,0,0,0,0,0,AT11,0,0,0,0,0)';
      INPUT_LOAD='(-0.01,0.01)';
    'MLB_DATA22':
      PIN_NUMBER='(0,0,0,0,0,0,0,0,0,0,0,0,0,0,0,0,0,0,0,0,0,0,0,0,0,0,0,0,0,0,0,0,0,0,CW9,0,0,0,0,0)';
      BIDIRECTIONAL='TRUE';
      INPUT_LOAD='(-0.01,0.01)';
      OUTPUT_LOAD='(1.0,-1.0)';
    'MLB_DATA11':
      PIN_NUMBER='(0,0,0,0,0,0,0,0,0,0,0,0,0,0,0,0,0,0,0,0,0,0,0,0,0,0,0,0,0,0,0,0,0,0,CK11,0,0,0,0,0)';
      BIDIRECTIONAL='TRUE';
      INPUT_LOAD='(-0.01,0.01)';
      OUTPUT_LOAD='(1.0,-1.0)';
    'MLB_CHECK2':
      PIN_NUMBER='(0,0,0,0,0,0,0,0,0,0,0,0,0,0,0,0,0,0,0,0,0,0,0,0,0,0,0,0,0,0,0,0,0,0,CA9,0,0,0,0,0)';
      BIDIRECTIONAL='TRUE';
      INPUT_LOAD='(-0.01,0.01)';
      OUTPUT_LOAD='(1.0,-1.0)';
    'MLA_DQS_L4':
      PIN_NUMBER='(0,0,0,0,0,0,0,0,0,0,0,0,0,0,0,0,0,0,0,0,0,0,0,0,0,0,0,0,0,0,0,0,0,0,AM9,0,0,0,0,0)';
      BIDIRECTIONAL='TRUE';
      INPUT_LOAD='(-0.01,0.01)';
      OUTPUT_LOAD='(1.0,-1.0)';
    'MLA_DQS_H0':
      PIN_NUMBER='(0,0,0,0,0,0,0,0,0,0,0,0,0,0,0,0,0,0,0,0,0,0,0,0,0,0,0,0,0,0,0,0,0,0,G9,0,0,0,0,0)';
      BIDIRECTIONAL='TRUE';
      INPUT_LOAD='(-0.01,0.01)';
      OUTPUT_LOAD='(1.0,-1.0)';
    'MLA_DATA28':
      PIN_NUMBER='(0,0,0,0,0,0,0,0,0,0,0,0,0,0,0,0,0,0,0,0,0,0,0,0,0,0,0,0,0,0,0,0,0,0,AG9,0,0,0,0,0)';
      BIDIRECTIONAL='TRUE';
      INPUT_LOAD='(-0.01,0.01)';
      OUTPUT_LOAD='(1.0,-1.0)';
    'MLA_DATA17':
      PIN_NUMBER='(0,0,0,0,0,0,0,0,0,0,0,0,0,0,0,0,0,0,0,0,0,0,0,0,0,0,0,0,0,0,0,0,0,0,V11,0,0,0,0,0)';
      BIDIRECTIONAL='TRUE';
      INPUT_LOAD='(-0.01,0.01)';
      OUTPUT_LOAD='(1.0,-1.0)';
    'MLB_DATA23':
      PIN_NUMBER='(0,0,0,0,0,0,0,0,0,0,0,0,0,0,0,0,0,0,0,0,0,0,0,0,0,0,0,0,0,0,0,0,0,0,CY11,0,0,0,0,0)';
      BIDIRECTIONAL='TRUE';
      INPUT_LOAD='(-0.01,0.01)';
      OUTPUT_LOAD='(1.0,-1.0)';
    'MLB_DATA12':
      PIN_NUMBER='(0,0,0,0,0,0,0,0,0,0,0,0,0,0,0,0,0,0,0,0,0,0,0,0,0,0,0,0,0,0,0,0,0,0,CM9,0,0,0,0,0)';
      BIDIRECTIONAL='TRUE';
      INPUT_LOAD='(-0.01,0.01)';
      OUTPUT_LOAD='(1.0,-1.0)';
    'MLB_CHECK3':
      PIN_NUMBER='(0,0,0,0,0,0,0,0,0,0,0,0,0,0,0,0,0,0,0,0,0,0,0,0,0,0,0,0,0,0,0,0,0,0,CB11,0,0,0,0,0)';
      BIDIRECTIONAL='TRUE';
      INPUT_LOAD='(-0.01,0.01)';
      OUTPUT_LOAD='(1.0,-1.0)';
    'MLA_DQS_L5':
      PIN_NUMBER='(0,0,0,0,0,0,0,0,0,0,0,0,0,0,0,0,0,0,0,0,0,0,0,0,0,0,0,0,0,0,0,0,0,0,H11,0,0,0,0,0)';
      BIDIRECTIONAL='TRUE';
      INPUT_LOAD='(-0.01,0.01)';
      OUTPUT_LOAD='(1.0,-1.0)';
    'MLA_DQS_H1':
      PIN_NUMBER='(0,0,0,0,0,0,0,0,0,0,0,0,0,0,0,0,0,0,0,0,0,0,0,0,0,0,0,0,0,0,0,0,0,0,N9,0,0,0,0,0)';
      BIDIRECTIONAL='TRUE';
      INPUT_LOAD='(-0.01,0.01)';
      OUTPUT_LOAD='(1.0,-1.0)';
    'MLA_DATA29':
      PIN_NUMBER='(0,0,0,0,0,0,0,0,0,0,0,0,0,0,0,0,0,0,0,0,0,0,0,0,0,0,0,0,0,0,0,0,0,0,AH11,0,0,0,0,0)';
      BIDIRECTIONAL='TRUE';
      INPUT_LOAD='(-0.01,0.01)';
      OUTPUT_LOAD='(1.0,-1.0)';
    'MLA_DATA18':
      PIN_NUMBER='(0,0,0,0,0,0,0,0,0,0,0,0,0,0,0,0,0,0,0,0,0,0,0,0,0,0,0,0,0,0,0,0,0,0,V9,0,0,0,0,0)';
      BIDIRECTIONAL='TRUE';
      INPUT_LOAD='(-0.01,0.01)';
      OUTPUT_LOAD='(1.0,-1.0)';
    'ML0_CLK_H':
      PIN_NUMBER='(0,0,0,0,0,0,0,0,0,0,0,0,0,0,0,0,0,0,0,0,0,0,0,0,0,0,0,0,0,0,0,0,0,0,BC9,0,0,0,0,0)';
      OUTPUT_LOAD='(1.0,-1.0)';
    'MLB_DQS_L0':
      PIN_NUMBER='(0,0,0,0,0,0,0,0,0,0,0,0,0,0,0,0,0,0,0,0,0,0,0,0,0,0,0,0,0,0,0,0,0,0,CE9,0,0,0,0,0)';
      BIDIRECTIONAL='TRUE';
      INPUT_LOAD='(-0.01,0.01)';
      OUTPUT_LOAD='(1.0,-1.0)';
    'MLB_DATA24':
      PIN_NUMBER='(0,0,0,0,0,0,0,0,0,0,0,0,0,0,0,0,0,0,0,0,0,0,0,0,0,0,0,0,0,0,0,0,0,0,CY9,0,0,0,0,0)';
      BIDIRECTIONAL='TRUE';
      INPUT_LOAD='(-0.01,0.01)';
      OUTPUT_LOAD='(1.0,-1.0)';
    'MLB_DATA13':
      PIN_NUMBER='(0,0,0,0,0,0,0,0,0,0,0,0,0,0,0,0,0,0,0,0,0,0,0,0,0,0,0,0,0,0,0,0,0,0,CN10,0,0,0,0,0)';
      BIDIRECTIONAL='TRUE';
      INPUT_LOAD='(-0.01,0.01)';
      OUTPUT_LOAD='(1.0,-1.0)';
    'MLB_CHECK4':
      PIN_NUMBER='(0,0,0,0,0,0,0,0,0,0,0,0,0,0,0,0,0,0,0,0,0,0,0,0,0,0,0,0,0,0,0,0,0,0,BT9,0,0,0,0,0)';
      BIDIRECTIONAL='TRUE';
      INPUT_LOAD='(-0.01,0.01)';
      OUTPUT_LOAD='(1.0,-1.0)';
    'MLA_DQS_L6':
      PIN_NUMBER='(0,0,0,0,0,0,0,0,0,0,0,0,0,0,0,0,0,0,0,0,0,0,0,0,0,0,0,0,0,0,0,0,0,0,P11,0,0,0,0,0)';
      BIDIRECTIONAL='TRUE';
      INPUT_LOAD='(-0.01,0.01)';
      OUTPUT_LOAD='(1.0,-1.0)';
    'MLA_DQS_H2':
      PIN_NUMBER='(0,0,0,0,0,0,0,0,0,0,0,0,0,0,0,0,0,0,0,0,0,0,0,0,0,0,0,0,0,0,0,0,0,0,W9,0,0,0,0,0)';
      BIDIRECTIONAL='TRUE';
      INPUT_LOAD='(-0.01,0.01)';
      OUTPUT_LOAD='(1.0,-1.0)';
    'MLA_DATA19':
      PIN_NUMBER='(0,0,0,0,0,0,0,0,0,0,0,0,0,0,0,0,0,0,0,0,0,0,0,0,0,0,0,0,0,0,0,0,0,0,W10,0,0,0,0,0)';
      BIDIRECTIONAL='TRUE';
      INPUT_LOAD='(-0.01,0.01)';
      OUTPUT_LOAD='(1.0,-1.0)';
    'ML1_CLK_H':
      PIN_NUMBER='(0,0,0,0,0,0,0,0,0,0,0,0,0,0,0,0,0,0,0,0,0,0,0,0,0,0,0,0,0,0,0,0,0,0,BF9,0,0,0,0,0)';
      OUTPUT_LOAD='(1.0,-1.0)';
    'MLB_DQS_L1':
      PIN_NUMBER='(0,0,0,0,0,0,0,0,0,0,0,0,0,0,0,0,0,0,0,0,0,0,0,0,0,0,0,0,0,0,0,0,0,0,CL9,0,0,0,0,0)';
      BIDIRECTIONAL='TRUE';
      INPUT_LOAD='(-0.01,0.01)';
      OUTPUT_LOAD='(1.0,-1.0)';
    'MLB_DATA25':
      PIN_NUMBER='(0,0,0,0,0,0,0,0,0,0,0,0,0,0,0,0,0,0,0,0,0,0,0,0,0,0,0,0,0,0,0,0,0,0,DA10,0,0,0,0,0)';
      BIDIRECTIONAL='TRUE';
      INPUT_LOAD='(-0.01,0.01)';
      OUTPUT_LOAD='(1.0,-1.0)';
    'MLB_DATA14':
      PIN_NUMBER='(0,0,0,0,0,0,0,0,0,0,0,0,0,0,0,0,0,0,0,0,0,0,0,0,0,0,0,0,0,0,0,0,0,0,CN9,0,0,0,0,0)';
      BIDIRECTIONAL='TRUE';
      INPUT_LOAD='(-0.01,0.01)';
      OUTPUT_LOAD='(1.0,-1.0)';
    'MLB_CHECK5':
      PIN_NUMBER='(0,0,0,0,0,0,0,0,0,0,0,0,0,0,0,0,0,0,0,0,0,0,0,0,0,0,0,0,0,0,0,0,0,0,BU10,0,0,0,0,0)';
      BIDIRECTIONAL='TRUE';
      INPUT_LOAD='(-0.01,0.01)';
      OUTPUT_LOAD='(1.0,-1.0)';
    'MLA_DQS_L7':
      PIN_NUMBER='(0,0,0,0,0,0,0,0,0,0,0,0,0,0,0,0,0,0,0,0,0,0,0,0,0,0,0,0,0,0,0,0,0,0,Y11,0,0,0,0,0)';
      BIDIRECTIONAL='TRUE';
      INPUT_LOAD='(-0.01,0.01)';
      OUTPUT_LOAD='(1.0,-1.0)';
    'MLA_DQS_H3':
      PIN_NUMBER='(0,0,0,0,0,0,0,0,0,0,0,0,0,0,0,0,0,0,0,0,0,0,0,0,0,0,0,0,0,0,0,0,0,0,AE9,0,0,0,0,0)';
      BIDIRECTIONAL='TRUE';
      INPUT_LOAD='(-0.01,0.01)';
      OUTPUT_LOAD='(1.0,-1.0)';
    'MLB_DQS_L2':
      PIN_NUMBER='(0,0,0,0,0,0,0,0,0,0,0,0,0,0,0,0,0,0,0,0,0,0,0,0,0,0,0,0,0,0,0,0,0,0,CU9,0,0,0,0,0)';
      BIDIRECTIONAL='TRUE';
      INPUT_LOAD='(-0.01,0.01)';
      OUTPUT_LOAD='(1.0,-1.0)';
    'MLB_DATA26':
      PIN_NUMBER='(0,0,0,0,0,0,0,0,0,0,0,0,0,0,0,0,0,0,0,0,0,0,0,0,0,0,0,0,0,0,0,0,0,0,DA9,0,0,0,0,0)';
      BIDIRECTIONAL='TRUE';
      INPUT_LOAD='(-0.01,0.01)';
      OUTPUT_LOAD='(1.0,-1.0)';
    'MLB_DATA15':
      PIN_NUMBER='(0,0,0,0,0,0,0,0,0,0,0,0,0,0,0,0,0,0,0,0,0,0,0,0,0,0,0,0,0,0,0,0,0,0,CP11,0,0,0,0,0)';
      BIDIRECTIONAL='TRUE';
      INPUT_LOAD='(-0.01,0.01)';
      OUTPUT_LOAD='(1.0,-1.0)';
    'MLB_CHECK6':
      PIN_NUMBER='(0,0,0,0,0,0,0,0,0,0,0,0,0,0,0,0,0,0,0,0,0,0,0,0,0,0,0,0,0,0,0,0,0,0,BU9,0,0,0,0,0)';
      BIDIRECTIONAL='TRUE';
      INPUT_LOAD='(-0.01,0.01)';
      OUTPUT_LOAD='(1.0,-1.0)';
    'MLB0_RSP_L':
      PIN_NUMBER='(0,0,0,0,0,0,0,0,0,0,0,0,0,0,0,0,0,0,0,0,0,0,0,0,0,0,0,0,0,0,0,0,0,0,BP9,0,0,0,0,0)';
      INPUT_LOAD='(-0.01,0.01)';
    'MLA_DQS_L8':
      PIN_NUMBER='(0,0,0,0,0,0,0,0,0,0,0,0,0,0,0,0,0,0,0,0,0,0,0,0,0,0,0,0,0,0,0,0,0,0,AF11,0,0,0,0,0)';
      BIDIRECTIONAL='TRUE';
      INPUT_LOAD='(-0.01,0.01)';
      OUTPUT_LOAD='(1.0,-1.0)';
    'MLA_DQS_H4':
      PIN_NUMBER='(0,0,0,0,0,0,0,0,0,0,0,0,0,0,0,0,0,0,0,0,0,0,0,0,0,0,0,0,0,0,0,0,0,0,AL9,0,0,0,0,0)';
      BIDIRECTIONAL='TRUE';
      INPUT_LOAD='(-0.01,0.01)';
      OUTPUT_LOAD='(1.0,-1.0)';
    'MLB_DQS_L3':
      PIN_NUMBER='(0,0,0,0,0,0,0,0,0,0,0,0,0,0,0,0,0,0,0,0,0,0,0,0,0,0,0,0,0,0,0,0,0,0,DC9,0,0,0,0,0)';
      BIDIRECTIONAL='TRUE';
      INPUT_LOAD='(-0.01,0.01)';
      OUTPUT_LOAD='(1.0,-1.0)';
    'MLB_DATA27':
      PIN_NUMBER='(0,0,0,0,0,0,0,0,0,0,0,0,0,0,0,0,0,0,0,0,0,0,0,0,0,0,0,0,0,0,0,0,0,0,DB11,0,0,0,0,0)';
      BIDIRECTIONAL='TRUE';
      INPUT_LOAD='(-0.01,0.01)';
      OUTPUT_LOAD='(1.0,-1.0)';
    'MLB_DATA16':
      PIN_NUMBER='(0,0,0,0,0,0,0,0,0,0,0,0,0,0,0,0,0,0,0,0,0,0,0,0,0,0,0,0,0,0,0,0,0,0,CP9,0,0,0,0,0)';
      BIDIRECTIONAL='TRUE';
      INPUT_LOAD='(-0.01,0.01)';
      OUTPUT_LOAD='(1.0,-1.0)';
    'MLB_CHECK7':
      PIN_NUMBER='(0,0,0,0,0,0,0,0,0,0,0,0,0,0,0,0,0,0,0,0,0,0,0,0,0,0,0,0,0,0,0,0,0,0,BV11,0,0,0,0,0)';
      BIDIRECTIONAL='TRUE';
      INPUT_LOAD='(-0.01,0.01)';
      OUTPUT_LOAD='(1.0,-1.0)';
    'MLB1_RSP_L':
      PIN_NUMBER='(0,0,0,0,0,0,0,0,0,0,0,0,0,0,0,0,0,0,0,0,0,0,0,0,0,0,0,0,0,0,0,0,0,0,BR9,0,0,0,0,0)';
      INPUT_LOAD='(-0.01,0.01)';
    'MLA_PAR':
      PIN_NUMBER='(0,0,0,0,0,0,0,0,0,0,0,0,0,0,0,0,0,0,0,0,0,0,0,0,0,0,0,0,0,0,0,0,0,0,BC10,0,0,0,0,0)';
      OUTPUT_LOAD='(1.0,-1.0)';
    'MLA_DQS_L9':
      PIN_NUMBER='(0,0,0,0,0,0,0,0,0,0,0,0,0,0,0,0,0,0,0,0,0,0,0,0,0,0,0,0,0,0,0,0,0,0,AM11,0,0,0,0,0)';
      BIDIRECTIONAL='TRUE';
      INPUT_LOAD='(-0.01,0.01)';
      OUTPUT_LOAD='(1.0,-1.0)';
    'MLA_DQS_H5':
      PIN_NUMBER='(0,0,0,0,0,0,0,0,0,0,0,0,0,0,0,0,0,0,0,0,0,0,0,0,0,0,0,0,0,0,0,0,0,0,J10,0,0,0,0,0)';
      BIDIRECTIONAL='TRUE';
      INPUT_LOAD='(-0.01,0.01)';
      OUTPUT_LOAD='(1.0,-1.0)';
    'ML0_CLK_L':
      PIN_NUMBER='(0,0,0,0,0,0,0,0,0,0,0,0,0,0,0,0,0,0,0,0,0,0,0,0,0,0,0,0,0,0,0,0,0,0,BD9,0,0,0,0,0)';
      OUTPUT_LOAD='(1.0,-1.0)';
    'MLB_PAR':
      PIN_NUMBER='(0,0,0,0,0,0,0,0,0,0,0,0,0,0,0,0,0,0,0,0,0,0,0,0,0,0,0,0,0,0,0,0,0,0,BL10,0,0,0,0,0)';
      OUTPUT_LOAD='(1.0,-1.0)';
    'MLB_DQS_L4':
      PIN_NUMBER='(0,0,0,0,0,0,0,0,0,0,0,0,0,0,0,0,0,0,0,0,0,0,0,0,0,0,0,0,0,0,0,0,0,0,BW10,0,0,0,0,0)';
      BIDIRECTIONAL='TRUE';
      INPUT_LOAD='(-0.01,0.01)';
      OUTPUT_LOAD='(1.0,-1.0)';
    'MLB_DQS_H0':
      PIN_NUMBER='(0,0,0,0,0,0,0,0,0,0,0,0,0,0,0,0,0,0,0,0,0,0,0,0,0,0,0,0,0,0,0,0,0,0,CD9,0,0,0,0,0)';
      BIDIRECTIONAL='TRUE';
      INPUT_LOAD='(-0.01,0.01)';
      OUTPUT_LOAD='(1.0,-1.0)';
    'MLB_DATA28':
      PIN_NUMBER='(0,0,0,0,0,0,0,0,0,0,0,0,0,0,0,0,0,0,0,0,0,0,0,0,0,0,0,0,0,0,0,0,0,0,DD9,0,0,0,0,0)';
      BIDIRECTIONAL='TRUE';
      INPUT_LOAD='(-0.01,0.01)';
      OUTPUT_LOAD='(1.0,-1.0)';
    'MLB_DATA17':
      PIN_NUMBER='(0,0,0,0,0,0,0,0,0,0,0,0,0,0,0,0,0,0,0,0,0,0,0,0,0,0,0,0,0,0,0,0,0,0,CR10,0,0,0,0,0)';
      BIDIRECTIONAL='TRUE';
      INPUT_LOAD='(-0.01,0.01)';
      OUTPUT_LOAD='(1.0,-1.0)';
    'MLA_DQS_H6':
      PIN_NUMBER='(0,0,0,0,0,0,0,0,0,0,0,0,0,0,0,0,0,0,0,0,0,0,0,0,0,0,0,0,0,0,0,0,0,0,R10,0,0,0,0,0)';
      BIDIRECTIONAL='TRUE';
      INPUT_LOAD='(-0.01,0.01)';
      OUTPUT_LOAD='(1.0,-1.0)';
    'MLA_DATA0':
      PIN_NUMBER='(0,0,0,0,0,0,0,0,0,0,0,0,0,0,0,0,0,0,0,0,0,0,0,0,0,0,0,0,0,0,0,0,0,0,E9,0,0,0,0,0)';
      BIDIRECTIONAL='TRUE';
      INPUT_LOAD='(-0.01,0.01)';
      OUTPUT_LOAD='(1.0,-1.0)';
    'MLA0_CS_L0':
      PIN_NUMBER='(0,0,0,0,0,0,0,0,0,0,0,0,0,0,0,0,0,0,0,0,0,0,0,0,0,0,0,0,0,0,0,0,0,0,AU9,0,0,0,0,0)';
      OUTPUT_LOAD='(1.0,-1.0)';
    'ML1_CLK_L':
      PIN_NUMBER='(0,0,0,0,0,0,0,0,0,0,0,0,0,0,0,0,0,0,0,0,0,0,0,0,0,0,0,0,0,0,0,0,0,0,BG9,0,0,0,0,0)';
      OUTPUT_LOAD='(1.0,-1.0)';
    'MLB_DQS_L5':
      PIN_NUMBER='(0,0,0,0,0,0,0,0,0,0,0,0,0,0,0,0,0,0,0,0,0,0,0,0,0,0,0,0,0,0,0,0,0,0,CE10,0,0,0,0,0)';
      BIDIRECTIONAL='TRUE';
      INPUT_LOAD='(-0.01,0.01)';
      OUTPUT_LOAD='(1.0,-1.0)';
    'MLB_DQS_H1':
      PIN_NUMBER='(0,0,0,0,0,0,0,0,0,0,0,0,0,0,0,0,0,0,0,0,0,0,0,0,0,0,0,0,0,0,0,0,0,0,CK9,0,0,0,0,0)';
      BIDIRECTIONAL='TRUE';
      INPUT_LOAD='(-0.01,0.01)';
      OUTPUT_LOAD='(1.0,-1.0)';
    'MLB_DATA29':
      PIN_NUMBER='(0,0,0,0,0,0,0,0,0,0,0,0,0,0,0,0,0,0,0,0,0,0,0,0,0,0,0,0,0,0,0,0,0,0,DE10,0,0,0,0,0)';
      BIDIRECTIONAL='TRUE';
      INPUT_LOAD='(-0.01,0.01)';
      OUTPUT_LOAD='(1.0,-1.0)';
    'MLB_DATA18':
      PIN_NUMBER='(0,0,0,0,0,0,0,0,0,0,0,0,0,0,0,0,0,0,0,0,0,0,0,0,0,0,0,0,0,0,0,0,0,0,CR9,0,0,0,0,0)';
      BIDIRECTIONAL='TRUE';
      INPUT_LOAD='(-0.01,0.01)';
      OUTPUT_LOAD='(1.0,-1.0)';
    'MLB_DATA0':
      PIN_NUMBER='(0,0,0,0,0,0,0,0,0,0,0,0,0,0,0,0,0,0,0,0,0,0,0,0,0,0,0,0,0,0,0,0,0,0,CB9,0,0,0,0,0)';
      BIDIRECTIONAL='TRUE';
      INPUT_LOAD='(-0.01,0.01)';
      OUTPUT_LOAD='(1.0,-1.0)';
    'MLA_DQS_H7':
      PIN_NUMBER='(0,0,0,0,0,0,0,0,0,0,0,0,0,0,0,0,0,0,0,0,0,0,0,0,0,0,0,0,0,0,0,0,0,0,AA10,0,0,0,0,0)';
      BIDIRECTIONAL='TRUE';
      INPUT_LOAD='(-0.01,0.01)';
      OUTPUT_LOAD='(1.0,-1.0)';
    'MLA_DATA1':
      PIN_NUMBER='(0,0,0,0,0,0,0,0,0,0,0,0,0,0,0,0,0,0,0,0,0,0,0,0,0,0,0,0,0,0,0,0,0,0,F11,0,0,0,0,0)';
      BIDIRECTIONAL='TRUE';
      INPUT_LOAD='(-0.01,0.01)';
      OUTPUT_LOAD='(1.0,-1.0)';
    'MLA1_CS_L0':
      PIN_NUMBER='(0,0,0,0,0,0,0,0,0,0,0,0,0,0,0,0,0,0,0,0,0,0,0,0,0,0,0,0,0,0,0,0,0,0,AV9,0,0,0,0,0)';
      OUTPUT_LOAD='(1.0,-1.0)';
    'MLA0_CS_L1':
      PIN_NUMBER='(0,0,0,0,0,0,0,0,0,0,0,0,0,0,0,0,0,0,0,0,0,0,0,0,0,0,0,0,0,0,0,0,0,0,AV11,0,0,0,0,0)';
      OUTPUT_LOAD='(1.0,-1.0)';
    'MLB_DQS_L6':
      PIN_NUMBER='(0,0,0,0,0,0,0,0,0,0,0,0,0,0,0,0,0,0,0,0,0,0,0,0,0,0,0,0,0,0,0,0,0,0,CL10,0,0,0,0,0)';
      BIDIRECTIONAL='TRUE';
      INPUT_LOAD='(-0.01,0.01)';
      OUTPUT_LOAD='(1.0,-1.0)';
    'MLB_DQS_H2':
      PIN_NUMBER='(0,0,0,0,0,0,0,0,0,0,0,0,0,0,0,0,0,0,0,0,0,0,0,0,0,0,0,0,0,0,0,0,0,0,CT9,0,0,0,0,0)';
      BIDIRECTIONAL='TRUE';
      INPUT_LOAD='(-0.01,0.01)';
      OUTPUT_LOAD='(1.0,-1.0)';
    'MLB_DATA19':
      PIN_NUMBER='(0,0,0,0,0,0,0,0,0,0,0,0,0,0,0,0,0,0,0,0,0,0,0,0,0,0,0,0,0,0,0,0,0,0,CT11,0,0,0,0,0)';
      BIDIRECTIONAL='TRUE';
      INPUT_LOAD='(-0.01,0.01)';
      OUTPUT_LOAD='(1.0,-1.0)';
    'MLB_DATA1':
      PIN_NUMBER='(0,0,0,0,0,0,0,0,0,0,0,0,0,0,0,0,0,0,0,0,0,0,0,0,0,0,0,0,0,0,0,0,0,0,CC10,0,0,0,0,0)';
      BIDIRECTIONAL='TRUE';
      INPUT_LOAD='(-0.01,0.01)';
      OUTPUT_LOAD='(1.0,-1.0)';
    'MLA_DQS_H8':
      PIN_NUMBER='(0,0,0,0,0,0,0,0,0,0,0,0,0,0,0,0,0,0,0,0,0,0,0,0,0,0,0,0,0,0,0,0,0,0,AG10,0,0,0,0,0)';
      BIDIRECTIONAL='TRUE';
      INPUT_LOAD='(-0.01,0.01)';
      OUTPUT_LOAD='(1.0,-1.0)';
    'MLA_DATA30':
      PIN_NUMBER='(0,0,0,0,0,0,0,0,0,0,0,0,0,0,0,0,0,0,0,0,0,0,0,0,0,0,0,0,0,0,0,0,0,0,AH9,0,0,0,0,0)';
      BIDIRECTIONAL='TRUE';
      INPUT_LOAD='(-0.01,0.01)';
      OUTPUT_LOAD='(1.0,-1.0)';
    'MLA_DATA2':
      PIN_NUMBER='(0,0,0,0,0,0,0,0,0,0,0,0,0,0,0,0,0,0,0,0,0,0,0,0,0,0,0,0,0,0,0,0,0,0,F9,0,0,0,0,0)';
      BIDIRECTIONAL='TRUE';
      INPUT_LOAD='(-0.01,0.01)';
      OUTPUT_LOAD='(1.0,-1.0)';
    'MLA1_CS_L1':
      PIN_NUMBER='(0,0,0,0,0,0,0,0,0,0,0,0,0,0,0,0,0,0,0,0,0,0,0,0,0,0,0,0,0,0,0,0,0,0,AW10,0,0,0,0,0)';
      OUTPUT_LOAD='(1.0,-1.0)';
    'MLB_DQS_L7':
      PIN_NUMBER='(0,0,0,0,0,0,0,0,0,0,0,0,0,0,0,0,0,0,0,0,0,0,0,0,0,0,0,0,0,0,0,0,0,0,CU10,0,0,0,0,0)';
      BIDIRECTIONAL='TRUE';
      INPUT_LOAD='(-0.01,0.01)';
      OUTPUT_LOAD='(1.0,-1.0)';
    'MLB_DQS_H3':
      PIN_NUMBER='(0,0,0,0,0,0,0,0,0,0,0,0,0,0,0,0,0,0,0,0,0,0,0,0,0,0,0,0,0,0,0,0,0,0,DB9,0,0,0,0,0)';
      BIDIRECTIONAL='TRUE';
      INPUT_LOAD='(-0.01,0.01)';
      OUTPUT_LOAD='(1.0,-1.0)';
    'MLB_DATA2':
      PIN_NUMBER='(0,0,0,0,0,0,0,0,0,0,0,0,0,0,0,0,0,0,0,0,0,0,0,0,0,0,0,0,0,0,0,0,0,0,CC9,0,0,0,0,0)';
      BIDIRECTIONAL='TRUE';
      INPUT_LOAD='(-0.01,0.01)';
      OUTPUT_LOAD='(1.0,-1.0)';
    'MLA_DQS_H9':
      PIN_NUMBER='(0,0,0,0,0,0,0,0,0,0,0,0,0,0,0,0,0,0,0,0,0,0,0,0,0,0,0,0,0,0,0,0,0,0,AN10,0,0,0,0,0)';
      BIDIRECTIONAL='TRUE';
      INPUT_LOAD='(-0.01,0.01)';
      OUTPUT_LOAD='(1.0,-1.0)';
    'MLA_DATA31':
      PIN_NUMBER='(0,0,0,0,0,0,0,0,0,0,0,0,0,0,0,0,0,0,0,0,0,0,0,0,0,0,0,0,0,0,0,0,0,0,AJ10,0,0,0,0,0)';
      BIDIRECTIONAL='TRUE';
      INPUT_LOAD='(-0.01,0.01)';
      OUTPUT_LOAD='(1.0,-1.0)';
    'MLA_DATA20':
      PIN_NUMBER='(0,0,0,0,0,0,0,0,0,0,0,0,0,0,0,0,0,0,0,0,0,0,0,0,0,0,0,0,0,0,0,0,0,0,AA9,0,0,0,0,0)';
      BIDIRECTIONAL='TRUE';
      INPUT_LOAD='(-0.01,0.01)';
      OUTPUT_LOAD='(1.0,-1.0)';
    'MLA_DATA3':
      PIN_NUMBER='(0,0,0,0,0,0,0,0,0,0,0,0,0,0,0,0,0,0,0,0,0,0,0,0,0,0,0,0,0,0,0,0,0,0,G10,0,0,0,0,0)';
      BIDIRECTIONAL='TRUE';
      INPUT_LOAD='(-0.01,0.01)';
      OUTPUT_LOAD='(1.0,-1.0)';
    'MLA_CHECK0':
      PIN_NUMBER='(0,0,0,0,0,0,0,0,0,0,0,0,0,0,0,0,0,0,0,0,0,0,0,0,0,0,0,0,0,0,0,0,0,0,AJ9,0,0,0,0,0)';
      BIDIRECTIONAL='TRUE';
      INPUT_LOAD='(-0.01,0.01)';
      OUTPUT_LOAD='(1.0,-1.0)';
    'MLA_CA0':
      PIN_NUMBER='(0,0,0,0,0,0,0,0,0,0,0,0,0,0,0,0,0,0,0,0,0,0,0,0,0,0,0,0,0,0,0,0,0,0,AW9,0,0,0,0,0)';
      OUTPUT_LOAD='(1.0,-1.0)';
    'MLB_DQS_L8':
      PIN_NUMBER='(0,0,0,0,0,0,0,0,0,0,0,0,0,0,0,0,0,0,0,0,0,0,0,0,0,0,0,0,0,0,0,0,0,0,DC10,0,0,0,0,0)';
      BIDIRECTIONAL='TRUE';
      INPUT_LOAD='(-0.01,0.01)';
      OUTPUT_LOAD='(1.0,-1.0)';
    'MLB_DQS_H4':
      PIN_NUMBER='(0,0,0,0,0,0,0,0,0,0,0,0,0,0,0,0,0,0,0,0,0,0,0,0,0,0,0,0,0,0,0,0,0,0,BY11,0,0,0,0,0)';
      BIDIRECTIONAL='TRUE';
      INPUT_LOAD='(-0.01,0.01)';
      OUTPUT_LOAD='(1.0,-1.0)';
    'MLB_DATA3':
      PIN_NUMBER='(0,0,0,0,0,0,0,0,0,0,0,0,0,0,0,0,0,0,0,0,0,0,0,0,0,0,0,0,0,0,0,0,0,0,CD11,0,0,0,0,0)';
      BIDIRECTIONAL='TRUE';
      INPUT_LOAD='(-0.01,0.01)';
      OUTPUT_LOAD='(1.0,-1.0)';
    'MLB_CA0':
      PIN_NUMBER='(0,0,0,0,0,0,0,0,0,0,0,0,0,0,0,0,0,0,0,0,0,0,0,0,0,0,0,0,0,0,0,0,0,0,BG10,0,0,0,0,0)';
      OUTPUT_LOAD='(1.0,-1.0)';
    'MLA_DATA21':
      PIN_NUMBER='(0,0,0,0,0,0,0,0,0,0,0,0,0,0,0,0,0,0,0,0,0,0,0,0,0,0,0,0,0,0,0,0,0,0,AB11,0,0,0,0,0)';
      BIDIRECTIONAL='TRUE';
      INPUT_LOAD='(-0.01,0.01)';
      OUTPUT_LOAD='(1.0,-1.0)';
    'MLA_DATA10':
      PIN_NUMBER='(0,0,0,0,0,0,0,0,0,0,0,0,0,0,0,0,0,0,0,0,0,0,0,0,0,0,0,0,0,0,0,0,0,0,M9,0,0,0,0,0)';
      BIDIRECTIONAL='TRUE';
      INPUT_LOAD='(-0.01,0.01)';
      OUTPUT_LOAD='(1.0,-1.0)';
    'MLA_DATA4':
      PIN_NUMBER='(0,0,0,0,0,0,0,0,0,0,0,0,0,0,0,0,0,0,0,0,0,0,0,0,0,0,0,0,0,0,0,0,0,0,J9,0,0,0,0,0)';
      BIDIRECTIONAL='TRUE';
      INPUT_LOAD='(-0.01,0.01)';
      OUTPUT_LOAD='(1.0,-1.0)';
    'MLA_CHECK1':
      PIN_NUMBER='(0,0,0,0,0,0,0,0,0,0,0,0,0,0,0,0,0,0,0,0,0,0,0,0,0,0,0,0,0,0,0,0,0,0,AK11,0,0,0,0,0)';
      BIDIRECTIONAL='TRUE';
      INPUT_LOAD='(-0.01,0.01)';
      OUTPUT_LOAD='(1.0,-1.0)';
    'MLA_CA1':
      PIN_NUMBER='(0,0,0,0,0,0,0,0,0,0,0,0,0,0,0,0,0,0,0,0,0,0,0,0,0,0,0,0,0,0,0,0,0,0,AY9,0,0,0,0,0)';
      OUTPUT_LOAD='(1.0,-1.0)';
    'TEST39L':
      PIN_NUMBER='(0,0,0,0,0,0,0,0,0,0,0,0,0,0,0,0,0,0,0,0,0,0,0,0,0,0,0,0,0,0,0,0,0,0,BF11,0,0,0,0,0)';
      OUTPUT_LOAD='(1.0,-1.0)';
    'MKB_DQS_L6':
      PIN_NUMBER='(0,0,0,0,0,0,0,0,0,0,0,0,0,0,0,0,0,0,0,0,0,0,0,0,0,0,0,0,0,0,0,0,0,0,0,CL7,0,0,0,0)';
      BIDIRECTIONAL='TRUE';
      INPUT_LOAD='(-0.01,0.01)';
      OUTPUT_LOAD='(1.0,-1.0)';
    'MKB_DQS_H2':
      PIN_NUMBER='(0,0,0,0,0,0,0,0,0,0,0,0,0,0,0,0,0,0,0,0,0,0,0,0,0,0,0,0,0,0,0,0,0,0,0,CT6,0,0,0,0)';
      BIDIRECTIONAL='TRUE';
      INPUT_LOAD='(-0.01,0.01)';
      OUTPUT_LOAD='(1.0,-1.0)';
    'MKB_DATA19':
      PIN_NUMBER='(0,0,0,0,0,0,0,0,0,0,0,0,0,0,0,0,0,0,0,0,0,0,0,0,0,0,0,0,0,0,0,0,0,0,0,CT7,0,0,0,0)';
      BIDIRECTIONAL='TRUE';
      INPUT_LOAD='(-0.01,0.01)';
      OUTPUT_LOAD='(1.0,-1.0)';
    'MKB_CA0':
      PIN_NUMBER='(0,0,0,0,0,0,0,0,0,0,0,0,0,0,0,0,0,0,0,0,0,0,0,0,0,0,0,0,0,0,0,0,0,0,0,BG7,0,0,0,0)';
      OUTPUT_LOAD='(1.0,-1.0)';
    'MKA_DQS_H8':
      PIN_NUMBER='(0,0,0,0,0,0,0,0,0,0,0,0,0,0,0,0,0,0,0,0,0,0,0,0,0,0,0,0,0,0,0,0,0,0,0,AG7,0,0,0,0)';
      BIDIRECTIONAL='TRUE';
      INPUT_LOAD='(-0.01,0.01)';
      OUTPUT_LOAD='(1.0,-1.0)';
    'MKA_DATA30':
      PIN_NUMBER='(0,0,0,0,0,0,0,0,0,0,0,0,0,0,0,0,0,0,0,0,0,0,0,0,0,0,0,0,0,0,0,0,0,0,0,AH6,0,0,0,0)';
      BIDIRECTIONAL='TRUE';
      INPUT_LOAD='(-0.01,0.01)';
      OUTPUT_LOAD='(1.0,-1.0)';
    'MKA_CA1':
      PIN_NUMBER='(0,0,0,0,0,0,0,0,0,0,0,0,0,0,0,0,0,0,0,0,0,0,0,0,0,0,0,0,0,0,0,0,0,0,0,AY6,0,0,0,0)';
      OUTPUT_LOAD='(1.0,-1.0)';
    'MKA1_CS_L0':
      PIN_NUMBER='(0,0,0,0,0,0,0,0,0,0,0,0,0,0,0,0,0,0,0,0,0,0,0,0,0,0,0,0,0,0,0,0,0,0,0,AV6,0,0,0,0)';
      OUTPUT_LOAD='(1.0,-1.0)';
    'MKA0_CS_L1':
      PIN_NUMBER='(0,0,0,0,0,0,0,0,0,0,0,0,0,0,0,0,0,0,0,0,0,0,0,0,0,0,0,0,0,0,0,0,0,0,0,AV7,0,0,0,0)';
      OUTPUT_LOAD='(1.0,-1.0)';
    'MKB_DQS_L7':
      PIN_NUMBER='(0,0,0,0,0,0,0,0,0,0,0,0,0,0,0,0,0,0,0,0,0,0,0,0,0,0,0,0,0,0,0,0,0,0,0,CU7,0,0,0,0)';
      BIDIRECTIONAL='TRUE';
      INPUT_LOAD='(-0.01,0.01)';
      OUTPUT_LOAD='(1.0,-1.0)';
    'MKB_DQS_H3':
      PIN_NUMBER='(0,0,0,0,0,0,0,0,0,0,0,0,0,0,0,0,0,0,0,0,0,0,0,0,0,0,0,0,0,0,0,0,0,0,0,DB6,0,0,0,0)';
      BIDIRECTIONAL='TRUE';
      INPUT_LOAD='(-0.01,0.01)';
      OUTPUT_LOAD='(1.0,-1.0)';
    'MKB_CA1':
      PIN_NUMBER='(0,0,0,0,0,0,0,0,0,0,0,0,0,0,0,0,0,0,0,0,0,0,0,0,0,0,0,0,0,0,0,0,0,0,0,BH7,0,0,0,0)';
      OUTPUT_LOAD='(1.0,-1.0)';
    'MKA_DQS_H9':
      PIN_NUMBER='(0,0,0,0,0,0,0,0,0,0,0,0,0,0,0,0,0,0,0,0,0,0,0,0,0,0,0,0,0,0,0,0,0,0,0,AN7,0,0,0,0)';
      BIDIRECTIONAL='TRUE';
      INPUT_LOAD='(-0.01,0.01)';
      OUTPUT_LOAD='(1.0,-1.0)';
    'MKA_DATA31':
      PIN_NUMBER='(0,0,0,0,0,0,0,0,0,0,0,0,0,0,0,0,0,0,0,0,0,0,0,0,0,0,0,0,0,0,0,0,0,0,0,AJ7,0,0,0,0)';
      BIDIRECTIONAL='TRUE';
      INPUT_LOAD='(-0.01,0.01)';
      OUTPUT_LOAD='(1.0,-1.0)';
    'MKA_DATA20':
      PIN_NUMBER='(0,0,0,0,0,0,0,0,0,0,0,0,0,0,0,0,0,0,0,0,0,0,0,0,0,0,0,0,0,0,0,0,0,0,0,AA5,0,0,0,0)';
      BIDIRECTIONAL='TRUE';
      INPUT_LOAD='(-0.01,0.01)';
      OUTPUT_LOAD='(1.0,-1.0)';
    'MKA_CHECK0':
      PIN_NUMBER='(0,0,0,0,0,0,0,0,0,0,0,0,0,0,0,0,0,0,0,0,0,0,0,0,0,0,0,0,0,0,0,0,0,0,0,AJ5,0,0,0,0)';
      BIDIRECTIONAL='TRUE';
      INPUT_LOAD='(-0.01,0.01)';
      OUTPUT_LOAD='(1.0,-1.0)';
    'MKA_CA2':
      PIN_NUMBER='(0,0,0,0,0,0,0,0,0,0,0,0,0,0,0,0,0,0,0,0,0,0,0,0,0,0,0,0,0,0,0,0,0,0,0,AY7,0,0,0,0)';
      OUTPUT_LOAD='(1.0,-1.0)';
    'MKA1_CS_L1':
      PIN_NUMBER='(0,0,0,0,0,0,0,0,0,0,0,0,0,0,0,0,0,0,0,0,0,0,0,0,0,0,0,0,0,0,0,0,0,0,0,AW7,0,0,0,0)';
      OUTPUT_LOAD='(1.0,-1.0)';
    'MK0_CLK_H':
      PIN_NUMBER='(0,0,0,0,0,0,0,0,0,0,0,0,0,0,0,0,0,0,0,0,0,0,0,0,0,0,0,0,0,0,0,0,0,0,0,BC5,0,0,0,0)';
      OUTPUT_LOAD='(1.0,-1.0)';
    'MKB_DQS_L8':
      PIN_NUMBER='(0,0,0,0,0,0,0,0,0,0,0,0,0,0,0,0,0,0,0,0,0,0,0,0,0,0,0,0,0,0,0,0,0,0,0,DC7,0,0,0,0)';
      BIDIRECTIONAL='TRUE';
      INPUT_LOAD='(-0.01,0.01)';
      OUTPUT_LOAD='(1.0,-1.0)';
    'MKB_DQS_H4':
      PIN_NUMBER='(0,0,0,0,0,0,0,0,0,0,0,0,0,0,0,0,0,0,0,0,0,0,0,0,0,0,0,0,0,0,0,0,0,0,0,BY7,0,0,0,0)';
      BIDIRECTIONAL='TRUE';
      INPUT_LOAD='(-0.01,0.01)';
      OUTPUT_LOAD='(1.0,-1.0)';
    'MKB_CA2':
      PIN_NUMBER='(0,0,0,0,0,0,0,0,0,0,0,0,0,0,0,0,0,0,0,0,0,0,0,0,0,0,0,0,0,0,0,0,0,0,0,BH6,0,0,0,0)';
      OUTPUT_LOAD='(1.0,-1.0)';
    'MKA_DATA21':
      PIN_NUMBER='(0,0,0,0,0,0,0,0,0,0,0,0,0,0,0,0,0,0,0,0,0,0,0,0,0,0,0,0,0,0,0,0,0,0,0,AB7,0,0,0,0)';
      BIDIRECTIONAL='TRUE';
      INPUT_LOAD='(-0.01,0.01)';
      OUTPUT_LOAD='(1.0,-1.0)';
    'MKA_DATA10':
      PIN_NUMBER='(0,0,0,0,0,0,0,0,0,0,0,0,0,0,0,0,0,0,0,0,0,0,0,0,0,0,0,0,0,0,0,0,0,0,0,M6,0,0,0,0)';
      BIDIRECTIONAL='TRUE';
      INPUT_LOAD='(-0.01,0.01)';
      OUTPUT_LOAD='(1.0,-1.0)';
    'MKA_CHECK1':
      PIN_NUMBER='(0,0,0,0,0,0,0,0,0,0,0,0,0,0,0,0,0,0,0,0,0,0,0,0,0,0,0,0,0,0,0,0,0,0,0,AK7,0,0,0,0)';
      BIDIRECTIONAL='TRUE';
      INPUT_LOAD='(-0.01,0.01)';
      OUTPUT_LOAD='(1.0,-1.0)';
    'MKA_CA3':
      PIN_NUMBER='(0,0,0,0,0,0,0,0,0,0,0,0,0,0,0,0,0,0,0,0,0,0,0,0,0,0,0,0,0,0,0,0,0,0,0,BA7,0,0,0,0)';
      OUTPUT_LOAD='(1.0,-1.0)';
    'MK1_CLK_H':
      PIN_NUMBER='(0,0,0,0,0,0,0,0,0,0,0,0,0,0,0,0,0,0,0,0,0,0,0,0,0,0,0,0,0,0,0,0,0,0,0,BF6,0,0,0,0)';
      OUTPUT_LOAD='(1.0,-1.0)';
    'MKB_DQS_L9':
      PIN_NUMBER='(0,0,0,0,0,0,0,0,0,0,0,0,0,0,0,0,0,0,0,0,0,0,0,0,0,0,0,0,0,0,0,0,0,0,0,BW5,0,0,0,0)';
      BIDIRECTIONAL='TRUE';
      INPUT_LOAD='(-0.01,0.01)';
      OUTPUT_LOAD='(1.0,-1.0)';
    'MKB_DQS_H5':
      PIN_NUMBER='(0,0,0,0,0,0,0,0,0,0,0,0,0,0,0,0,0,0,0,0,0,0,0,0,0,0,0,0,0,0,0,0,0,0,0,CF7,0,0,0,0)';
      BIDIRECTIONAL='TRUE';
      INPUT_LOAD='(-0.01,0.01)';
      OUTPUT_LOAD='(1.0,-1.0)';
    'MKB_CA3':
      PIN_NUMBER='(0,0,0,0,0,0,0,0,0,0,0,0,0,0,0,0,0,0,0,0,0,0,0,0,0,0,0,0,0,0,0,0,0,0,0,BJ5,0,0,0,0)';
      OUTPUT_LOAD='(1.0,-1.0)';
    'MKA_DATA22':
      PIN_NUMBER='(0,0,0,0,0,0,0,0,0,0,0,0,0,0,0,0,0,0,0,0,0,0,0,0,0,0,0,0,0,0,0,0,0,0,0,AB6,0,0,0,0)';
      BIDIRECTIONAL='TRUE';
      INPUT_LOAD='(-0.01,0.01)';
      OUTPUT_LOAD='(1.0,-1.0)';
    'MKA_DATA11':
      PIN_NUMBER='(0,0,0,0,0,0,0,0,0,0,0,0,0,0,0,0,0,0,0,0,0,0,0,0,0,0,0,0,0,0,0,0,0,0,0,N7,0,0,0,0)';
      BIDIRECTIONAL='TRUE';
      INPUT_LOAD='(-0.01,0.01)';
      OUTPUT_LOAD='(1.0,-1.0)';
    'MKA_CHECK2':
      PIN_NUMBER='(0,0,0,0,0,0,0,0,0,0,0,0,0,0,0,0,0,0,0,0,0,0,0,0,0,0,0,0,0,0,0,0,0,0,0,AK6,0,0,0,0)';
      BIDIRECTIONAL='TRUE';
      INPUT_LOAD='(-0.01,0.01)';
      OUTPUT_LOAD='(1.0,-1.0)';
    'MKA_CA4':
      PIN_NUMBER='(0,0,0,0,0,0,0,0,0,0,0,0,0,0,0,0,0,0,0,0,0,0,0,0,0,0,0,0,0,0,0,0,0,0,0,BA5,0,0,0,0)';
      OUTPUT_LOAD='(1.0,-1.0)';
    'MK_RESET_L':
      PIN_NUMBER='(0,0,0,0,0,0,0,0,0,0,0,0,0,0,0,0,0,0,0,0,0,0,0,0,0,0,0,0,0,0,0,0,0,0,0,AU7,0,0,0,0)';
      OUTPUT_LOAD='(1.0,-1.0)';
    'MKB_DQS_H6':
      PIN_NUMBER='(0,0,0,0,0,0,0,0,0,0,0,0,0,0,0,0,0,0,0,0,0,0,0,0,0,0,0,0,0,0,0,0,0,0,0,CM7,0,0,0,0)';
      BIDIRECTIONAL='TRUE';
      INPUT_LOAD='(-0.01,0.01)';
      OUTPUT_LOAD='(1.0,-1.0)';
    'MKB_CA4':
      PIN_NUMBER='(0,0,0,0,0,0,0,0,0,0,0,0,0,0,0,0,0,0,0,0,0,0,0,0,0,0,0,0,0,0,0,0,0,0,0,BJ7,0,0,0,0)';
      OUTPUT_LOAD='(1.0,-1.0)';
    'MKA_DATA23':
      PIN_NUMBER='(0,0,0,0,0,0,0,0,0,0,0,0,0,0,0,0,0,0,0,0,0,0,0,0,0,0,0,0,0,0,0,0,0,0,0,AC7,0,0,0,0)';
      BIDIRECTIONAL='TRUE';
      INPUT_LOAD='(-0.01,0.01)';
      OUTPUT_LOAD='(1.0,-1.0)';
    'MKA_DATA12':
      PIN_NUMBER='(0,0,0,0,0,0,0,0,0,0,0,0,0,0,0,0,0,0,0,0,0,0,0,0,0,0,0,0,0,0,0,0,0,0,0,R5,0,0,0,0)';
      BIDIRECTIONAL='TRUE';
      INPUT_LOAD='(-0.01,0.01)';
      OUTPUT_LOAD='(1.0,-1.0)';
    'MKA_CHECK3':
      PIN_NUMBER='(0,0,0,0,0,0,0,0,0,0,0,0,0,0,0,0,0,0,0,0,0,0,0,0,0,0,0,0,0,0,0,0,0,0,0,AL7,0,0,0,0)';
      BIDIRECTIONAL='TRUE';
      INPUT_LOAD='(-0.01,0.01)';
      OUTPUT_LOAD='(1.0,-1.0)';
    'MKA_CA5':
      PIN_NUMBER='(0,0,0,0,0,0,0,0,0,0,0,0,0,0,0,0,0,0,0,0,0,0,0,0,0,0,0,0,0,0,0,0,0,0,0,BB6,0,0,0,0)';
      OUTPUT_LOAD='(1.0,-1.0)';
    'MKB_DQS_H7':
      PIN_NUMBER='(0,0,0,0,0,0,0,0,0,0,0,0,0,0,0,0,0,0,0,0,0,0,0,0,0,0,0,0,0,0,0,0,0,0,0,CV7,0,0,0,0)';
      BIDIRECTIONAL='TRUE';
      INPUT_LOAD='(-0.01,0.01)';
      OUTPUT_LOAD='(1.0,-1.0)';
    'MKB_CA5':
      PIN_NUMBER='(0,0,0,0,0,0,0,0,0,0,0,0,0,0,0,0,0,0,0,0,0,0,0,0,0,0,0,0,0,0,0,0,0,0,0,BK7,0,0,0,0)';
      OUTPUT_LOAD='(1.0,-1.0)';
    'MKB0_CS_L0':
      PIN_NUMBER='(0,0,0,0,0,0,0,0,0,0,0,0,0,0,0,0,0,0,0,0,0,0,0,0,0,0,0,0,0,0,0,0,0,0,0,BM7,0,0,0,0)';
      OUTPUT_LOAD='(1.0,-1.0)';
    'MKA_DQS_L0':
      PIN_NUMBER='(0,0,0,0,0,0,0,0,0,0,0,0,0,0,0,0,0,0,0,0,0,0,0,0,0,0,0,0,0,0,0,0,0,0,0,H6,0,0,0,0)';
      BIDIRECTIONAL='TRUE';
      INPUT_LOAD='(-0.01,0.01)';
      OUTPUT_LOAD='(1.0,-1.0)';
    'MKA_DATA24':
      PIN_NUMBER='(0,0,0,0,0,0,0,0,0,0,0,0,0,0,0,0,0,0,0,0,0,0,0,0,0,0,0,0,0,0,0,0,0,0,0,AC5,0,0,0,0)';
      BIDIRECTIONAL='TRUE';
      INPUT_LOAD='(-0.01,0.01)';
      OUTPUT_LOAD='(1.0,-1.0)';
    'MKA_DATA13':
      PIN_NUMBER='(0,0,0,0,0,0,0,0,0,0,0,0,0,0,0,0,0,0,0,0,0,0,0,0,0,0,0,0,0,0,0,0,0,0,0,T7,0,0,0,0)';
      BIDIRECTIONAL='TRUE';
      INPUT_LOAD='(-0.01,0.01)';
      OUTPUT_LOAD='(1.0,-1.0)';
    'MKA_CHECK4':
      PIN_NUMBER='(0,0,0,0,0,0,0,0,0,0,0,0,0,0,0,0,0,0,0,0,0,0,0,0,0,0,0,0,0,0,0,0,0,0,0,AN5,0,0,0,0)';
      BIDIRECTIONAL='TRUE';
      INPUT_LOAD='(-0.01,0.01)';
      OUTPUT_LOAD='(1.0,-1.0)';
    'MKA_CA6':
      PIN_NUMBER='(0,0,0,0,0,0,0,0,0,0,0,0,0,0,0,0,0,0,0,0,0,0,0,0,0,0,0,0,0,0,0,0,0,0,0,BB7,0,0,0,0)';
      OUTPUT_LOAD='(1.0,-1.0)';
    'MK0_CLK_L':
      PIN_NUMBER='(0,0,0,0,0,0,0,0,0,0,0,0,0,0,0,0,0,0,0,0,0,0,0,0,0,0,0,0,0,0,0,0,0,0,0,BD6,0,0,0,0)';
      OUTPUT_LOAD='(1.0,-1.0)';
    'MKB_DQS_H8':
      PIN_NUMBER='(0,0,0,0,0,0,0,0,0,0,0,0,0,0,0,0,0,0,0,0,0,0,0,0,0,0,0,0,0,0,0,0,0,0,0,DD7,0,0,0,0)';
      BIDIRECTIONAL='TRUE';
      INPUT_LOAD='(-0.01,0.01)';
      OUTPUT_LOAD='(1.0,-1.0)';
    'MKB_DATA30':
      PIN_NUMBER='(0,0,0,0,0,0,0,0,0,0,0,0,0,0,0,0,0,0,0,0,0,0,0,0,0,0,0,0,0,0,0,0,0,0,0,DE5,0,0,0,0)';
      BIDIRECTIONAL='TRUE';
      INPUT_LOAD='(-0.01,0.01)';
      OUTPUT_LOAD='(1.0,-1.0)';
    'MKB_CA6':
      PIN_NUMBER='(0,0,0,0,0,0,0,0,0,0,0,0,0,0,0,0,0,0,0,0,0,0,0,0,0,0,0,0,0,0,0,0,0,0,0,BK6,0,0,0,0)';
      OUTPUT_LOAD='(1.0,-1.0)';
    'MKB1_CS_L0':
      PIN_NUMBER='(0,0,0,0,0,0,0,0,0,0,0,0,0,0,0,0,0,0,0,0,0,0,0,0,0,0,0,0,0,0,0,0,0,0,0,BL5,0,0,0,0)';
      OUTPUT_LOAD='(1.0,-1.0)';
    'MKB0_CS_L1':
      PIN_NUMBER='(0,0,0,0,0,0,0,0,0,0,0,0,0,0,0,0,0,0,0,0,0,0,0,0,0,0,0,0,0,0,0,0,0,0,0,BN5,0,0,0,0)';
      OUTPUT_LOAD='(1.0,-1.0)';
    'MKA_DQS_L1':
      PIN_NUMBER='(0,0,0,0,0,0,0,0,0,0,0,0,0,0,0,0,0,0,0,0,0,0,0,0,0,0,0,0,0,0,0,0,0,0,0,P6,0,0,0,0)';
      BIDIRECTIONAL='TRUE';
      INPUT_LOAD='(-0.01,0.01)';
      OUTPUT_LOAD='(1.0,-1.0)';
    'MKA_DATA25':
      PIN_NUMBER='(0,0,0,0,0,0,0,0,0,0,0,0,0,0,0,0,0,0,0,0,0,0,0,0,0,0,0,0,0,0,0,0,0,0,0,AD7,0,0,0,0)';
      BIDIRECTIONAL='TRUE';
      INPUT_LOAD='(-0.01,0.01)';
      OUTPUT_LOAD='(1.0,-1.0)';
    'MKA_DATA14':
      PIN_NUMBER='(0,0,0,0,0,0,0,0,0,0,0,0,0,0,0,0,0,0,0,0,0,0,0,0,0,0,0,0,0,0,0,0,0,0,0,T6,0,0,0,0)';
      BIDIRECTIONAL='TRUE';
      INPUT_LOAD='(-0.01,0.01)';
      OUTPUT_LOAD='(1.0,-1.0)';
    'MKA_DATA0':
      PIN_NUMBER='(0,0,0,0,0,0,0,0,0,0,0,0,0,0,0,0,0,0,0,0,0,0,0,0,0,0,0,0,0,0,0,0,0,0,0,E5,0,0,0,0)';
      BIDIRECTIONAL='TRUE';
      INPUT_LOAD='(-0.01,0.01)';
      OUTPUT_LOAD='(1.0,-1.0)';
    'MKA_CHECK5':
      PIN_NUMBER='(0,0,0,0,0,0,0,0,0,0,0,0,0,0,0,0,0,0,0,0,0,0,0,0,0,0,0,0,0,0,0,0,0,0,0,AP7,0,0,0,0)';
      BIDIRECTIONAL='TRUE';
      INPUT_LOAD='(-0.01,0.01)';
      OUTPUT_LOAD='(1.0,-1.0)';
    'MK1_CLK_L':
      PIN_NUMBER='(0,0,0,0,0,0,0,0,0,0,0,0,0,0,0,0,0,0,0,0,0,0,0,0,0,0,0,0,0,0,0,0,0,0,0,BG5,0,0,0,0)';
      OUTPUT_LOAD='(1.0,-1.0)';
    'MKB_DQS_H9':
      PIN_NUMBER='(0,0,0,0,0,0,0,0,0,0,0,0,0,0,0,0,0,0,0,0,0,0,0,0,0,0,0,0,0,0,0,0,0,0,0,BV6,0,0,0,0)';
      BIDIRECTIONAL='TRUE';
      INPUT_LOAD='(-0.01,0.01)';
      OUTPUT_LOAD='(1.0,-1.0)';
    'MKB_DATA31':
      PIN_NUMBER='(0,0,0,0,0,0,0,0,0,0,0,0,0,0,0,0,0,0,0,0,0,0,0,0,0,0,0,0,0,0,0,0,0,0,0,DF7,0,0,0,0)';
      BIDIRECTIONAL='TRUE';
      INPUT_LOAD='(-0.01,0.01)';
      OUTPUT_LOAD='(1.0,-1.0)';
    'MKB_DATA20':
      PIN_NUMBER='(0,0,0,0,0,0,0,0,0,0,0,0,0,0,0,0,0,0,0,0,0,0,0,0,0,0,0,0,0,0,0,0,0,0,0,CV6,0,0,0,0)';
      BIDIRECTIONAL='TRUE';
      INPUT_LOAD='(-0.01,0.01)';
      OUTPUT_LOAD='(1.0,-1.0)';
    'MKB_DATA0':
      PIN_NUMBER='(0,0,0,0,0,0,0,0,0,0,0,0,0,0,0,0,0,0,0,0,0,0,0,0,0,0,0,0,0,0,0,0,0,0,0,CB6,0,0,0,0)';
      BIDIRECTIONAL='TRUE';
      INPUT_LOAD='(-0.01,0.01)';
      OUTPUT_LOAD='(1.0,-1.0)';
    'MKB_CHECK0':
      PIN_NUMBER='(0,0,0,0,0,0,0,0,0,0,0,0,0,0,0,0,0,0,0,0,0,0,0,0,0,0,0,0,0,0,0,0,0,0,0,BY6,0,0,0,0)';
      BIDIRECTIONAL='TRUE';
      INPUT_LOAD='(-0.01,0.01)';
      OUTPUT_LOAD='(1.0,-1.0)';
    'MKB1_CS_L1':
      PIN_NUMBER='(0,0,0,0,0,0,0,0,0,0,0,0,0,0,0,0,0,0,0,0,0,0,0,0,0,0,0,0,0,0,0,0,0,0,0,BM6,0,0,0,0)';
      OUTPUT_LOAD='(1.0,-1.0)';
    'MKA_DQS_L2':
      PIN_NUMBER='(0,0,0,0,0,0,0,0,0,0,0,0,0,0,0,0,0,0,0,0,0,0,0,0,0,0,0,0,0,0,0,0,0,0,0,Y6,0,0,0,0)';
      BIDIRECTIONAL='TRUE';
      INPUT_LOAD='(-0.01,0.01)';
      OUTPUT_LOAD='(1.0,-1.0)';
    'MKA_DATA26':
      PIN_NUMBER='(0,0,0,0,0,0,0,0,0,0,0,0,0,0,0,0,0,0,0,0,0,0,0,0,0,0,0,0,0,0,0,0,0,0,0,AD6,0,0,0,0)';
      BIDIRECTIONAL='TRUE';
      INPUT_LOAD='(-0.01,0.01)';
      OUTPUT_LOAD='(1.0,-1.0)';
    'MKA_DATA15':
      PIN_NUMBER='(0,0,0,0,0,0,0,0,0,0,0,0,0,0,0,0,0,0,0,0,0,0,0,0,0,0,0,0,0,0,0,0,0,0,0,U7,0,0,0,0)';
      BIDIRECTIONAL='TRUE';
      INPUT_LOAD='(-0.01,0.01)';
      OUTPUT_LOAD='(1.0,-1.0)';
    'MKA_DATA1':
      PIN_NUMBER='(0,0,0,0,0,0,0,0,0,0,0,0,0,0,0,0,0,0,0,0,0,0,0,0,0,0,0,0,0,0,0,0,0,0,0,F7,0,0,0,0)';
      BIDIRECTIONAL='TRUE';
      INPUT_LOAD='(-0.01,0.01)';
      OUTPUT_LOAD='(1.0,-1.0)';
    'MKA_CHECK6':
      PIN_NUMBER='(0,0,0,0,0,0,0,0,0,0,0,0,0,0,0,0,0,0,0,0,0,0,0,0,0,0,0,0,0,0,0,0,0,0,0,AP6,0,0,0,0)';
      BIDIRECTIONAL='TRUE';
      INPUT_LOAD='(-0.01,0.01)';
      OUTPUT_LOAD='(1.0,-1.0)';
    'MKB_DATA21':
      PIN_NUMBER='(0,0,0,0,0,0,0,0,0,0,0,0,0,0,0,0,0,0,0,0,0,0,0,0,0,0,0,0,0,0,0,0,0,0,0,CW7,0,0,0,0)';
      BIDIRECTIONAL='TRUE';
      INPUT_LOAD='(-0.01,0.01)';
      OUTPUT_LOAD='(1.0,-1.0)';
    'MKB_DATA10':
      PIN_NUMBER='(0,0,0,0,0,0,0,0,0,0,0,0,0,0,0,0,0,0,0,0,0,0,0,0,0,0,0,0,0,0,0,0,0,0,0,CJ5,0,0,0,0)';
      BIDIRECTIONAL='TRUE';
      INPUT_LOAD='(-0.01,0.01)';
      OUTPUT_LOAD='(1.0,-1.0)';
    'MKB_DATA1':
      PIN_NUMBER='(0,0,0,0,0,0,0,0,0,0,0,0,0,0,0,0,0,0,0,0,0,0,0,0,0,0,0,0,0,0,0,0,0,0,0,CC7,0,0,0,0)';
      BIDIRECTIONAL='TRUE';
      INPUT_LOAD='(-0.01,0.01)';
      OUTPUT_LOAD='(1.0,-1.0)';
    'MKB_CHECK1':
      PIN_NUMBER='(0,0,0,0,0,0,0,0,0,0,0,0,0,0,0,0,0,0,0,0,0,0,0,0,0,0,0,0,0,0,0,0,0,0,0,CA7,0,0,0,0)';
      BIDIRECTIONAL='TRUE';
      INPUT_LOAD='(-0.01,0.01)';
      OUTPUT_LOAD='(1.0,-1.0)';
    'MKA_DQS_L3':
      PIN_NUMBER='(0,0,0,0,0,0,0,0,0,0,0,0,0,0,0,0,0,0,0,0,0,0,0,0,0,0,0,0,0,0,0,0,0,0,0,AF6,0,0,0,0)';
      BIDIRECTIONAL='TRUE';
      INPUT_LOAD='(-0.01,0.01)';
      OUTPUT_LOAD='(1.0,-1.0)';
    'MKA_DATA27':
      PIN_NUMBER='(0,0,0,0,0,0,0,0,0,0,0,0,0,0,0,0,0,0,0,0,0,0,0,0,0,0,0,0,0,0,0,0,0,0,0,AE7,0,0,0,0)';
      BIDIRECTIONAL='TRUE';
      INPUT_LOAD='(-0.01,0.01)';
      OUTPUT_LOAD='(1.0,-1.0)';
    'MKA_DATA16':
      PIN_NUMBER='(0,0,0,0,0,0,0,0,0,0,0,0,0,0,0,0,0,0,0,0,0,0,0,0,0,0,0,0,0,0,0,0,0,0,0,U5,0,0,0,0)';
      BIDIRECTIONAL='TRUE';
      INPUT_LOAD='(-0.01,0.01)';
      OUTPUT_LOAD='(1.0,-1.0)';
    'MKA_DATA2':
      PIN_NUMBER='(0,0,0,0,0,0,0,0,0,0,0,0,0,0,0,0,0,0,0,0,0,0,0,0,0,0,0,0,0,0,0,0,0,0,0,F6,0,0,0,0)';
      BIDIRECTIONAL='TRUE';
      INPUT_LOAD='(-0.01,0.01)';
      OUTPUT_LOAD='(1.0,-1.0)';
    'MKA_CHECK7':
      PIN_NUMBER='(0,0,0,0,0,0,0,0,0,0,0,0,0,0,0,0,0,0,0,0,0,0,0,0,0,0,0,0,0,0,0,0,0,0,0,AR7,0,0,0,0)';
      BIDIRECTIONAL='TRUE';
      INPUT_LOAD='(-0.01,0.01)';
      OUTPUT_LOAD='(1.0,-1.0)';
    'MKA0_RSP_L':
      PIN_NUMBER='(0,0,0,0,0,0,0,0,0,0,0,0,0,0,0,0,0,0,0,0,0,0,0,0,0,0,0,0,0,0,0,0,0,0,0,BN7,0,0,0,0)';
      INPUT_LOAD='(-0.01,0.01)';
    'MK_ALERT_L':
      PIN_NUMBER='(0,0,0,0,0,0,0,0,0,0,0,0,0,0,0,0,0,0,0,0,0,0,0,0,0,0,0,0,0,0,0,0,0,0,0,AT7,0,0,0,0)';
      INPUT_LOAD='(-0.01,0.01)';
    'MKB_DATA22':
      PIN_NUMBER='(0,0,0,0,0,0,0,0,0,0,0,0,0,0,0,0,0,0,0,0,0,0,0,0,0,0,0,0,0,0,0,0,0,0,0,CW5,0,0,0,0)';
      BIDIRECTIONAL='TRUE';
      INPUT_LOAD='(-0.01,0.01)';
      OUTPUT_LOAD='(1.0,-1.0)';
    'MKB_DATA11':
      PIN_NUMBER='(0,0,0,0,0,0,0,0,0,0,0,0,0,0,0,0,0,0,0,0,0,0,0,0,0,0,0,0,0,0,0,0,0,0,0,CK7,0,0,0,0)';
      BIDIRECTIONAL='TRUE';
      INPUT_LOAD='(-0.01,0.01)';
      OUTPUT_LOAD='(1.0,-1.0)';
    'MKB_DATA2':
      PIN_NUMBER='(0,0,0,0,0,0,0,0,0,0,0,0,0,0,0,0,0,0,0,0,0,0,0,0,0,0,0,0,0,0,0,0,0,0,0,CC5,0,0,0,0)';
      BIDIRECTIONAL='TRUE';
      INPUT_LOAD='(-0.01,0.01)';
      OUTPUT_LOAD='(1.0,-1.0)';
    'MKB_CHECK2':
      PIN_NUMBER='(0,0,0,0,0,0,0,0,0,0,0,0,0,0,0,0,0,0,0,0,0,0,0,0,0,0,0,0,0,0,0,0,0,0,0,CA5,0,0,0,0)';
      BIDIRECTIONAL='TRUE';
      INPUT_LOAD='(-0.01,0.01)';
      OUTPUT_LOAD='(1.0,-1.0)';
    'MKA_DQS_L4':
      PIN_NUMBER='(0,0,0,0,0,0,0,0,0,0,0,0,0,0,0,0,0,0,0,0,0,0,0,0,0,0,0,0,0,0,0,0,0,0,0,AM6,0,0,0,0)';
      BIDIRECTIONAL='TRUE';
      INPUT_LOAD='(-0.01,0.01)';
      OUTPUT_LOAD='(1.0,-1.0)';
    'MKA_DQS_H0':
      PIN_NUMBER='(0,0,0,0,0,0,0,0,0,0,0,0,0,0,0,0,0,0,0,0,0,0,0,0,0,0,0,0,0,0,0,0,0,0,0,G5,0,0,0,0)';
      BIDIRECTIONAL='TRUE';
      INPUT_LOAD='(-0.01,0.01)';
      OUTPUT_LOAD='(1.0,-1.0)';
    'MKA_DATA28':
      PIN_NUMBER='(0,0,0,0,0,0,0,0,0,0,0,0,0,0,0,0,0,0,0,0,0,0,0,0,0,0,0,0,0,0,0,0,0,0,0,AG5,0,0,0,0)';
      BIDIRECTIONAL='TRUE';
      INPUT_LOAD='(-0.01,0.01)';
      OUTPUT_LOAD='(1.0,-1.0)';
    'MKA_DATA17':
      PIN_NUMBER='(0,0,0,0,0,0,0,0,0,0,0,0,0,0,0,0,0,0,0,0,0,0,0,0,0,0,0,0,0,0,0,0,0,0,0,V7,0,0,0,0)';
      BIDIRECTIONAL='TRUE';
      INPUT_LOAD='(-0.01,0.01)';
      OUTPUT_LOAD='(1.0,-1.0)';
    'MKA_DATA3':
      PIN_NUMBER='(0,0,0,0,0,0,0,0,0,0,0,0,0,0,0,0,0,0,0,0,0,0,0,0,0,0,0,0,0,0,0,0,0,0,0,G7,0,0,0,0)';
      BIDIRECTIONAL='TRUE';
      INPUT_LOAD='(-0.01,0.01)';
      OUTPUT_LOAD='(1.0,-1.0)';
    'MKA1_RSP_L':
      PIN_NUMBER='(0,0,0,0,0,0,0,0,0,0,0,0,0,0,0,0,0,0,0,0,0,0,0,0,0,0,0,0,0,0,0,0,0,0,0,BP7,0,0,0,0)';
      INPUT_LOAD='(-0.01,0.01)';
    'MKB_DATA23':
      PIN_NUMBER='(0,0,0,0,0,0,0,0,0,0,0,0,0,0,0,0,0,0,0,0,0,0,0,0,0,0,0,0,0,0,0,0,0,0,0,CY7,0,0,0,0)';
      BIDIRECTIONAL='TRUE';
      INPUT_LOAD='(-0.01,0.01)';
      OUTPUT_LOAD='(1.0,-1.0)';
    'MKB_DATA12':
      PIN_NUMBER='(0,0,0,0,0,0,0,0,0,0,0,0,0,0,0,0,0,0,0,0,0,0,0,0,0,0,0,0,0,0,0,0,0,0,0,CM6,0,0,0,0)';
      BIDIRECTIONAL='TRUE';
      INPUT_LOAD='(-0.01,0.01)';
      OUTPUT_LOAD='(1.0,-1.0)';
    'MKB_DATA3':
      PIN_NUMBER='(0,0,0,0,0,0,0,0,0,0,0,0,0,0,0,0,0,0,0,0,0,0,0,0,0,0,0,0,0,0,0,0,0,0,0,CD7,0,0,0,0)';
      BIDIRECTIONAL='TRUE';
      INPUT_LOAD='(-0.01,0.01)';
      OUTPUT_LOAD='(1.0,-1.0)';
    'MKB_CHECK3':
      PIN_NUMBER='(0,0,0,0,0,0,0,0,0,0,0,0,0,0,0,0,0,0,0,0,0,0,0,0,0,0,0,0,0,0,0,0,0,0,0,CB7,0,0,0,0)';
      BIDIRECTIONAL='TRUE';
      INPUT_LOAD='(-0.01,0.01)';
      OUTPUT_LOAD='(1.0,-1.0)';
    'MKA_DQS_L5':
      PIN_NUMBER='(0,0,0,0,0,0,0,0,0,0,0,0,0,0,0,0,0,0,0,0,0,0,0,0,0,0,0,0,0,0,0,0,0,0,0,H7,0,0,0,0)';
      BIDIRECTIONAL='TRUE';
      INPUT_LOAD='(-0.01,0.01)';
      OUTPUT_LOAD='(1.0,-1.0)';
    'MKA_DQS_H1':
      PIN_NUMBER='(0,0,0,0,0,0,0,0,0,0,0,0,0,0,0,0,0,0,0,0,0,0,0,0,0,0,0,0,0,0,0,0,0,0,0,N5,0,0,0,0)';
      BIDIRECTIONAL='TRUE';
      INPUT_LOAD='(-0.01,0.01)';
      OUTPUT_LOAD='(1.0,-1.0)';
    'MKA_DATA29':
      PIN_NUMBER='(0,0,0,0,0,0,0,0,0,0,0,0,0,0,0,0,0,0,0,0,0,0,0,0,0,0,0,0,0,0,0,0,0,0,0,AH7,0,0,0,0)';
      BIDIRECTIONAL='TRUE';
      INPUT_LOAD='(-0.01,0.01)';
      OUTPUT_LOAD='(1.0,-1.0)';
    'MKA_DATA18':
      PIN_NUMBER='(0,0,0,0,0,0,0,0,0,0,0,0,0,0,0,0,0,0,0,0,0,0,0,0,0,0,0,0,0,0,0,0,0,0,0,V6,0,0,0,0)';
      BIDIRECTIONAL='TRUE';
      INPUT_LOAD='(-0.01,0.01)';
      OUTPUT_LOAD='(1.0,-1.0)';
    'MKA_DATA4':
      PIN_NUMBER='(0,0,0,0,0,0,0,0,0,0,0,0,0,0,0,0,0,0,0,0,0,0,0,0,0,0,0,0,0,0,0,0,0,0,0,J5,0,0,0,0)';
      BIDIRECTIONAL='TRUE';
      INPUT_LOAD='(-0.01,0.01)';
      OUTPUT_LOAD='(1.0,-1.0)';
    'MKB_DQS_L0':
      PIN_NUMBER='(0,0,0,0,0,0,0,0,0,0,0,0,0,0,0,0,0,0,0,0,0,0,0,0,0,0,0,0,0,0,0,0,0,0,0,CE5,0,0,0,0)';
      BIDIRECTIONAL='TRUE';
      INPUT_LOAD='(-0.01,0.01)';
      OUTPUT_LOAD='(1.0,-1.0)';
    'MKB_DATA24':
      PIN_NUMBER='(0,0,0,0,0,0,0,0,0,0,0,0,0,0,0,0,0,0,0,0,0,0,0,0,0,0,0,0,0,0,0,0,0,0,0,CY6,0,0,0,0)';
      BIDIRECTIONAL='TRUE';
      INPUT_LOAD='(-0.01,0.01)';
      OUTPUT_LOAD='(1.0,-1.0)';
    'MKB_DATA13':
      PIN_NUMBER='(0,0,0,0,0,0,0,0,0,0,0,0,0,0,0,0,0,0,0,0,0,0,0,0,0,0,0,0,0,0,0,0,0,0,0,CN7,0,0,0,0)';
      BIDIRECTIONAL='TRUE';
      INPUT_LOAD='(-0.01,0.01)';
      OUTPUT_LOAD='(1.0,-1.0)';
    'MKB_DATA4':
      PIN_NUMBER='(0,0,0,0,0,0,0,0,0,0,0,0,0,0,0,0,0,0,0,0,0,0,0,0,0,0,0,0,0,0,0,0,0,0,0,CF6,0,0,0,0)';
      BIDIRECTIONAL='TRUE';
      INPUT_LOAD='(-0.01,0.01)';
      OUTPUT_LOAD='(1.0,-1.0)';
    'MKB_CHECK4':
      PIN_NUMBER='(0,0,0,0,0,0,0,0,0,0,0,0,0,0,0,0,0,0,0,0,0,0,0,0,0,0,0,0,0,0,0,0,0,0,0,BT6,0,0,0,0)';
      BIDIRECTIONAL='TRUE';
      INPUT_LOAD='(-0.01,0.01)';
      OUTPUT_LOAD='(1.0,-1.0)';
    'MKA_DQS_L6':
      PIN_NUMBER='(0,0,0,0,0,0,0,0,0,0,0,0,0,0,0,0,0,0,0,0,0,0,0,0,0,0,0,0,0,0,0,0,0,0,0,P7,0,0,0,0)';
      BIDIRECTIONAL='TRUE';
      INPUT_LOAD='(-0.01,0.01)';
      OUTPUT_LOAD='(1.0,-1.0)';
    'MKA_DQS_H2':
      PIN_NUMBER='(0,0,0,0,0,0,0,0,0,0,0,0,0,0,0,0,0,0,0,0,0,0,0,0,0,0,0,0,0,0,0,0,0,0,0,W5,0,0,0,0)';
      BIDIRECTIONAL='TRUE';
      INPUT_LOAD='(-0.01,0.01)';
      OUTPUT_LOAD='(1.0,-1.0)';
    'MKA_DATA19':
      PIN_NUMBER='(0,0,0,0,0,0,0,0,0,0,0,0,0,0,0,0,0,0,0,0,0,0,0,0,0,0,0,0,0,0,0,0,0,0,0,W7,0,0,0,0)';
      BIDIRECTIONAL='TRUE';
      INPUT_LOAD='(-0.01,0.01)';
      OUTPUT_LOAD='(1.0,-1.0)';
    'MKA_DATA5':
      PIN_NUMBER='(0,0,0,0,0,0,0,0,0,0,0,0,0,0,0,0,0,0,0,0,0,0,0,0,0,0,0,0,0,0,0,0,0,0,0,K7,0,0,0,0)';
      BIDIRECTIONAL='TRUE';
      INPUT_LOAD='(-0.01,0.01)';
      OUTPUT_LOAD='(1.0,-1.0)';
    'MKB_DQS_L1':
      PIN_NUMBER='(0,0,0,0,0,0,0,0,0,0,0,0,0,0,0,0,0,0,0,0,0,0,0,0,0,0,0,0,0,0,0,0,0,0,0,CL5,0,0,0,0)';
      BIDIRECTIONAL='TRUE';
      INPUT_LOAD='(-0.01,0.01)';
      OUTPUT_LOAD='(1.0,-1.0)';
    'MKB_DATA25':
      PIN_NUMBER='(0,0,0,0,0,0,0,0,0,0,0,0,0,0,0,0,0,0,0,0,0,0,0,0,0,0,0,0,0,0,0,0,0,0,0,DA7,0,0,0,0)';
      BIDIRECTIONAL='TRUE';
      INPUT_LOAD='(-0.01,0.01)';
      OUTPUT_LOAD='(1.0,-1.0)';
    'MKB_DATA14':
      PIN_NUMBER='(0,0,0,0,0,0,0,0,0,0,0,0,0,0,0,0,0,0,0,0,0,0,0,0,0,0,0,0,0,0,0,0,0,0,0,CN5,0,0,0,0)';
      BIDIRECTIONAL='TRUE';
      INPUT_LOAD='(-0.01,0.01)';
      OUTPUT_LOAD='(1.0,-1.0)';
    'MKB_DATA5':
      PIN_NUMBER='(0,0,0,0,0,0,0,0,0,0,0,0,0,0,0,0,0,0,0,0,0,0,0,0,0,0,0,0,0,0,0,0,0,0,0,CG7,0,0,0,0)';
      BIDIRECTIONAL='TRUE';
      INPUT_LOAD='(-0.01,0.01)';
      OUTPUT_LOAD='(1.0,-1.0)';
    'MKB_CHECK5':
      PIN_NUMBER='(0,0,0,0,0,0,0,0,0,0,0,0,0,0,0,0,0,0,0,0,0,0,0,0,0,0,0,0,0,0,0,0,0,0,0,BU7,0,0,0,0)';
      BIDIRECTIONAL='TRUE';
      INPUT_LOAD='(-0.01,0.01)';
      OUTPUT_LOAD='(1.0,-1.0)';
    'MKA_PAR':
      PIN_NUMBER='(0,0,0,0,0,0,0,0,0,0,0,0,0,0,0,0,0,0,0,0,0,0,0,0,0,0,0,0,0,0,0,0,0,0,0,BC7,0,0,0,0)';
      OUTPUT_LOAD='(1.0,-1.0)';
    'MKA_DQS_L7':
      PIN_NUMBER='(0,0,0,0,0,0,0,0,0,0,0,0,0,0,0,0,0,0,0,0,0,0,0,0,0,0,0,0,0,0,0,0,0,0,0,Y7,0,0,0,0)';
      BIDIRECTIONAL='TRUE';
      INPUT_LOAD='(-0.01,0.01)';
      OUTPUT_LOAD='(1.0,-1.0)';
    'MKA_DQS_H3':
      PIN_NUMBER='(0,0,0,0,0,0,0,0,0,0,0,0,0,0,0,0,0,0,0,0,0,0,0,0,0,0,0,0,0,0,0,0,0,0,0,AE5,0,0,0,0)';
      BIDIRECTIONAL='TRUE';
      INPUT_LOAD='(-0.01,0.01)';
      OUTPUT_LOAD='(1.0,-1.0)';
    'MKA_DATA6':
      PIN_NUMBER='(0,0,0,0,0,0,0,0,0,0,0,0,0,0,0,0,0,0,0,0,0,0,0,0,0,0,0,0,0,0,0,0,0,0,0,K6,0,0,0,0)';
      BIDIRECTIONAL='TRUE';
      INPUT_LOAD='(-0.01,0.01)';
      OUTPUT_LOAD='(1.0,-1.0)';
    'MKB_PAR':
      PIN_NUMBER='(0,0,0,0,0,0,0,0,0,0,0,0,0,0,0,0,0,0,0,0,0,0,0,0,0,0,0,0,0,0,0,0,0,0,0,BL7,0,0,0,0)';
      OUTPUT_LOAD='(1.0,-1.0)';
    'MKB_DQS_L2':
      PIN_NUMBER='(0,0,0,0,0,0,0,0,0,0,0,0,0,0,0,0,0,0,0,0,0,0,0,0,0,0,0,0,0,0,0,0,0,0,0,CU5,0,0,0,0)';
      BIDIRECTIONAL='TRUE';
      INPUT_LOAD='(-0.01,0.01)';
      OUTPUT_LOAD='(1.0,-1.0)';
    'MKB_DATA26':
      PIN_NUMBER='(0,0,0,0,0,0,0,0,0,0,0,0,0,0,0,0,0,0,0,0,0,0,0,0,0,0,0,0,0,0,0,0,0,0,0,DA5,0,0,0,0)';
      BIDIRECTIONAL='TRUE';
      INPUT_LOAD='(-0.01,0.01)';
      OUTPUT_LOAD='(1.0,-1.0)';
    'MKB_DATA15':
      PIN_NUMBER='(0,0,0,0,0,0,0,0,0,0,0,0,0,0,0,0,0,0,0,0,0,0,0,0,0,0,0,0,0,0,0,0,0,0,0,CP7,0,0,0,0)';
      BIDIRECTIONAL='TRUE';
      INPUT_LOAD='(-0.01,0.01)';
      OUTPUT_LOAD='(1.0,-1.0)';
    'MKB_DATA6':
      PIN_NUMBER='(0,0,0,0,0,0,0,0,0,0,0,0,0,0,0,0,0,0,0,0,0,0,0,0,0,0,0,0,0,0,0,0,0,0,0,CG5,0,0,0,0)';
      BIDIRECTIONAL='TRUE';
      INPUT_LOAD='(-0.01,0.01)';
      OUTPUT_LOAD='(1.0,-1.0)';
    'MKB_CHECK6':
      PIN_NUMBER='(0,0,0,0,0,0,0,0,0,0,0,0,0,0,0,0,0,0,0,0,0,0,0,0,0,0,0,0,0,0,0,0,0,0,0,BU5,0,0,0,0)';
      BIDIRECTIONAL='TRUE';
      INPUT_LOAD='(-0.01,0.01)';
      OUTPUT_LOAD='(1.0,-1.0)';
    'MKA_DQS_L8':
      PIN_NUMBER='(0,0,0,0,0,0,0,0,0,0,0,0,0,0,0,0,0,0,0,0,0,0,0,0,0,0,0,0,0,0,0,0,0,0,0,AF7,0,0,0,0)';
      BIDIRECTIONAL='TRUE';
      INPUT_LOAD='(-0.01,0.01)';
      OUTPUT_LOAD='(1.0,-1.0)';
    'MKA_DQS_H4':
      PIN_NUMBER='(0,0,0,0,0,0,0,0,0,0,0,0,0,0,0,0,0,0,0,0,0,0,0,0,0,0,0,0,0,0,0,0,0,0,0,AL5,0,0,0,0)';
      BIDIRECTIONAL='TRUE';
      INPUT_LOAD='(-0.01,0.01)';
      OUTPUT_LOAD='(1.0,-1.0)';
    'MKA_DATA7':
      PIN_NUMBER='(0,0,0,0,0,0,0,0,0,0,0,0,0,0,0,0,0,0,0,0,0,0,0,0,0,0,0,0,0,0,0,0,0,0,0,L7,0,0,0,0)';
      BIDIRECTIONAL='TRUE';
      INPUT_LOAD='(-0.01,0.01)';
      OUTPUT_LOAD='(1.0,-1.0)';
    'MKB_DQS_L3':
      PIN_NUMBER='(0,0,0,0,0,0,0,0,0,0,0,0,0,0,0,0,0,0,0,0,0,0,0,0,0,0,0,0,0,0,0,0,0,0,0,DC5,0,0,0,0)';
      BIDIRECTIONAL='TRUE';
      INPUT_LOAD='(-0.01,0.01)';
      OUTPUT_LOAD='(1.0,-1.0)';
    'MKB_DATA27':
      PIN_NUMBER='(0,0,0,0,0,0,0,0,0,0,0,0,0,0,0,0,0,0,0,0,0,0,0,0,0,0,0,0,0,0,0,0,0,0,0,DB7,0,0,0,0)';
      BIDIRECTIONAL='TRUE';
      INPUT_LOAD='(-0.01,0.01)';
      OUTPUT_LOAD='(1.0,-1.0)';
    'MKB_DATA16':
      PIN_NUMBER='(0,0,0,0,0,0,0,0,0,0,0,0,0,0,0,0,0,0,0,0,0,0,0,0,0,0,0,0,0,0,0,0,0,0,0,CP6,0,0,0,0)';
      BIDIRECTIONAL='TRUE';
      INPUT_LOAD='(-0.01,0.01)';
      OUTPUT_LOAD='(1.0,-1.0)';
    'MKB_DATA7':
      PIN_NUMBER='(0,0,0,0,0,0,0,0,0,0,0,0,0,0,0,0,0,0,0,0,0,0,0,0,0,0,0,0,0,0,0,0,0,0,0,CH7,0,0,0,0)';
      BIDIRECTIONAL='TRUE';
      INPUT_LOAD='(-0.01,0.01)';
      OUTPUT_LOAD='(1.0,-1.0)';
    'MKB_CHECK7':
      PIN_NUMBER='(0,0,0,0,0,0,0,0,0,0,0,0,0,0,0,0,0,0,0,0,0,0,0,0,0,0,0,0,0,0,0,0,0,0,0,BV7,0,0,0,0)';
      BIDIRECTIONAL='TRUE';
      INPUT_LOAD='(-0.01,0.01)';
      OUTPUT_LOAD='(1.0,-1.0)';
    'MKB0_RSP_L':
      PIN_NUMBER='(0,0,0,0,0,0,0,0,0,0,0,0,0,0,0,0,0,0,0,0,0,0,0,0,0,0,0,0,0,0,0,0,0,0,0,BP6,0,0,0,0)';
      INPUT_LOAD='(-0.01,0.01)';
    'MKA_DQS_L9':
      PIN_NUMBER='(0,0,0,0,0,0,0,0,0,0,0,0,0,0,0,0,0,0,0,0,0,0,0,0,0,0,0,0,0,0,0,0,0,0,0,AM7,0,0,0,0)';
      BIDIRECTIONAL='TRUE';
      INPUT_LOAD='(-0.01,0.01)';
      OUTPUT_LOAD='(1.0,-1.0)';
    'MKA_DQS_H5':
      PIN_NUMBER='(0,0,0,0,0,0,0,0,0,0,0,0,0,0,0,0,0,0,0,0,0,0,0,0,0,0,0,0,0,0,0,0,0,0,0,J7,0,0,0,0)';
      BIDIRECTIONAL='TRUE';
      INPUT_LOAD='(-0.01,0.01)';
      OUTPUT_LOAD='(1.0,-1.0)';
    'MKA_DATA8':
      PIN_NUMBER='(0,0,0,0,0,0,0,0,0,0,0,0,0,0,0,0,0,0,0,0,0,0,0,0,0,0,0,0,0,0,0,0,0,0,0,L5,0,0,0,0)';
      BIDIRECTIONAL='TRUE';
      INPUT_LOAD='(-0.01,0.01)';
      OUTPUT_LOAD='(1.0,-1.0)';
    'MKB_DQS_L4':
      PIN_NUMBER='(0,0,0,0,0,0,0,0,0,0,0,0,0,0,0,0,0,0,0,0,0,0,0,0,0,0,0,0,0,0,0,0,0,0,0,BW7,0,0,0,0)';
      BIDIRECTIONAL='TRUE';
      INPUT_LOAD='(-0.01,0.01)';
      OUTPUT_LOAD='(1.0,-1.0)';
    'MKB_DQS_H0':
      PIN_NUMBER='(0,0,0,0,0,0,0,0,0,0,0,0,0,0,0,0,0,0,0,0,0,0,0,0,0,0,0,0,0,0,0,0,0,0,0,CD6,0,0,0,0)';
      BIDIRECTIONAL='TRUE';
      INPUT_LOAD='(-0.01,0.01)';
      OUTPUT_LOAD='(1.0,-1.0)';
    'MKB_DATA28':
      PIN_NUMBER='(0,0,0,0,0,0,0,0,0,0,0,0,0,0,0,0,0,0,0,0,0,0,0,0,0,0,0,0,0,0,0,0,0,0,0,DD6,0,0,0,0)';
      BIDIRECTIONAL='TRUE';
      INPUT_LOAD='(-0.01,0.01)';
      OUTPUT_LOAD='(1.0,-1.0)';
    'MKB_DATA17':
      PIN_NUMBER='(0,0,0,0,0,0,0,0,0,0,0,0,0,0,0,0,0,0,0,0,0,0,0,0,0,0,0,0,0,0,0,0,0,0,0,CR7,0,0,0,0)';
      BIDIRECTIONAL='TRUE';
      INPUT_LOAD='(-0.01,0.01)';
      OUTPUT_LOAD='(1.0,-1.0)';
    'MKB_DATA8':
      PIN_NUMBER='(0,0,0,0,0,0,0,0,0,0,0,0,0,0,0,0,0,0,0,0,0,0,0,0,0,0,0,0,0,0,0,0,0,0,0,CH6,0,0,0,0)';
      BIDIRECTIONAL='TRUE';
      INPUT_LOAD='(-0.01,0.01)';
      OUTPUT_LOAD='(1.0,-1.0)';
    'MKB1_RSP_L':
      PIN_NUMBER='(0,0,0,0,0,0,0,0,0,0,0,0,0,0,0,0,0,0,0,0,0,0,0,0,0,0,0,0,0,0,0,0,0,0,0,BR5,0,0,0,0)';
      INPUT_LOAD='(-0.01,0.01)';
    'MKA_DQS_H6':
      PIN_NUMBER='(0,0,0,0,0,0,0,0,0,0,0,0,0,0,0,0,0,0,0,0,0,0,0,0,0,0,0,0,0,0,0,0,0,0,0,R7,0,0,0,0)';
      BIDIRECTIONAL='TRUE';
      INPUT_LOAD='(-0.01,0.01)';
      OUTPUT_LOAD='(1.0,-1.0)';
    'MKA_DATA9':
      PIN_NUMBER='(0,0,0,0,0,0,0,0,0,0,0,0,0,0,0,0,0,0,0,0,0,0,0,0,0,0,0,0,0,0,0,0,0,0,0,M7,0,0,0,0)';
      BIDIRECTIONAL='TRUE';
      INPUT_LOAD='(-0.01,0.01)';
      OUTPUT_LOAD='(1.0,-1.0)';
    'MKB_DQS_L5':
      PIN_NUMBER='(0,0,0,0,0,0,0,0,0,0,0,0,0,0,0,0,0,0,0,0,0,0,0,0,0,0,0,0,0,0,0,0,0,0,0,CE7,0,0,0,0)';
      BIDIRECTIONAL='TRUE';
      INPUT_LOAD='(-0.01,0.01)';
      OUTPUT_LOAD='(1.0,-1.0)';
    'MKB_DQS_H1':
      PIN_NUMBER='(0,0,0,0,0,0,0,0,0,0,0,0,0,0,0,0,0,0,0,0,0,0,0,0,0,0,0,0,0,0,0,0,0,0,0,CK6,0,0,0,0)';
      BIDIRECTIONAL='TRUE';
      INPUT_LOAD='(-0.01,0.01)';
      OUTPUT_LOAD='(1.0,-1.0)';
    'MKB_DATA29':
      PIN_NUMBER='(0,0,0,0,0,0,0,0,0,0,0,0,0,0,0,0,0,0,0,0,0,0,0,0,0,0,0,0,0,0,0,0,0,0,0,DE7,0,0,0,0)';
      BIDIRECTIONAL='TRUE';
      INPUT_LOAD='(-0.01,0.01)';
      OUTPUT_LOAD='(1.0,-1.0)';
    'MKB_DATA18':
      PIN_NUMBER='(0,0,0,0,0,0,0,0,0,0,0,0,0,0,0,0,0,0,0,0,0,0,0,0,0,0,0,0,0,0,0,0,0,0,0,CR5,0,0,0,0)';
      BIDIRECTIONAL='TRUE';
      INPUT_LOAD='(-0.01,0.01)';
      OUTPUT_LOAD='(1.0,-1.0)';
    'MKB_DATA9':
      PIN_NUMBER='(0,0,0,0,0,0,0,0,0,0,0,0,0,0,0,0,0,0,0,0,0,0,0,0,0,0,0,0,0,0,0,0,0,0,0,CJ7,0,0,0,0)';
      BIDIRECTIONAL='TRUE';
      INPUT_LOAD='(-0.01,0.01)';
      OUTPUT_LOAD='(1.0,-1.0)';
    'MKA_DQS_H7':
      PIN_NUMBER='(0,0,0,0,0,0,0,0,0,0,0,0,0,0,0,0,0,0,0,0,0,0,0,0,0,0,0,0,0,0,0,0,0,0,0,AA7,0,0,0,0)';
      BIDIRECTIONAL='TRUE';
      INPUT_LOAD='(-0.01,0.01)';
      OUTPUT_LOAD='(1.0,-1.0)';
    'MKA_CA0':
      PIN_NUMBER='(0,0,0,0,0,0,0,0,0,0,0,0,0,0,0,0,0,0,0,0,0,0,0,0,0,0,0,0,0,0,0,0,0,0,0,AW5,0,0,0,0)';
      OUTPUT_LOAD='(1.0,-1.0)';
    'MKA0_CS_L0':
      PIN_NUMBER='(0,0,0,0,0,0,0,0,0,0,0,0,0,0,0,0,0,0,0,0,0,0,0,0,0,0,0,0,0,0,0,0,0,0,0,AU5,0,0,0,0)';
      OUTPUT_LOAD='(1.0,-1.0)';
    'TEST39K':
      PIN_NUMBER='(0,0,0,0,0,0,0,0,0,0,0,0,0,0,0,0,0,0,0,0,0,0,0,0,0,0,0,0,0,0,0,0,0,0,0,BF7,0,0,0,0)';
      OUTPUT_LOAD='(1.0,-1.0)';
    'VSS_BV46':
      PIN_NUMBER='(0,0,0,0,0,0,0,0,0,0,0,0,0,0,0,0,0,0,0,0,0,0,0,0,0,0,0,0,0,0,0,0,0,0,0,0,BV46,0,0,0)';
      PINUSE='POWER';
      NO_LOAD_CHECK='Both';
      NO_IO_CHECK='Both';
      NO_ASSERT_CHECK='TRUE';
      NO_DIR_CHECK='TRUE';
      ALLOW_CONNECT='TRUE';
    'VSS_BV47':
      PIN_NUMBER='(0,0,0,0,0,0,0,0,0,0,0,0,0,0,0,0,0,0,0,0,0,0,0,0,0,0,0,0,0,0,0,0,0,0,0,0,BV47,0,0,0)';
      PINUSE='POWER';
      NO_LOAD_CHECK='Both';
      NO_IO_CHECK='Both';
      NO_ASSERT_CHECK='TRUE';
      NO_DIR_CHECK='TRUE';
      ALLOW_CONNECT='TRUE';
    'VSS_BV48':
      PIN_NUMBER='(0,0,0,0,0,0,0,0,0,0,0,0,0,0,0,0,0,0,0,0,0,0,0,0,0,0,0,0,0,0,0,0,0,0,0,0,BV48,0,0,0)';
      PINUSE='POWER';
      NO_LOAD_CHECK='Both';
      NO_IO_CHECK='Both';
      NO_ASSERT_CHECK='TRUE';
      NO_DIR_CHECK='TRUE';
      ALLOW_CONNECT='TRUE';
    'VSS_BV49':
      PIN_NUMBER='(0,0,0,0,0,0,0,0,0,0,0,0,0,0,0,0,0,0,0,0,0,0,0,0,0,0,0,0,0,0,0,0,0,0,0,0,BV49,0,0,0)';
      PINUSE='POWER';
      NO_LOAD_CHECK='Both';
      NO_IO_CHECK='Both';
      NO_ASSERT_CHECK='TRUE';
      NO_DIR_CHECK='TRUE';
      ALLOW_CONNECT='TRUE';
    'VSS_BV50':
      PIN_NUMBER='(0,0,0,0,0,0,0,0,0,0,0,0,0,0,0,0,0,0,0,0,0,0,0,0,0,0,0,0,0,0,0,0,0,0,0,0,BV50,0,0,0)';
      PINUSE='POWER';
      NO_LOAD_CHECK='Both';
      NO_IO_CHECK='Both';
      NO_ASSERT_CHECK='TRUE';
      NO_DIR_CHECK='TRUE';
      ALLOW_CONNECT='TRUE';
    'VSS_BV51':
      PIN_NUMBER='(0,0,0,0,0,0,0,0,0,0,0,0,0,0,0,0,0,0,0,0,0,0,0,0,0,0,0,0,0,0,0,0,0,0,0,0,BV51,0,0,0)';
      PINUSE='POWER';
      NO_LOAD_CHECK='Both';
      NO_IO_CHECK='Both';
      NO_ASSERT_CHECK='TRUE';
      NO_DIR_CHECK='TRUE';
      ALLOW_CONNECT='TRUE';
    'VSS_BV52':
      PIN_NUMBER='(0,0,0,0,0,0,0,0,0,0,0,0,0,0,0,0,0,0,0,0,0,0,0,0,0,0,0,0,0,0,0,0,0,0,0,0,BV52,0,0,0)';
      PINUSE='POWER';
      NO_LOAD_CHECK='Both';
      NO_IO_CHECK='Both';
      NO_ASSERT_CHECK='TRUE';
      NO_DIR_CHECK='TRUE';
      ALLOW_CONNECT='TRUE';
    'VSS_BV53':
      PIN_NUMBER='(0,0,0,0,0,0,0,0,0,0,0,0,0,0,0,0,0,0,0,0,0,0,0,0,0,0,0,0,0,0,0,0,0,0,0,0,BV53,0,0,0)';
      PINUSE='POWER';
      NO_LOAD_CHECK='Both';
      NO_IO_CHECK='Both';
      NO_ASSERT_CHECK='TRUE';
      NO_DIR_CHECK='TRUE';
      ALLOW_CONNECT='TRUE';
    'VSS_BV59':
      PIN_NUMBER='(0,0,0,0,0,0,0,0,0,0,0,0,0,0,0,0,0,0,0,0,0,0,0,0,0,0,0,0,0,0,0,0,0,0,0,0,BV59,0,0,0)';
      PINUSE='POWER';
      NO_LOAD_CHECK='Both';
      NO_IO_CHECK='Both';
      NO_ASSERT_CHECK='TRUE';
      NO_DIR_CHECK='TRUE';
      ALLOW_CONNECT='TRUE';
    'VSS_BV61':
      PIN_NUMBER='(0,0,0,0,0,0,0,0,0,0,0,0,0,0,0,0,0,0,0,0,0,0,0,0,0,0,0,0,0,0,0,0,0,0,0,0,BV61,0,0,0)';
      PINUSE='POWER';
      NO_LOAD_CHECK='Both';
      NO_IO_CHECK='Both';
      NO_ASSERT_CHECK='TRUE';
      NO_DIR_CHECK='TRUE';
      ALLOW_CONNECT='TRUE';
    'VSS_BV66':
      PIN_NUMBER='(0,0,0,0,0,0,0,0,0,0,0,0,0,0,0,0,0,0,0,0,0,0,0,0,0,0,0,0,0,0,0,0,0,0,0,0,BV66,0,0,0)';
      PINUSE='POWER';
      NO_LOAD_CHECK='Both';
      NO_IO_CHECK='Both';
      NO_ASSERT_CHECK='TRUE';
      NO_DIR_CHECK='TRUE';
      ALLOW_CONNECT='TRUE';
    'VSS_BV68':
      PIN_NUMBER='(0,0,0,0,0,0,0,0,0,0,0,0,0,0,0,0,0,0,0,0,0,0,0,0,0,0,0,0,0,0,0,0,0,0,0,0,BV68,0,0,0)';
      PINUSE='POWER';
      NO_LOAD_CHECK='Both';
      NO_IO_CHECK='Both';
      NO_ASSERT_CHECK='TRUE';
      NO_DIR_CHECK='TRUE';
      ALLOW_CONNECT='TRUE';
    'VSS_BV73':
      PIN_NUMBER='(0,0,0,0,0,0,0,0,0,0,0,0,0,0,0,0,0,0,0,0,0,0,0,0,0,0,0,0,0,0,0,0,0,0,0,0,BV73,0,0,0)';
      PINUSE='POWER';
      NO_LOAD_CHECK='Both';
      NO_IO_CHECK='Both';
      NO_ASSERT_CHECK='TRUE';
      NO_DIR_CHECK='TRUE';
      ALLOW_CONNECT='TRUE';
    'VSS_BW1':
      PIN_NUMBER='(0,0,0,0,0,0,0,0,0,0,0,0,0,0,0,0,0,0,0,0,0,0,0,0,0,0,0,0,0,0,0,0,0,0,0,0,BW1,0,0,0)';
      PINUSE='POWER';
      NO_LOAD_CHECK='Both';
      NO_IO_CHECK='Both';
      NO_ASSERT_CHECK='TRUE';
      NO_DIR_CHECK='TRUE';
      ALLOW_CONNECT='TRUE';
    'VSS_BW4':
      PIN_NUMBER='(0,0,0,0,0,0,0,0,0,0,0,0,0,0,0,0,0,0,0,0,0,0,0,0,0,0,0,0,0,0,0,0,0,0,0,0,BW4,0,0,0)';
      PINUSE='POWER';
      NO_LOAD_CHECK='Both';
      NO_IO_CHECK='Both';
      NO_ASSERT_CHECK='TRUE';
      NO_DIR_CHECK='TRUE';
      ALLOW_CONNECT='TRUE';
    'VSS_BW6':
      PIN_NUMBER='(0,0,0,0,0,0,0,0,0,0,0,0,0,0,0,0,0,0,0,0,0,0,0,0,0,0,0,0,0,0,0,0,0,0,0,0,BW6,0,0,0)';
      PINUSE='POWER';
      NO_LOAD_CHECK='Both';
      NO_IO_CHECK='Both';
      NO_ASSERT_CHECK='TRUE';
      NO_DIR_CHECK='TRUE';
      ALLOW_CONNECT='TRUE';
    'VSS_BW8':
      PIN_NUMBER='(0,0,0,0,0,0,0,0,0,0,0,0,0,0,0,0,0,0,0,0,0,0,0,0,0,0,0,0,0,0,0,0,0,0,0,0,BW8,0,0,0)';
      PINUSE='POWER';
      NO_LOAD_CHECK='Both';
      NO_IO_CHECK='Both';
      NO_ASSERT_CHECK='TRUE';
      NO_DIR_CHECK='TRUE';
      ALLOW_CONNECT='TRUE';
    'VSS_BW11':
      PIN_NUMBER='(0,0,0,0,0,0,0,0,0,0,0,0,0,0,0,0,0,0,0,0,0,0,0,0,0,0,0,0,0,0,0,0,0,0,0,0,BW11,0,0,0)';
      PINUSE='POWER';
      NO_LOAD_CHECK='Both';
      NO_IO_CHECK='Both';
      NO_ASSERT_CHECK='TRUE';
      NO_DIR_CHECK='TRUE';
      ALLOW_CONNECT='TRUE';
    'VSS_BW13':
      PIN_NUMBER='(0,0,0,0,0,0,0,0,0,0,0,0,0,0,0,0,0,0,0,0,0,0,0,0,0,0,0,0,0,0,0,0,0,0,0,0,BW13,0,0,0)';
      PINUSE='POWER';
      NO_LOAD_CHECK='Both';
      NO_IO_CHECK='Both';
      NO_ASSERT_CHECK='TRUE';
      NO_DIR_CHECK='TRUE';
      ALLOW_CONNECT='TRUE';
    'VSS_BW15':
      PIN_NUMBER='(0,0,0,0,0,0,0,0,0,0,0,0,0,0,0,0,0,0,0,0,0,0,0,0,0,0,0,0,0,0,0,0,0,0,0,0,BW15,0,0,0)';
      PINUSE='POWER';
      NO_LOAD_CHECK='Both';
      NO_IO_CHECK='Both';
      NO_ASSERT_CHECK='TRUE';
      NO_DIR_CHECK='TRUE';
      ALLOW_CONNECT='TRUE';
    'VSS_BW18':
      PIN_NUMBER='(0,0,0,0,0,0,0,0,0,0,0,0,0,0,0,0,0,0,0,0,0,0,0,0,0,0,0,0,0,0,0,0,0,0,0,0,BW18,0,0,0)';
      PINUSE='POWER';
      NO_LOAD_CHECK='Both';
      NO_IO_CHECK='Both';
      NO_ASSERT_CHECK='TRUE';
      NO_DIR_CHECK='TRUE';
      ALLOW_CONNECT='TRUE';
    'VSS_BW20':
      PIN_NUMBER='(0,0,0,0,0,0,0,0,0,0,0,0,0,0,0,0,0,0,0,0,0,0,0,0,0,0,0,0,0,0,0,0,0,0,0,0,BW20,0,0,0)';
      PINUSE='POWER';
      NO_LOAD_CHECK='Both';
      NO_IO_CHECK='Both';
      NO_ASSERT_CHECK='TRUE';
      NO_DIR_CHECK='TRUE';
      ALLOW_CONNECT='TRUE';
    'VSS_BW22':
      PIN_NUMBER='(0,0,0,0,0,0,0,0,0,0,0,0,0,0,0,0,0,0,0,0,0,0,0,0,0,0,0,0,0,0,0,0,0,0,0,0,BW22,0,0,0)';
      PINUSE='POWER';
      NO_LOAD_CHECK='Both';
      NO_IO_CHECK='Both';
      NO_ASSERT_CHECK='TRUE';
      NO_DIR_CHECK='TRUE';
      ALLOW_CONNECT='TRUE';
    'VSS_BW28':
      PIN_NUMBER='(0,0,0,0,0,0,0,0,0,0,0,0,0,0,0,0,0,0,0,0,0,0,0,0,0,0,0,0,0,0,0,0,0,0,0,0,BW28,0,0,0)';
      PINUSE='POWER';
      NO_LOAD_CHECK='Both';
      NO_IO_CHECK='Both';
      NO_ASSERT_CHECK='TRUE';
      NO_DIR_CHECK='TRUE';
      ALLOW_CONNECT='TRUE';
    'VSS_BW31':
      PIN_NUMBER='(0,0,0,0,0,0,0,0,0,0,0,0,0,0,0,0,0,0,0,0,0,0,0,0,0,0,0,0,0,0,0,0,0,0,0,0,BW31,0,0,0)';
      PINUSE='POWER';
      NO_LOAD_CHECK='Both';
      NO_IO_CHECK='Both';
      NO_ASSERT_CHECK='TRUE';
      NO_DIR_CHECK='TRUE';
      ALLOW_CONNECT='TRUE';
    'VSS_BW34':
      PIN_NUMBER='(0,0,0,0,0,0,0,0,0,0,0,0,0,0,0,0,0,0,0,0,0,0,0,0,0,0,0,0,0,0,0,0,0,0,0,0,BW34,0,0,0)';
      PINUSE='POWER';
      NO_LOAD_CHECK='Both';
      NO_IO_CHECK='Both';
      NO_ASSERT_CHECK='TRUE';
      NO_DIR_CHECK='TRUE';
      ALLOW_CONNECT='TRUE';
    'VSS_BW42':
      PIN_NUMBER='(0,0,0,0,0,0,0,0,0,0,0,0,0,0,0,0,0,0,0,0,0,0,0,0,0,0,0,0,0,0,0,0,0,0,0,0,BW42,0,0,0)';
      PINUSE='POWER';
      NO_LOAD_CHECK='Both';
      NO_IO_CHECK='Both';
      NO_ASSERT_CHECK='TRUE';
      NO_DIR_CHECK='TRUE';
      ALLOW_CONNECT='TRUE';
    'VSS_BW45':
      PIN_NUMBER='(0,0,0,0,0,0,0,0,0,0,0,0,0,0,0,0,0,0,0,0,0,0,0,0,0,0,0,0,0,0,0,0,0,0,0,0,BW45,0,0,0)';
      PINUSE='POWER';
      NO_LOAD_CHECK='Both';
      NO_IO_CHECK='Both';
      NO_ASSERT_CHECK='TRUE';
      NO_DIR_CHECK='TRUE';
      ALLOW_CONNECT='TRUE';
    'VSS_BW48':
      PIN_NUMBER='(0,0,0,0,0,0,0,0,0,0,0,0,0,0,0,0,0,0,0,0,0,0,0,0,0,0,0,0,0,0,0,0,0,0,0,0,BW48,0,0,0)';
      PINUSE='POWER';
      NO_LOAD_CHECK='Both';
      NO_IO_CHECK='Both';
      NO_ASSERT_CHECK='TRUE';
      NO_DIR_CHECK='TRUE';
      ALLOW_CONNECT='TRUE';
    'VSS_BW51':
      PIN_NUMBER='(0,0,0,0,0,0,0,0,0,0,0,0,0,0,0,0,0,0,0,0,0,0,0,0,0,0,0,0,0,0,0,0,0,0,0,0,BW51,0,0,0)';
      PINUSE='POWER';
      NO_LOAD_CHECK='Both';
      NO_IO_CHECK='Both';
      NO_ASSERT_CHECK='TRUE';
      NO_DIR_CHECK='TRUE';
      ALLOW_CONNECT='TRUE';
    'VSS_BW54':
      PIN_NUMBER='(0,0,0,0,0,0,0,0,0,0,0,0,0,0,0,0,0,0,0,0,0,0,0,0,0,0,0,0,0,0,0,0,0,0,0,0,BW54,0,0,0)';
      PINUSE='POWER';
      NO_LOAD_CHECK='Both';
      NO_IO_CHECK='Both';
      NO_ASSERT_CHECK='TRUE';
      NO_DIR_CHECK='TRUE';
      ALLOW_CONNECT='TRUE';
    'VSS_BW56':
      PIN_NUMBER='(0,0,0,0,0,0,0,0,0,0,0,0,0,0,0,0,0,0,0,0,0,0,0,0,0,0,0,0,0,0,0,0,0,0,0,0,BW56,0,0,0)';
      PINUSE='POWER';
      NO_LOAD_CHECK='Both';
      NO_IO_CHECK='Both';
      NO_ASSERT_CHECK='TRUE';
      NO_DIR_CHECK='TRUE';
      ALLOW_CONNECT='TRUE';
    'VSS_BW58':
      PIN_NUMBER='(0,0,0,0,0,0,0,0,0,0,0,0,0,0,0,0,0,0,0,0,0,0,0,0,0,0,0,0,0,0,0,0,0,0,0,0,BW58,0,0,0)';
      PINUSE='POWER';
      NO_LOAD_CHECK='Both';
      NO_IO_CHECK='Both';
      NO_ASSERT_CHECK='TRUE';
      NO_DIR_CHECK='TRUE';
      ALLOW_CONNECT='TRUE';
    'VSS_BW61':
      PIN_NUMBER='(0,0,0,0,0,0,0,0,0,0,0,0,0,0,0,0,0,0,0,0,0,0,0,0,0,0,0,0,0,0,0,0,0,0,0,0,BW61,0,0,0)';
      PINUSE='POWER';
      NO_LOAD_CHECK='Both';
      NO_IO_CHECK='Both';
      NO_ASSERT_CHECK='TRUE';
      NO_DIR_CHECK='TRUE';
      ALLOW_CONNECT='TRUE';
    'VSS_BW63':
      PIN_NUMBER='(0,0,0,0,0,0,0,0,0,0,0,0,0,0,0,0,0,0,0,0,0,0,0,0,0,0,0,0,0,0,0,0,0,0,0,0,BW63,0,0,0)';
      PINUSE='POWER';
      NO_LOAD_CHECK='Both';
      NO_IO_CHECK='Both';
      NO_ASSERT_CHECK='TRUE';
      NO_DIR_CHECK='TRUE';
      ALLOW_CONNECT='TRUE';
    'VSS_BW65':
      PIN_NUMBER='(0,0,0,0,0,0,0,0,0,0,0,0,0,0,0,0,0,0,0,0,0,0,0,0,0,0,0,0,0,0,0,0,0,0,0,0,BW65,0,0,0)';
      PINUSE='POWER';
      NO_LOAD_CHECK='Both';
      NO_IO_CHECK='Both';
      NO_ASSERT_CHECK='TRUE';
      NO_DIR_CHECK='TRUE';
      ALLOW_CONNECT='TRUE';
    'VSS_BW68':
      PIN_NUMBER='(0,0,0,0,0,0,0,0,0,0,0,0,0,0,0,0,0,0,0,0,0,0,0,0,0,0,0,0,0,0,0,0,0,0,0,0,BW68,0,0,0)';
      PINUSE='POWER';
      NO_LOAD_CHECK='Both';
      NO_IO_CHECK='Both';
      NO_ASSERT_CHECK='TRUE';
      NO_DIR_CHECK='TRUE';
      ALLOW_CONNECT='TRUE';
    'VSS_BW70':
      PIN_NUMBER='(0,0,0,0,0,0,0,0,0,0,0,0,0,0,0,0,0,0,0,0,0,0,0,0,0,0,0,0,0,0,0,0,0,0,0,0,BW70,0,0,0)';
      PINUSE='POWER';
      NO_LOAD_CHECK='Both';
      NO_IO_CHECK='Both';
      NO_ASSERT_CHECK='TRUE';
      NO_DIR_CHECK='TRUE';
      ALLOW_CONNECT='TRUE';
    'VSS_BW72':
      PIN_NUMBER='(0,0,0,0,0,0,0,0,0,0,0,0,0,0,0,0,0,0,0,0,0,0,0,0,0,0,0,0,0,0,0,0,0,0,0,0,BW72,0,0,0)';
      PINUSE='POWER';
      NO_LOAD_CHECK='Both';
      NO_IO_CHECK='Both';
      NO_ASSERT_CHECK='TRUE';
      NO_DIR_CHECK='TRUE';
      ALLOW_CONNECT='TRUE';
    'VSS_BW75':
      PIN_NUMBER='(0,0,0,0,0,0,0,0,0,0,0,0,0,0,0,0,0,0,0,0,0,0,0,0,0,0,0,0,0,0,0,0,0,0,0,0,BW75,0,0,0)';
      PINUSE='POWER';
      NO_LOAD_CHECK='Both';
      NO_IO_CHECK='Both';
      NO_ASSERT_CHECK='TRUE';
      NO_DIR_CHECK='TRUE';
      ALLOW_CONNECT='TRUE';
    'VSS_BY3':
      PIN_NUMBER='(0,0,0,0,0,0,0,0,0,0,0,0,0,0,0,0,0,0,0,0,0,0,0,0,0,0,0,0,0,0,0,0,0,0,0,0,BY3,0,0,0)';
      PINUSE='POWER';
      NO_LOAD_CHECK='Both';
      NO_IO_CHECK='Both';
      NO_ASSERT_CHECK='TRUE';
      NO_DIR_CHECK='TRUE';
      ALLOW_CONNECT='TRUE';
    'VSS_BY5':
      PIN_NUMBER='(0,0,0,0,0,0,0,0,0,0,0,0,0,0,0,0,0,0,0,0,0,0,0,0,0,0,0,0,0,0,0,0,0,0,0,0,BY5,0,0,0)';
      PINUSE='POWER';
      NO_LOAD_CHECK='Both';
      NO_IO_CHECK='Both';
      NO_ASSERT_CHECK='TRUE';
      NO_DIR_CHECK='TRUE';
      ALLOW_CONNECT='TRUE';
    'VSS_BY8':
      PIN_NUMBER='(0,0,0,0,0,0,0,0,0,0,0,0,0,0,0,0,0,0,0,0,0,0,0,0,0,0,0,0,0,0,0,0,0,0,0,0,BY8,0,0,0)';
      PINUSE='POWER';
      NO_LOAD_CHECK='Both';
      NO_IO_CHECK='Both';
      NO_ASSERT_CHECK='TRUE';
      NO_DIR_CHECK='TRUE';
      ALLOW_CONNECT='TRUE';
    'VSS_BY10':
      PIN_NUMBER='(0,0,0,0,0,0,0,0,0,0,0,0,0,0,0,0,0,0,0,0,0,0,0,0,0,0,0,0,0,0,0,0,0,0,0,0,BY10,0,0,0)';
      PINUSE='POWER';
      NO_LOAD_CHECK='Both';
      NO_IO_CHECK='Both';
      NO_ASSERT_CHECK='TRUE';
      NO_DIR_CHECK='TRUE';
      ALLOW_CONNECT='TRUE';
    'VSS_BY12':
      PIN_NUMBER='(0,0,0,0,0,0,0,0,0,0,0,0,0,0,0,0,0,0,0,0,0,0,0,0,0,0,0,0,0,0,0,0,0,0,0,0,BY12,0,0,0)';
      PINUSE='POWER';
      NO_LOAD_CHECK='Both';
      NO_IO_CHECK='Both';
      NO_ASSERT_CHECK='TRUE';
      NO_DIR_CHECK='TRUE';
      ALLOW_CONNECT='TRUE';
    'VSS_BY15':
      PIN_NUMBER='(0,0,0,0,0,0,0,0,0,0,0,0,0,0,0,0,0,0,0,0,0,0,0,0,0,0,0,0,0,0,0,0,0,0,0,0,BY15,0,0,0)';
      PINUSE='POWER';
      NO_LOAD_CHECK='Both';
      NO_IO_CHECK='Both';
      NO_ASSERT_CHECK='TRUE';
      NO_DIR_CHECK='TRUE';
      ALLOW_CONNECT='TRUE';
    'VSS_BY17':
      PIN_NUMBER='(0,0,0,0,0,0,0,0,0,0,0,0,0,0,0,0,0,0,0,0,0,0,0,0,0,0,0,0,0,0,0,0,0,0,0,0,BY17,0,0,0)';
      PINUSE='POWER';
      NO_LOAD_CHECK='Both';
      NO_IO_CHECK='Both';
      NO_ASSERT_CHECK='TRUE';
      NO_DIR_CHECK='TRUE';
      ALLOW_CONNECT='TRUE';
    'VSS_BY19':
      PIN_NUMBER='(0,0,0,0,0,0,0,0,0,0,0,0,0,0,0,0,0,0,0,0,0,0,0,0,0,0,0,0,0,0,0,0,0,0,0,0,BY19,0,0,0)';
      PINUSE='POWER';
      NO_LOAD_CHECK='Both';
      NO_IO_CHECK='Both';
      NO_ASSERT_CHECK='TRUE';
      NO_DIR_CHECK='TRUE';
      ALLOW_CONNECT='TRUE';
    'VSS_BY22':
      PIN_NUMBER='(0,0,0,0,0,0,0,0,0,0,0,0,0,0,0,0,0,0,0,0,0,0,0,0,0,0,0,0,0,0,0,0,0,0,0,0,BY22,0,0,0)';
      PINUSE='POWER';
      NO_LOAD_CHECK='Both';
      NO_IO_CHECK='Both';
      NO_ASSERT_CHECK='TRUE';
      NO_DIR_CHECK='TRUE';
      ALLOW_CONNECT='TRUE';
    'VSS_BY25':
      PIN_NUMBER='(0,0,0,0,0,0,0,0,0,0,0,0,0,0,0,0,0,0,0,0,0,0,0,0,0,0,0,0,0,0,0,0,0,0,0,0,BY25,0,0,0)';
      PINUSE='POWER';
      NO_LOAD_CHECK='Both';
      NO_IO_CHECK='Both';
      NO_ASSERT_CHECK='TRUE';
      NO_DIR_CHECK='TRUE';
      ALLOW_CONNECT='TRUE';
    'VSS_BY28':
      PIN_NUMBER='(0,0,0,0,0,0,0,0,0,0,0,0,0,0,0,0,0,0,0,0,0,0,0,0,0,0,0,0,0,0,0,0,0,0,0,0,BY28,0,0,0)';
      PINUSE='POWER';
      NO_LOAD_CHECK='Both';
      NO_IO_CHECK='Both';
      NO_ASSERT_CHECK='TRUE';
      NO_DIR_CHECK='TRUE';
      ALLOW_CONNECT='TRUE';
    'VSS_BY31':
      PIN_NUMBER='(0,0,0,0,0,0,0,0,0,0,0,0,0,0,0,0,0,0,0,0,0,0,0,0,0,0,0,0,0,0,0,0,0,0,0,0,BY31,0,0,0)';
      PINUSE='POWER';
      NO_LOAD_CHECK='Both';
      NO_IO_CHECK='Both';
      NO_ASSERT_CHECK='TRUE';
      NO_DIR_CHECK='TRUE';
      ALLOW_CONNECT='TRUE';
    'VSS_BY34':
      PIN_NUMBER='(0,0,0,0,0,0,0,0,0,0,0,0,0,0,0,0,0,0,0,0,0,0,0,0,0,0,0,0,0,0,0,0,0,0,0,0,BY34,0,0,0)';
      PINUSE='POWER';
      NO_LOAD_CHECK='Both';
      NO_IO_CHECK='Both';
      NO_ASSERT_CHECK='TRUE';
      NO_DIR_CHECK='TRUE';
      ALLOW_CONNECT='TRUE';
    'VSS_BY37':
      PIN_NUMBER='(0,0,0,0,0,0,0,0,0,0,0,0,0,0,0,0,0,0,0,0,0,0,0,0,0,0,0,0,0,0,0,0,0,0,0,0,BY37,0,0,0)';
      PINUSE='POWER';
      NO_LOAD_CHECK='Both';
      NO_IO_CHECK='Both';
      NO_ASSERT_CHECK='TRUE';
      NO_DIR_CHECK='TRUE';
      ALLOW_CONNECT='TRUE';
    'VSS_BY39':
      PIN_NUMBER='(0,0,0,0,0,0,0,0,0,0,0,0,0,0,0,0,0,0,0,0,0,0,0,0,0,0,0,0,0,0,0,0,0,0,0,0,BY39,0,0,0)';
      PINUSE='POWER';
      NO_LOAD_CHECK='Both';
      NO_IO_CHECK='Both';
      NO_ASSERT_CHECK='TRUE';
      NO_DIR_CHECK='TRUE';
      ALLOW_CONNECT='TRUE';
    'VSS_BY42':
      PIN_NUMBER='(0,0,0,0,0,0,0,0,0,0,0,0,0,0,0,0,0,0,0,0,0,0,0,0,0,0,0,0,0,0,0,0,0,0,0,0,BY42,0,0,0)';
      PINUSE='POWER';
      NO_LOAD_CHECK='Both';
      NO_IO_CHECK='Both';
      NO_ASSERT_CHECK='TRUE';
      NO_DIR_CHECK='TRUE';
      ALLOW_CONNECT='TRUE';
    'VSS_BY45':
      PIN_NUMBER='(0,0,0,0,0,0,0,0,0,0,0,0,0,0,0,0,0,0,0,0,0,0,0,0,0,0,0,0,0,0,0,0,0,0,0,0,BY45,0,0,0)';
      PINUSE='POWER';
      NO_LOAD_CHECK='Both';
      NO_IO_CHECK='Both';
      NO_ASSERT_CHECK='TRUE';
      NO_DIR_CHECK='TRUE';
      ALLOW_CONNECT='TRUE';
    'VSS_BY48':
      PIN_NUMBER='(0,0,0,0,0,0,0,0,0,0,0,0,0,0,0,0,0,0,0,0,0,0,0,0,0,0,0,0,0,0,0,0,0,0,0,0,BY48,0,0,0)';
      PINUSE='POWER';
      NO_LOAD_CHECK='Both';
      NO_IO_CHECK='Both';
      NO_ASSERT_CHECK='TRUE';
      NO_DIR_CHECK='TRUE';
      ALLOW_CONNECT='TRUE';
    'VSS_BY51':
      PIN_NUMBER='(0,0,0,0,0,0,0,0,0,0,0,0,0,0,0,0,0,0,0,0,0,0,0,0,0,0,0,0,0,0,0,0,0,0,0,0,BY51,0,0,0)';
      PINUSE='POWER';
      NO_LOAD_CHECK='Both';
      NO_IO_CHECK='Both';
      NO_ASSERT_CHECK='TRUE';
      NO_DIR_CHECK='TRUE';
      ALLOW_CONNECT='TRUE';
    'VSS_BY54':
      PIN_NUMBER='(0,0,0,0,0,0,0,0,0,0,0,0,0,0,0,0,0,0,0,0,0,0,0,0,0,0,0,0,0,0,0,0,0,0,0,0,BY54,0,0,0)';
      PINUSE='POWER';
      NO_LOAD_CHECK='Both';
      NO_IO_CHECK='Both';
      NO_ASSERT_CHECK='TRUE';
      NO_DIR_CHECK='TRUE';
      ALLOW_CONNECT='TRUE';
    'VSS_BY57':
      PIN_NUMBER='(0,0,0,0,0,0,0,0,0,0,0,0,0,0,0,0,0,0,0,0,0,0,0,0,0,0,0,0,0,0,0,0,0,0,0,0,BY57,0,0,0)';
      PINUSE='POWER';
      NO_LOAD_CHECK='Both';
      NO_IO_CHECK='Both';
      NO_ASSERT_CHECK='TRUE';
      NO_DIR_CHECK='TRUE';
      ALLOW_CONNECT='TRUE';
    'VSS_BY59':
      PIN_NUMBER='(0,0,0,0,0,0,0,0,0,0,0,0,0,0,0,0,0,0,0,0,0,0,0,0,0,0,0,0,0,0,0,0,0,0,0,0,BY59,0,0,0)';
      PINUSE='POWER';
      NO_LOAD_CHECK='Both';
      NO_IO_CHECK='Both';
      NO_ASSERT_CHECK='TRUE';
      NO_DIR_CHECK='TRUE';
      ALLOW_CONNECT='TRUE';
    'VSS_BY61':
      PIN_NUMBER='(0,0,0,0,0,0,0,0,0,0,0,0,0,0,0,0,0,0,0,0,0,0,0,0,0,0,0,0,0,0,0,0,0,0,0,0,BY61,0,0,0)';
      PINUSE='POWER';
      NO_LOAD_CHECK='Both';
      NO_IO_CHECK='Both';
      NO_ASSERT_CHECK='TRUE';
      NO_DIR_CHECK='TRUE';
      ALLOW_CONNECT='TRUE';
    'VSS_BY64':
      PIN_NUMBER='(0,0,0,0,0,0,0,0,0,0,0,0,0,0,0,0,0,0,0,0,0,0,0,0,0,0,0,0,0,0,0,0,0,0,0,0,BY64,0,0,0)';
      PINUSE='POWER';
      NO_LOAD_CHECK='Both';
      NO_IO_CHECK='Both';
      NO_ASSERT_CHECK='TRUE';
      NO_DIR_CHECK='TRUE';
      ALLOW_CONNECT='TRUE';
    'VSS_BY66':
      PIN_NUMBER='(0,0,0,0,0,0,0,0,0,0,0,0,0,0,0,0,0,0,0,0,0,0,0,0,0,0,0,0,0,0,0,0,0,0,0,0,BY66,0,0,0)';
      PINUSE='POWER';
      NO_LOAD_CHECK='Both';
      NO_IO_CHECK='Both';
      NO_ASSERT_CHECK='TRUE';
      NO_DIR_CHECK='TRUE';
      ALLOW_CONNECT='TRUE';
    'VSS_BY68':
      PIN_NUMBER='(0,0,0,0,0,0,0,0,0,0,0,0,0,0,0,0,0,0,0,0,0,0,0,0,0,0,0,0,0,0,0,0,0,0,0,0,BY68,0,0,0)';
      PINUSE='POWER';
      NO_LOAD_CHECK='Both';
      NO_IO_CHECK='Both';
      NO_ASSERT_CHECK='TRUE';
      NO_DIR_CHECK='TRUE';
      ALLOW_CONNECT='TRUE';
    'VSS_BY71':
      PIN_NUMBER='(0,0,0,0,0,0,0,0,0,0,0,0,0,0,0,0,0,0,0,0,0,0,0,0,0,0,0,0,0,0,0,0,0,0,0,0,BY71,0,0,0)';
      PINUSE='POWER';
      NO_LOAD_CHECK='Both';
      NO_IO_CHECK='Both';
      NO_ASSERT_CHECK='TRUE';
      NO_DIR_CHECK='TRUE';
      ALLOW_CONNECT='TRUE';
    'VSS_BY73':
      PIN_NUMBER='(0,0,0,0,0,0,0,0,0,0,0,0,0,0,0,0,0,0,0,0,0,0,0,0,0,0,0,0,0,0,0,0,0,0,0,0,BY73,0,0,0)';
      PINUSE='POWER';
      NO_LOAD_CHECK='Both';
      NO_IO_CHECK='Both';
      NO_ASSERT_CHECK='TRUE';
      NO_DIR_CHECK='TRUE';
      ALLOW_CONNECT='TRUE';
    'VSS_CA1':
      PIN_NUMBER='(0,0,0,0,0,0,0,0,0,0,0,0,0,0,0,0,0,0,0,0,0,0,0,0,0,0,0,0,0,0,0,0,0,0,0,0,CA1,0,0,0)';
      PINUSE='POWER';
      NO_LOAD_CHECK='Both';
      NO_IO_CHECK='Both';
      NO_ASSERT_CHECK='TRUE';
      NO_DIR_CHECK='TRUE';
      ALLOW_CONNECT='TRUE';
    'VSS_CA6':
      PIN_NUMBER='(0,0,0,0,0,0,0,0,0,0,0,0,0,0,0,0,0,0,0,0,0,0,0,0,0,0,0,0,0,0,0,0,0,0,0,0,CA6,0,0,0)';
      PINUSE='POWER';
      NO_LOAD_CHECK='Both';
      NO_IO_CHECK='Both';
      NO_ASSERT_CHECK='TRUE';
      NO_DIR_CHECK='TRUE';
      ALLOW_CONNECT='TRUE';
    'VSS_CA8':
      PIN_NUMBER='(0,0,0,0,0,0,0,0,0,0,0,0,0,0,0,0,0,0,0,0,0,0,0,0,0,0,0,0,0,0,0,0,0,0,0,0,CA8,0,0,0)';
      PINUSE='POWER';
      NO_LOAD_CHECK='Both';
      NO_IO_CHECK='Both';
      NO_ASSERT_CHECK='TRUE';
      NO_DIR_CHECK='TRUE';
      ALLOW_CONNECT='TRUE';
    'VSS_CA13':
      PIN_NUMBER='(0,0,0,0,0,0,0,0,0,0,0,0,0,0,0,0,0,0,0,0,0,0,0,0,0,0,0,0,0,0,0,0,0,0,0,0,CA13,0,0,0)';
      PINUSE='POWER';
      NO_LOAD_CHECK='Both';
      NO_IO_CHECK='Both';
      NO_ASSERT_CHECK='TRUE';
      NO_DIR_CHECK='TRUE';
      ALLOW_CONNECT='TRUE';
    'VSS_CA15':
      PIN_NUMBER='(0,0,0,0,0,0,0,0,0,0,0,0,0,0,0,0,0,0,0,0,0,0,0,0,0,0,0,0,0,0,0,0,0,0,0,0,CA15,0,0,0)';
      PINUSE='POWER';
      NO_LOAD_CHECK='Both';
      NO_IO_CHECK='Both';
      NO_ASSERT_CHECK='TRUE';
      NO_DIR_CHECK='TRUE';
      ALLOW_CONNECT='TRUE';
    'VSS_CA20':
      PIN_NUMBER='(0,0,0,0,0,0,0,0,0,0,0,0,0,0,0,0,0,0,0,0,0,0,0,0,0,0,0,0,0,0,0,0,0,0,0,0,CA20,0,0,0)';
      PINUSE='POWER';
      NO_LOAD_CHECK='Both';
      NO_IO_CHECK='Both';
      NO_ASSERT_CHECK='TRUE';
      NO_DIR_CHECK='TRUE';
      ALLOW_CONNECT='TRUE';
    'VSS_CA22':
      PIN_NUMBER='(0,0,0,0,0,0,0,0,0,0,0,0,0,0,0,0,0,0,0,0,0,0,0,0,0,0,0,0,0,0,0,0,0,0,0,0,CA22,0,0,0)';
      PINUSE='POWER';
      NO_LOAD_CHECK='Both';
      NO_IO_CHECK='Both';
      NO_ASSERT_CHECK='TRUE';
      NO_DIR_CHECK='TRUE';
      ALLOW_CONNECT='TRUE';
    'VSS_CA25':
      PIN_NUMBER='(0,0,0,0,0,0,0,0,0,0,0,0,0,0,0,0,0,0,0,0,0,0,0,0,0,0,0,0,0,0,0,0,0,0,0,0,CA25,0,0,0)';
      PINUSE='POWER';
      NO_LOAD_CHECK='Both';
      NO_IO_CHECK='Both';
      NO_ASSERT_CHECK='TRUE';
      NO_DIR_CHECK='TRUE';
      ALLOW_CONNECT='TRUE';
    'VSS_CA28':
      PIN_NUMBER='(0,0,0,0,0,0,0,0,0,0,0,0,0,0,0,0,0,0,0,0,0,0,0,0,0,0,0,0,0,0,0,0,0,0,0,0,CA28,0,0,0)';
      PINUSE='POWER';
      NO_LOAD_CHECK='Both';
      NO_IO_CHECK='Both';
      NO_ASSERT_CHECK='TRUE';
      NO_DIR_CHECK='TRUE';
      ALLOW_CONNECT='TRUE';
    'VSS_CA31':
      PIN_NUMBER='(0,0,0,0,0,0,0,0,0,0,0,0,0,0,0,0,0,0,0,0,0,0,0,0,0,0,0,0,0,0,0,0,0,0,0,0,CA31,0,0,0)';
      PINUSE='POWER';
      NO_LOAD_CHECK='Both';
      NO_IO_CHECK='Both';
      NO_ASSERT_CHECK='TRUE';
      NO_DIR_CHECK='TRUE';
      ALLOW_CONNECT='TRUE';
    'VSS_CA34':
      PIN_NUMBER='(0,0,0,0,0,0,0,0,0,0,0,0,0,0,0,0,0,0,0,0,0,0,0,0,0,0,0,0,0,0,0,0,0,0,0,0,CA34,0,0,0)';
      PINUSE='POWER';
      NO_LOAD_CHECK='Both';
      NO_IO_CHECK='Both';
      NO_ASSERT_CHECK='TRUE';
      NO_DIR_CHECK='TRUE';
      ALLOW_CONNECT='TRUE';
    'VSS_CA35':
      PIN_NUMBER='(0,0,0,0,0,0,0,0,0,0,0,0,0,0,0,0,0,0,0,0,0,0,0,0,0,0,0,0,0,0,0,0,0,0,0,0,CA35,0,0,0)';
      PINUSE='POWER';
      NO_LOAD_CHECK='Both';
      NO_IO_CHECK='Both';
      NO_ASSERT_CHECK='TRUE';
      NO_DIR_CHECK='TRUE';
      ALLOW_CONNECT='TRUE';
    'VSS_CA36':
      PIN_NUMBER='(0,0,0,0,0,0,0,0,0,0,0,0,0,0,0,0,0,0,0,0,0,0,0,0,0,0,0,0,0,0,0,0,0,0,0,0,CA36,0,0,0)';
      PINUSE='POWER';
      NO_LOAD_CHECK='Both';
      NO_IO_CHECK='Both';
      NO_ASSERT_CHECK='TRUE';
      NO_DIR_CHECK='TRUE';
      ALLOW_CONNECT='TRUE';
    'VSS_CA40':
      PIN_NUMBER='(0,0,0,0,0,0,0,0,0,0,0,0,0,0,0,0,0,0,0,0,0,0,0,0,0,0,0,0,0,0,0,0,0,0,0,0,CA40,0,0,0)';
      PINUSE='POWER';
      NO_LOAD_CHECK='Both';
      NO_IO_CHECK='Both';
      NO_ASSERT_CHECK='TRUE';
      NO_DIR_CHECK='TRUE';
      ALLOW_CONNECT='TRUE';
    'VSS_CA41':
      PIN_NUMBER='(0,0,0,0,0,0,0,0,0,0,0,0,0,0,0,0,0,0,0,0,0,0,0,0,0,0,0,0,0,0,0,0,0,0,0,0,CA41,0,0,0)';
      PINUSE='POWER';
      NO_LOAD_CHECK='Both';
      NO_IO_CHECK='Both';
      NO_ASSERT_CHECK='TRUE';
      NO_DIR_CHECK='TRUE';
      ALLOW_CONNECT='TRUE';
    'VSS_CA42':
      PIN_NUMBER='(0,0,0,0,0,0,0,0,0,0,0,0,0,0,0,0,0,0,0,0,0,0,0,0,0,0,0,0,0,0,0,0,0,0,0,0,CA42,0,0,0)';
      PINUSE='POWER';
      NO_LOAD_CHECK='Both';
      NO_IO_CHECK='Both';
      NO_ASSERT_CHECK='TRUE';
      NO_DIR_CHECK='TRUE';
      ALLOW_CONNECT='TRUE';
    'VSS_CA45':
      PIN_NUMBER='(0,0,0,0,0,0,0,0,0,0,0,0,0,0,0,0,0,0,0,0,0,0,0,0,0,0,0,0,0,0,0,0,0,0,0,0,CA45,0,0,0)';
      PINUSE='POWER';
      NO_LOAD_CHECK='Both';
      NO_IO_CHECK='Both';
      NO_ASSERT_CHECK='TRUE';
      NO_DIR_CHECK='TRUE';
      ALLOW_CONNECT='TRUE';
    'VSS_CA48':
      PIN_NUMBER='(0,0,0,0,0,0,0,0,0,0,0,0,0,0,0,0,0,0,0,0,0,0,0,0,0,0,0,0,0,0,0,0,0,0,0,0,CA48,0,0,0)';
      PINUSE='POWER';
      NO_LOAD_CHECK='Both';
      NO_IO_CHECK='Both';
      NO_ASSERT_CHECK='TRUE';
      NO_DIR_CHECK='TRUE';
      ALLOW_CONNECT='TRUE';
    'VSS_CA51':
      PIN_NUMBER='(0,0,0,0,0,0,0,0,0,0,0,0,0,0,0,0,0,0,0,0,0,0,0,0,0,0,0,0,0,0,0,0,0,0,0,0,CA51,0,0,0)';
      PINUSE='POWER';
      NO_LOAD_CHECK='Both';
      NO_IO_CHECK='Both';
      NO_ASSERT_CHECK='TRUE';
      NO_DIR_CHECK='TRUE';
      ALLOW_CONNECT='TRUE';
    'VSS_CA54':
      PIN_NUMBER='(0,0,0,0,0,0,0,0,0,0,0,0,0,0,0,0,0,0,0,0,0,0,0,0,0,0,0,0,0,0,0,0,0,0,0,0,CA54,0,0,0)';
      PINUSE='POWER';
      NO_LOAD_CHECK='Both';
      NO_IO_CHECK='Both';
      NO_ASSERT_CHECK='TRUE';
      NO_DIR_CHECK='TRUE';
      ALLOW_CONNECT='TRUE';
    'VSS_CA56':
      PIN_NUMBER='(0,0,0,0,0,0,0,0,0,0,0,0,0,0,0,0,0,0,0,0,0,0,0,0,0,0,0,0,0,0,0,0,0,0,0,0,CA56,0,0,0)';
      PINUSE='POWER';
      NO_LOAD_CHECK='Both';
      NO_IO_CHECK='Both';
      NO_ASSERT_CHECK='TRUE';
      NO_DIR_CHECK='TRUE';
      ALLOW_CONNECT='TRUE';
    'VSS_CA61':
      PIN_NUMBER='(0,0,0,0,0,0,0,0,0,0,0,0,0,0,0,0,0,0,0,0,0,0,0,0,0,0,0,0,0,0,0,0,0,0,0,0,CA61,0,0,0)';
      PINUSE='POWER';
      NO_LOAD_CHECK='Both';
      NO_IO_CHECK='Both';
      NO_ASSERT_CHECK='TRUE';
      NO_DIR_CHECK='TRUE';
      ALLOW_CONNECT='TRUE';
    'VSS_CA63':
      PIN_NUMBER='(0,0,0,0,0,0,0,0,0,0,0,0,0,0,0,0,0,0,0,0,0,0,0,0,0,0,0,0,0,0,0,0,0,0,0,0,CA63,0,0,0)';
      PINUSE='POWER';
      NO_LOAD_CHECK='Both';
      NO_IO_CHECK='Both';
      NO_ASSERT_CHECK='TRUE';
      NO_DIR_CHECK='TRUE';
      ALLOW_CONNECT='TRUE';
    'VSS_CA68':
      PIN_NUMBER='(0,0,0,0,0,0,0,0,0,0,0,0,0,0,0,0,0,0,0,0,0,0,0,0,0,0,0,0,0,0,0,0,0,0,0,0,CA68,0,0,0)';
      PINUSE='POWER';
      NO_LOAD_CHECK='Both';
      NO_IO_CHECK='Both';
      NO_ASSERT_CHECK='TRUE';
      NO_DIR_CHECK='TRUE';
      ALLOW_CONNECT='TRUE';
    'VSS_CA70':
      PIN_NUMBER='(0,0,0,0,0,0,0,0,0,0,0,0,0,0,0,0,0,0,0,0,0,0,0,0,0,0,0,0,0,0,0,0,0,0,0,0,CA70,0,0,0)';
      PINUSE='POWER';
      NO_LOAD_CHECK='Both';
      NO_IO_CHECK='Both';
      NO_ASSERT_CHECK='TRUE';
      NO_DIR_CHECK='TRUE';
      ALLOW_CONNECT='TRUE';
    'VSS_CA75':
      PIN_NUMBER='(0,0,0,0,0,0,0,0,0,0,0,0,0,0,0,0,0,0,0,0,0,0,0,0,0,0,0,0,0,0,0,0,0,0,0,0,CA75,0,0,0)';
      PINUSE='POWER';
      NO_LOAD_CHECK='Both';
      NO_IO_CHECK='Both';
      NO_ASSERT_CHECK='TRUE';
      NO_DIR_CHECK='TRUE';
      ALLOW_CONNECT='TRUE';
    'VSS_CB3':
      PIN_NUMBER='(0,0,0,0,0,0,0,0,0,0,0,0,0,0,0,0,0,0,0,0,0,0,0,0,0,0,0,0,0,0,0,0,0,0,0,0,CB3,0,0,0)';
      PINUSE='POWER';
      NO_LOAD_CHECK='Both';
      NO_IO_CHECK='Both';
      NO_ASSERT_CHECK='TRUE';
      NO_DIR_CHECK='TRUE';
      ALLOW_CONNECT='TRUE';
    'VSS_CB5':
      PIN_NUMBER='(0,0,0,0,0,0,0,0,0,0,0,0,0,0,0,0,0,0,0,0,0,0,0,0,0,0,0,0,0,0,0,0,0,0,0,0,CB5,0,0,0)';
      PINUSE='POWER';
      NO_LOAD_CHECK='Both';
      NO_IO_CHECK='Both';
      NO_ASSERT_CHECK='TRUE';
      NO_DIR_CHECK='TRUE';
      ALLOW_CONNECT='TRUE';
    'VSS_CB8':
      PIN_NUMBER='(0,0,0,0,0,0,0,0,0,0,0,0,0,0,0,0,0,0,0,0,0,0,0,0,0,0,0,0,0,0,0,0,0,0,0,0,CB8,0,0,0)';
      PINUSE='POWER';
      NO_LOAD_CHECK='Both';
      NO_IO_CHECK='Both';
      NO_ASSERT_CHECK='TRUE';
      NO_DIR_CHECK='TRUE';
      ALLOW_CONNECT='TRUE';
    'VSS_CB10':
      PIN_NUMBER='(0,0,0,0,0,0,0,0,0,0,0,0,0,0,0,0,0,0,0,0,0,0,0,0,0,0,0,0,0,0,0,0,0,0,0,0,CB10,0,0,0)';
      PINUSE='POWER';
      NO_LOAD_CHECK='Both';
      NO_IO_CHECK='Both';
      NO_ASSERT_CHECK='TRUE';
      NO_DIR_CHECK='TRUE';
      ALLOW_CONNECT='TRUE';
    'VSS_CB12':
      PIN_NUMBER='(0,0,0,0,0,0,0,0,0,0,0,0,0,0,0,0,0,0,0,0,0,0,0,0,0,0,0,0,0,0,0,0,0,0,0,0,CB12,0,0,0)';
      PINUSE='POWER';
      NO_LOAD_CHECK='Both';
      NO_IO_CHECK='Both';
      NO_ASSERT_CHECK='TRUE';
      NO_DIR_CHECK='TRUE';
      ALLOW_CONNECT='TRUE';
    'VSS_CB15':
      PIN_NUMBER='(0,0,0,0,0,0,0,0,0,0,0,0,0,0,0,0,0,0,0,0,0,0,0,0,0,0,0,0,0,0,0,0,0,0,0,0,CB15,0,0,0)';
      PINUSE='POWER';
      NO_LOAD_CHECK='Both';
      NO_IO_CHECK='Both';
      NO_ASSERT_CHECK='TRUE';
      NO_DIR_CHECK='TRUE';
      ALLOW_CONNECT='TRUE';
    'VSS_CB17':
      PIN_NUMBER='(0,0,0,0,0,0,0,0,0,0,0,0,0,0,0,0,0,0,0,0,0,0,0,0,0,0,0,0,0,0,0,0,0,0,0,0,CB17,0,0,0)';
      PINUSE='POWER';
      NO_LOAD_CHECK='Both';
      NO_IO_CHECK='Both';
      NO_ASSERT_CHECK='TRUE';
      NO_DIR_CHECK='TRUE';
      ALLOW_CONNECT='TRUE';
    'VSS_CB19':
      PIN_NUMBER='(0,0,0,0,0,0,0,0,0,0,0,0,0,0,0,0,0,0,0,0,0,0,0,0,0,0,0,0,0,0,0,0,0,0,0,0,CB19,0,0,0)';
      PINUSE='POWER';
      NO_LOAD_CHECK='Both';
      NO_IO_CHECK='Both';
      NO_ASSERT_CHECK='TRUE';
      NO_DIR_CHECK='TRUE';
      ALLOW_CONNECT='TRUE';
    'VSS_CB23':
      PIN_NUMBER='(0,0,0,0,0,0,0,0,0,0,0,0,0,0,0,0,0,0,0,0,0,0,0,0,0,0,0,0,0,0,0,0,0,0,0,0,CB23,0,0,0)';
      PINUSE='POWER';
      NO_LOAD_CHECK='Both';
      NO_IO_CHECK='Both';
      NO_ASSERT_CHECK='TRUE';
      NO_DIR_CHECK='TRUE';
      ALLOW_CONNECT='TRUE';
    'VSS_CB24':
      PIN_NUMBER='(0,0,0,0,0,0,0,0,0,0,0,0,0,0,0,0,0,0,0,0,0,0,0,0,0,0,0,0,0,0,0,0,0,0,0,0,CB24,0,0,0)';
      PINUSE='POWER';
      NO_LOAD_CHECK='Both';
      NO_IO_CHECK='Both';
      NO_ASSERT_CHECK='TRUE';
      NO_DIR_CHECK='TRUE';
      ALLOW_CONNECT='TRUE';
    'VSS_CB25':
      PIN_NUMBER='(0,0,0,0,0,0,0,0,0,0,0,0,0,0,0,0,0,0,0,0,0,0,0,0,0,0,0,0,0,0,0,0,0,0,0,0,CB25,0,0,0)';
      PINUSE='POWER';
      NO_LOAD_CHECK='Both';
      NO_IO_CHECK='Both';
      NO_ASSERT_CHECK='TRUE';
      NO_DIR_CHECK='TRUE';
      ALLOW_CONNECT='TRUE';
    'VSS_CB26':
      PIN_NUMBER='(0,0,0,0,0,0,0,0,0,0,0,0,0,0,0,0,0,0,0,0,0,0,0,0,0,0,0,0,0,0,0,0,0,0,0,0,CB26,0,0,0)';
      PINUSE='POWER';
      NO_LOAD_CHECK='Both';
      NO_IO_CHECK='Both';
      NO_ASSERT_CHECK='TRUE';
      NO_DIR_CHECK='TRUE';
      ALLOW_CONNECT='TRUE';
    'VSS_CB27':
      PIN_NUMBER='(0,0,0,0,0,0,0,0,0,0,0,0,0,0,0,0,0,0,0,0,0,0,0,0,0,0,0,0,0,0,0,0,0,0,0,0,CB27,0,0,0)';
      PINUSE='POWER';
      NO_LOAD_CHECK='Both';
      NO_IO_CHECK='Both';
      NO_ASSERT_CHECK='TRUE';
      NO_DIR_CHECK='TRUE';
      ALLOW_CONNECT='TRUE';
    'VSS_CB28':
      PIN_NUMBER='(0,0,0,0,0,0,0,0,0,0,0,0,0,0,0,0,0,0,0,0,0,0,0,0,0,0,0,0,0,0,0,0,0,0,0,0,CB28,0,0,0)';
      PINUSE='POWER';
      NO_LOAD_CHECK='Both';
      NO_IO_CHECK='Both';
      NO_ASSERT_CHECK='TRUE';
      NO_DIR_CHECK='TRUE';
      ALLOW_CONNECT='TRUE';
    'VSS_CB29':
      PIN_NUMBER='(0,0,0,0,0,0,0,0,0,0,0,0,0,0,0,0,0,0,0,0,0,0,0,0,0,0,0,0,0,0,0,0,0,0,0,0,CB29,0,0,0)';
      PINUSE='POWER';
      NO_LOAD_CHECK='Both';
      NO_IO_CHECK='Both';
      NO_ASSERT_CHECK='TRUE';
      NO_DIR_CHECK='TRUE';
      ALLOW_CONNECT='TRUE';
    'VSS_CB30':
      PIN_NUMBER='(0,0,0,0,0,0,0,0,0,0,0,0,0,0,0,0,0,0,0,0,0,0,0,0,0,0,0,0,0,0,0,0,0,0,0,0,CB30,0,0,0)';
      PINUSE='POWER';
      NO_LOAD_CHECK='Both';
      NO_IO_CHECK='Both';
      NO_ASSERT_CHECK='TRUE';
      NO_DIR_CHECK='TRUE';
      ALLOW_CONNECT='TRUE';
    'VSS_CB31':
      PIN_NUMBER='(0,0,0,0,0,0,0,0,0,0,0,0,0,0,0,0,0,0,0,0,0,0,0,0,0,0,0,0,0,0,0,0,0,0,0,0,CB31,0,0,0)';
      PINUSE='POWER';
      NO_LOAD_CHECK='Both';
      NO_IO_CHECK='Both';
      NO_ASSERT_CHECK='TRUE';
      NO_DIR_CHECK='TRUE';
      ALLOW_CONNECT='TRUE';
    'VSS_CB32':
      PIN_NUMBER='(0,0,0,0,0,0,0,0,0,0,0,0,0,0,0,0,0,0,0,0,0,0,0,0,0,0,0,0,0,0,0,0,0,0,0,0,CB32,0,0,0)';
      PINUSE='POWER';
      NO_LOAD_CHECK='Both';
      NO_IO_CHECK='Both';
      NO_ASSERT_CHECK='TRUE';
      NO_DIR_CHECK='TRUE';
      ALLOW_CONNECT='TRUE';
    'VSS_CB33':
      PIN_NUMBER='(0,0,0,0,0,0,0,0,0,0,0,0,0,0,0,0,0,0,0,0,0,0,0,0,0,0,0,0,0,0,0,0,0,0,0,0,CB33,0,0,0)';
      PINUSE='POWER';
      NO_LOAD_CHECK='Both';
      NO_IO_CHECK='Both';
      NO_ASSERT_CHECK='TRUE';
      NO_DIR_CHECK='TRUE';
      ALLOW_CONNECT='TRUE';
    'VSS_CB34':
      PIN_NUMBER='(0,0,0,0,0,0,0,0,0,0,0,0,0,0,0,0,0,0,0,0,0,0,0,0,0,0,0,0,0,0,0,0,0,0,0,0,CB34,0,0,0)';
      PINUSE='POWER';
      NO_LOAD_CHECK='Both';
      NO_IO_CHECK='Both';
      NO_ASSERT_CHECK='TRUE';
      NO_DIR_CHECK='TRUE';
      ALLOW_CONNECT='TRUE';
    'VSS_CB37':
      PIN_NUMBER='(0,0,0,0,0,0,0,0,0,0,0,0,0,0,0,0,0,0,0,0,0,0,0,0,0,0,0,0,0,0,0,0,0,0,0,0,CB37,0,0,0)';
      PINUSE='POWER';
      NO_LOAD_CHECK='Both';
      NO_IO_CHECK='Both';
      NO_ASSERT_CHECK='TRUE';
      NO_DIR_CHECK='TRUE';
      ALLOW_CONNECT='TRUE';
    'VSS_CB39':
      PIN_NUMBER='(0,0,0,0,0,0,0,0,0,0,0,0,0,0,0,0,0,0,0,0,0,0,0,0,0,0,0,0,0,0,0,0,0,0,0,0,CB39,0,0,0)';
      PINUSE='POWER';
      NO_LOAD_CHECK='Both';
      NO_IO_CHECK='Both';
      NO_ASSERT_CHECK='TRUE';
      NO_DIR_CHECK='TRUE';
      ALLOW_CONNECT='TRUE';
    'VSS_CB42':
      PIN_NUMBER='(0,0,0,0,0,0,0,0,0,0,0,0,0,0,0,0,0,0,0,0,0,0,0,0,0,0,0,0,0,0,0,0,0,0,0,0,CB42,0,0,0)';
      PINUSE='POWER';
      NO_LOAD_CHECK='Both';
      NO_IO_CHECK='Both';
      NO_ASSERT_CHECK='TRUE';
      NO_DIR_CHECK='TRUE';
      ALLOW_CONNECT='TRUE';
    'VSS_CB43':
      PIN_NUMBER='(0,0,0,0,0,0,0,0,0,0,0,0,0,0,0,0,0,0,0,0,0,0,0,0,0,0,0,0,0,0,0,0,0,0,0,0,CB43,0,0,0)';
      PINUSE='POWER';
      NO_LOAD_CHECK='Both';
      NO_IO_CHECK='Both';
      NO_ASSERT_CHECK='TRUE';
      NO_DIR_CHECK='TRUE';
      ALLOW_CONNECT='TRUE';
    'VSS_CB45':
      PIN_NUMBER='(0,0,0,0,0,0,0,0,0,0,0,0,0,0,0,0,0,0,0,0,0,0,0,0,0,0,0,0,0,0,0,0,0,0,0,0,CB45,0,0,0)';
      PINUSE='POWER';
      NO_LOAD_CHECK='Both';
      NO_IO_CHECK='Both';
      NO_ASSERT_CHECK='TRUE';
      NO_DIR_CHECK='TRUE';
      ALLOW_CONNECT='TRUE';
    'VSS_CB46':
      PIN_NUMBER='(0,0,0,0,0,0,0,0,0,0,0,0,0,0,0,0,0,0,0,0,0,0,0,0,0,0,0,0,0,0,0,0,0,0,0,0,CB46,0,0,0)';
      PINUSE='POWER';
      NO_LOAD_CHECK='Both';
      NO_IO_CHECK='Both';
      NO_ASSERT_CHECK='TRUE';
      NO_DIR_CHECK='TRUE';
      ALLOW_CONNECT='TRUE';
    'VSS_CB47':
      PIN_NUMBER='(0,0,0,0,0,0,0,0,0,0,0,0,0,0,0,0,0,0,0,0,0,0,0,0,0,0,0,0,0,0,0,0,0,0,0,0,CB47,0,0,0)';
      PINUSE='POWER';
      NO_LOAD_CHECK='Both';
      NO_IO_CHECK='Both';
      NO_ASSERT_CHECK='TRUE';
      NO_DIR_CHECK='TRUE';
      ALLOW_CONNECT='TRUE';
    'VSS_CB48':
      PIN_NUMBER='(0,0,0,0,0,0,0,0,0,0,0,0,0,0,0,0,0,0,0,0,0,0,0,0,0,0,0,0,0,0,0,0,0,0,0,0,CB48,0,0,0)';
      PINUSE='POWER';
      NO_LOAD_CHECK='Both';
      NO_IO_CHECK='Both';
      NO_ASSERT_CHECK='TRUE';
      NO_DIR_CHECK='TRUE';
      ALLOW_CONNECT='TRUE';
    'VSS_CB49':
      PIN_NUMBER='(0,0,0,0,0,0,0,0,0,0,0,0,0,0,0,0,0,0,0,0,0,0,0,0,0,0,0,0,0,0,0,0,0,0,0,0,CB49,0,0,0)';
      PINUSE='POWER';
      NO_LOAD_CHECK='Both';
      NO_IO_CHECK='Both';
      NO_ASSERT_CHECK='TRUE';
      NO_DIR_CHECK='TRUE';
      ALLOW_CONNECT='TRUE';
    'VSS_CB50':
      PIN_NUMBER='(0,0,0,0,0,0,0,0,0,0,0,0,0,0,0,0,0,0,0,0,0,0,0,0,0,0,0,0,0,0,0,0,0,0,0,0,CB50,0,0,0)';
      PINUSE='POWER';
      NO_LOAD_CHECK='Both';
      NO_IO_CHECK='Both';
      NO_ASSERT_CHECK='TRUE';
      NO_DIR_CHECK='TRUE';
      ALLOW_CONNECT='TRUE';
    'VSS_CB51':
      PIN_NUMBER='(0,0,0,0,0,0,0,0,0,0,0,0,0,0,0,0,0,0,0,0,0,0,0,0,0,0,0,0,0,0,0,0,0,0,0,0,CB51,0,0,0)';
      PINUSE='POWER';
      NO_LOAD_CHECK='Both';
      NO_IO_CHECK='Both';
      NO_ASSERT_CHECK='TRUE';
      NO_DIR_CHECK='TRUE';
      ALLOW_CONNECT='TRUE';
    'VSS_CB52':
      PIN_NUMBER='(0,0,0,0,0,0,0,0,0,0,0,0,0,0,0,0,0,0,0,0,0,0,0,0,0,0,0,0,0,0,0,0,0,0,0,0,CB52,0,0,0)';
      PINUSE='POWER';
      NO_LOAD_CHECK='Both';
      NO_IO_CHECK='Both';
      NO_ASSERT_CHECK='TRUE';
      NO_DIR_CHECK='TRUE';
      ALLOW_CONNECT='TRUE';
    'VSS_CB53':
      PIN_NUMBER='(0,0,0,0,0,0,0,0,0,0,0,0,0,0,0,0,0,0,0,0,0,0,0,0,0,0,0,0,0,0,0,0,0,0,0,0,CB53,0,0,0)';
      PINUSE='POWER';
      NO_LOAD_CHECK='Both';
      NO_IO_CHECK='Both';
      NO_ASSERT_CHECK='TRUE';
      NO_DIR_CHECK='TRUE';
      ALLOW_CONNECT='TRUE';
    'VSS_CB57':
      PIN_NUMBER='(0,0,0,0,0,0,0,0,0,0,0,0,0,0,0,0,0,0,0,0,0,0,0,0,0,0,0,0,0,0,0,0,0,0,0,0,CB57,0,0,0)';
      PINUSE='POWER';
      NO_LOAD_CHECK='Both';
      NO_IO_CHECK='Both';
      NO_ASSERT_CHECK='TRUE';
      NO_DIR_CHECK='TRUE';
      ALLOW_CONNECT='TRUE';
    'VSS_CB59':
      PIN_NUMBER='(0,0,0,0,0,0,0,0,0,0,0,0,0,0,0,0,0,0,0,0,0,0,0,0,0,0,0,0,0,0,0,0,0,0,0,0,CB59,0,0,0)';
      PINUSE='POWER';
      NO_LOAD_CHECK='Both';
      NO_IO_CHECK='Both';
      NO_ASSERT_CHECK='TRUE';
      NO_DIR_CHECK='TRUE';
      ALLOW_CONNECT='TRUE';
    'VSS_CB61':
      PIN_NUMBER='(0,0,0,0,0,0,0,0,0,0,0,0,0,0,0,0,0,0,0,0,0,0,0,0,0,0,0,0,0,0,0,0,0,0,0,0,CB61,0,0,0)';
      PINUSE='POWER';
      NO_LOAD_CHECK='Both';
      NO_IO_CHECK='Both';
      NO_ASSERT_CHECK='TRUE';
      NO_DIR_CHECK='TRUE';
      ALLOW_CONNECT='TRUE';
    'VSS_CB64':
      PIN_NUMBER='(0,0,0,0,0,0,0,0,0,0,0,0,0,0,0,0,0,0,0,0,0,0,0,0,0,0,0,0,0,0,0,0,0,0,0,0,CB64,0,0,0)';
      PINUSE='POWER';
      NO_LOAD_CHECK='Both';
      NO_IO_CHECK='Both';
      NO_ASSERT_CHECK='TRUE';
      NO_DIR_CHECK='TRUE';
      ALLOW_CONNECT='TRUE';
    'VSS_CB66':
      PIN_NUMBER='(0,0,0,0,0,0,0,0,0,0,0,0,0,0,0,0,0,0,0,0,0,0,0,0,0,0,0,0,0,0,0,0,0,0,0,0,CB66,0,0,0)';
      PINUSE='POWER';
      NO_LOAD_CHECK='Both';
      NO_IO_CHECK='Both';
      NO_ASSERT_CHECK='TRUE';
      NO_DIR_CHECK='TRUE';
      ALLOW_CONNECT='TRUE';
    'VSS_CB68':
      PIN_NUMBER='(0,0,0,0,0,0,0,0,0,0,0,0,0,0,0,0,0,0,0,0,0,0,0,0,0,0,0,0,0,0,0,0,0,0,0,0,CB68,0,0,0)';
      PINUSE='POWER';
      NO_LOAD_CHECK='Both';
      NO_IO_CHECK='Both';
      NO_ASSERT_CHECK='TRUE';
      NO_DIR_CHECK='TRUE';
      ALLOW_CONNECT='TRUE';
    'VSS_CB71':
      PIN_NUMBER='(0,0,0,0,0,0,0,0,0,0,0,0,0,0,0,0,0,0,0,0,0,0,0,0,0,0,0,0,0,0,0,0,0,0,0,0,CB71,0,0,0)';
      PINUSE='POWER';
      NO_LOAD_CHECK='Both';
      NO_IO_CHECK='Both';
      NO_ASSERT_CHECK='TRUE';
      NO_DIR_CHECK='TRUE';
      ALLOW_CONNECT='TRUE';
    'VSS_CB73':
      PIN_NUMBER='(0,0,0,0,0,0,0,0,0,0,0,0,0,0,0,0,0,0,0,0,0,0,0,0,0,0,0,0,0,0,0,0,0,0,0,0,CB73,0,0,0)';
      PINUSE='POWER';
      NO_LOAD_CHECK='Both';
      NO_IO_CHECK='Both';
      NO_ASSERT_CHECK='TRUE';
      NO_DIR_CHECK='TRUE';
      ALLOW_CONNECT='TRUE';
    'VSS_CC1':
      PIN_NUMBER='(0,0,0,0,0,0,0,0,0,0,0,0,0,0,0,0,0,0,0,0,0,0,0,0,0,0,0,0,0,0,0,0,0,0,0,0,CC1,0,0,0)';
      PINUSE='POWER';
      NO_LOAD_CHECK='Both';
      NO_IO_CHECK='Both';
      NO_ASSERT_CHECK='TRUE';
      NO_DIR_CHECK='TRUE';
      ALLOW_CONNECT='TRUE';
    'VSS_CC4':
      PIN_NUMBER='(0,0,0,0,0,0,0,0,0,0,0,0,0,0,0,0,0,0,0,0,0,0,0,0,0,0,0,0,0,0,0,0,0,0,0,0,CC4,0,0,0)';
      PINUSE='POWER';
      NO_LOAD_CHECK='Both';
      NO_IO_CHECK='Both';
      NO_ASSERT_CHECK='TRUE';
      NO_DIR_CHECK='TRUE';
      ALLOW_CONNECT='TRUE';
    'VSS_CC6':
      PIN_NUMBER='(0,0,0,0,0,0,0,0,0,0,0,0,0,0,0,0,0,0,0,0,0,0,0,0,0,0,0,0,0,0,0,0,0,0,0,0,CC6,0,0,0)';
      PINUSE='POWER';
      NO_LOAD_CHECK='Both';
      NO_IO_CHECK='Both';
      NO_ASSERT_CHECK='TRUE';
      NO_DIR_CHECK='TRUE';
      ALLOW_CONNECT='TRUE';
    'VSS_CC8':
      PIN_NUMBER='(0,0,0,0,0,0,0,0,0,0,0,0,0,0,0,0,0,0,0,0,0,0,0,0,0,0,0,0,0,0,0,0,0,0,0,0,CC8,0,0,0)';
      PINUSE='POWER';
      NO_LOAD_CHECK='Both';
      NO_IO_CHECK='Both';
      NO_ASSERT_CHECK='TRUE';
      NO_DIR_CHECK='TRUE';
      ALLOW_CONNECT='TRUE';
    'VSS_CC11':
      PIN_NUMBER='(0,0,0,0,0,0,0,0,0,0,0,0,0,0,0,0,0,0,0,0,0,0,0,0,0,0,0,0,0,0,0,0,0,0,0,0,CC11,0,0,0)';
      PINUSE='POWER';
      NO_LOAD_CHECK='Both';
      NO_IO_CHECK='Both';
      NO_ASSERT_CHECK='TRUE';
      NO_DIR_CHECK='TRUE';
      ALLOW_CONNECT='TRUE';
    'VSS_CC13':
      PIN_NUMBER='(0,0,0,0,0,0,0,0,0,0,0,0,0,0,0,0,0,0,0,0,0,0,0,0,0,0,0,0,0,0,0,0,0,0,0,0,CC13,0,0,0)';
      PINUSE='POWER';
      NO_LOAD_CHECK='Both';
      NO_IO_CHECK='Both';
      NO_ASSERT_CHECK='TRUE';
      NO_DIR_CHECK='TRUE';
      ALLOW_CONNECT='TRUE';
    'VSS_CC15':
      PIN_NUMBER='(0,0,0,0,0,0,0,0,0,0,0,0,0,0,0,0,0,0,0,0,0,0,0,0,0,0,0,0,0,0,0,0,0,0,0,0,CC15,0,0,0)';
      PINUSE='POWER';
      NO_LOAD_CHECK='Both';
      NO_IO_CHECK='Both';
      NO_ASSERT_CHECK='TRUE';
      NO_DIR_CHECK='TRUE';
      ALLOW_CONNECT='TRUE';
    'VSS_CC18':
      PIN_NUMBER='(0,0,0,0,0,0,0,0,0,0,0,0,0,0,0,0,0,0,0,0,0,0,0,0,0,0,0,0,0,0,0,0,0,0,0,0,CC18,0,0,0)';
      PINUSE='POWER';
      NO_LOAD_CHECK='Both';
      NO_IO_CHECK='Both';
      NO_ASSERT_CHECK='TRUE';
      NO_DIR_CHECK='TRUE';
      ALLOW_CONNECT='TRUE';
    'VSS_CC20':
      PIN_NUMBER='(0,0,0,0,0,0,0,0,0,0,0,0,0,0,0,0,0,0,0,0,0,0,0,0,0,0,0,0,0,0,0,0,0,0,0,0,CC20,0,0,0)';
      PINUSE='POWER';
      NO_LOAD_CHECK='Both';
      NO_IO_CHECK='Both';
      NO_ASSERT_CHECK='TRUE';
      NO_DIR_CHECK='TRUE';
      ALLOW_CONNECT='TRUE';
    'VSS_CC25':
      PIN_NUMBER='(0,0,0,0,0,0,0,0,0,0,0,0,0,0,0,0,0,0,0,0,0,0,0,0,0,0,0,0,0,0,0,0,0,0,0,0,CC25,0,0,0)';
      PINUSE='POWER';
      NO_LOAD_CHECK='Both';
      NO_IO_CHECK='Both';
      NO_ASSERT_CHECK='TRUE';
      NO_DIR_CHECK='TRUE';
      ALLOW_CONNECT='TRUE';
    'VSS_CC28':
      PIN_NUMBER='(0,0,0,0,0,0,0,0,0,0,0,0,0,0,0,0,0,0,0,0,0,0,0,0,0,0,0,0,0,0,0,0,0,0,0,0,CC28,0,0,0)';
      PINUSE='POWER';
      NO_LOAD_CHECK='Both';
      NO_IO_CHECK='Both';
      NO_ASSERT_CHECK='TRUE';
      NO_DIR_CHECK='TRUE';
      ALLOW_CONNECT='TRUE';
    'VSS_CC31':
      PIN_NUMBER='(0,0,0,0,0,0,0,0,0,0,0,0,0,0,0,0,0,0,0,0,0,0,0,0,0,0,0,0,0,0,0,0,0,0,0,0,CC31,0,0,0)';
      PINUSE='POWER';
      NO_LOAD_CHECK='Both';
      NO_IO_CHECK='Both';
      NO_ASSERT_CHECK='TRUE';
      NO_DIR_CHECK='TRUE';
      ALLOW_CONNECT='TRUE';
    'VSS_CC34':
      PIN_NUMBER='(0,0,0,0,0,0,0,0,0,0,0,0,0,0,0,0,0,0,0,0,0,0,0,0,0,0,0,0,0,0,0,0,0,0,0,0,CC34,0,0,0)';
      PINUSE='POWER';
      NO_LOAD_CHECK='Both';
      NO_IO_CHECK='Both';
      NO_ASSERT_CHECK='TRUE';
      NO_DIR_CHECK='TRUE';
      ALLOW_CONNECT='TRUE';
    'VSS_CC42':
      PIN_NUMBER='(0,0,0,0,0,0,0,0,0,0,0,0,0,0,0,0,0,0,0,0,0,0,0,0,0,0,0,0,0,0,0,0,0,0,0,0,CC42,0,0,0)';
      PINUSE='POWER';
      NO_LOAD_CHECK='Both';
      NO_IO_CHECK='Both';
      NO_ASSERT_CHECK='TRUE';
      NO_DIR_CHECK='TRUE';
      ALLOW_CONNECT='TRUE';
    'VSS_CC45':
      PIN_NUMBER='(0,0,0,0,0,0,0,0,0,0,0,0,0,0,0,0,0,0,0,0,0,0,0,0,0,0,0,0,0,0,0,0,0,0,0,0,CC45,0,0,0)';
      PINUSE='POWER';
      NO_LOAD_CHECK='Both';
      NO_IO_CHECK='Both';
      NO_ASSERT_CHECK='TRUE';
      NO_DIR_CHECK='TRUE';
      ALLOW_CONNECT='TRUE';
    'VSS_CC48':
      PIN_NUMBER='(0,0,0,0,0,0,0,0,0,0,0,0,0,0,0,0,0,0,0,0,0,0,0,0,0,0,0,0,0,0,0,0,0,0,0,0,CC48,0,0,0)';
      PINUSE='POWER';
      NO_LOAD_CHECK='Both';
      NO_IO_CHECK='Both';
      NO_ASSERT_CHECK='TRUE';
      NO_DIR_CHECK='TRUE';
      ALLOW_CONNECT='TRUE';
    'VSS_CC51':
      PIN_NUMBER='(0,0,0,0,0,0,0,0,0,0,0,0,0,0,0,0,0,0,0,0,0,0,0,0,0,0,0,0,0,0,0,0,0,0,0,0,CC51,0,0,0)';
      PINUSE='POWER';
      NO_LOAD_CHECK='Both';
      NO_IO_CHECK='Both';
      NO_ASSERT_CHECK='TRUE';
      NO_DIR_CHECK='TRUE';
      ALLOW_CONNECT='TRUE';
    'VSS_CC54':
      PIN_NUMBER='(0,0,0,0,0,0,0,0,0,0,0,0,0,0,0,0,0,0,0,0,0,0,0,0,0,0,0,0,0,0,0,0,0,0,0,0,CC54,0,0,0)';
      PINUSE='POWER';
      NO_LOAD_CHECK='Both';
      NO_IO_CHECK='Both';
      NO_ASSERT_CHECK='TRUE';
      NO_DIR_CHECK='TRUE';
      ALLOW_CONNECT='TRUE';
    'VSS_CC56':
      PIN_NUMBER='(0,0,0,0,0,0,0,0,0,0,0,0,0,0,0,0,0,0,0,0,0,0,0,0,0,0,0,0,0,0,0,0,0,0,0,0,CC56,0,0,0)';
      PINUSE='POWER';
      NO_LOAD_CHECK='Both';
      NO_IO_CHECK='Both';
      NO_ASSERT_CHECK='TRUE';
      NO_DIR_CHECK='TRUE';
      ALLOW_CONNECT='TRUE';
    'VSS_CC58':
      PIN_NUMBER='(0,0,0,0,0,0,0,0,0,0,0,0,0,0,0,0,0,0,0,0,0,0,0,0,0,0,0,0,0,0,0,0,0,0,0,0,CC58,0,0,0)';
      PINUSE='POWER';
      NO_LOAD_CHECK='Both';
      NO_IO_CHECK='Both';
      NO_ASSERT_CHECK='TRUE';
      NO_DIR_CHECK='TRUE';
      ALLOW_CONNECT='TRUE';
    'VSS_CC61':
      PIN_NUMBER='(0,0,0,0,0,0,0,0,0,0,0,0,0,0,0,0,0,0,0,0,0,0,0,0,0,0,0,0,0,0,0,0,0,0,0,0,CC61,0,0,0)';
      PINUSE='POWER';
      NO_LOAD_CHECK='Both';
      NO_IO_CHECK='Both';
      NO_ASSERT_CHECK='TRUE';
      NO_DIR_CHECK='TRUE';
      ALLOW_CONNECT='TRUE';
    'VSS_CC63':
      PIN_NUMBER='(0,0,0,0,0,0,0,0,0,0,0,0,0,0,0,0,0,0,0,0,0,0,0,0,0,0,0,0,0,0,0,0,0,0,0,0,CC63,0,0,0)';
      PINUSE='POWER';
      NO_LOAD_CHECK='Both';
      NO_IO_CHECK='Both';
      NO_ASSERT_CHECK='TRUE';
      NO_DIR_CHECK='TRUE';
      ALLOW_CONNECT='TRUE';
    'VSS_CC65':
      PIN_NUMBER='(0,0,0,0,0,0,0,0,0,0,0,0,0,0,0,0,0,0,0,0,0,0,0,0,0,0,0,0,0,0,0,0,0,0,0,0,CC65,0,0,0)';
      PINUSE='POWER';
      NO_LOAD_CHECK='Both';
      NO_IO_CHECK='Both';
      NO_ASSERT_CHECK='TRUE';
      NO_DIR_CHECK='TRUE';
      ALLOW_CONNECT='TRUE';
    'VSS_CC68':
      PIN_NUMBER='(0,0,0,0,0,0,0,0,0,0,0,0,0,0,0,0,0,0,0,0,0,0,0,0,0,0,0,0,0,0,0,0,0,0,0,0,CC68,0,0,0)';
      PINUSE='POWER';
      NO_LOAD_CHECK='Both';
      NO_IO_CHECK='Both';
      NO_ASSERT_CHECK='TRUE';
      NO_DIR_CHECK='TRUE';
      ALLOW_CONNECT='TRUE';
    'VSS_CC70':
      PIN_NUMBER='(0,0,0,0,0,0,0,0,0,0,0,0,0,0,0,0,0,0,0,0,0,0,0,0,0,0,0,0,0,0,0,0,0,0,0,0,CC70,0,0,0)';
      PINUSE='POWER';
      NO_LOAD_CHECK='Both';
      NO_IO_CHECK='Both';
      NO_ASSERT_CHECK='TRUE';
      NO_DIR_CHECK='TRUE';
      ALLOW_CONNECT='TRUE';
    'VSS_CC72':
      PIN_NUMBER='(0,0,0,0,0,0,0,0,0,0,0,0,0,0,0,0,0,0,0,0,0,0,0,0,0,0,0,0,0,0,0,0,0,0,0,0,CC72,0,0,0)';
      PINUSE='POWER';
      NO_LOAD_CHECK='Both';
      NO_IO_CHECK='Both';
      NO_ASSERT_CHECK='TRUE';
      NO_DIR_CHECK='TRUE';
      ALLOW_CONNECT='TRUE';
    'VSS_CC75':
      PIN_NUMBER='(0,0,0,0,0,0,0,0,0,0,0,0,0,0,0,0,0,0,0,0,0,0,0,0,0,0,0,0,0,0,0,0,0,0,0,0,CC75,0,0,0)';
      PINUSE='POWER';
      NO_LOAD_CHECK='Both';
      NO_IO_CHECK='Both';
      NO_ASSERT_CHECK='TRUE';
      NO_DIR_CHECK='TRUE';
      ALLOW_CONNECT='TRUE';
    'VSS_CD3':
      PIN_NUMBER='(0,0,0,0,0,0,0,0,0,0,0,0,0,0,0,0,0,0,0,0,0,0,0,0,0,0,0,0,0,0,0,0,0,0,0,0,CD3,0,0,0)';
      PINUSE='POWER';
      NO_LOAD_CHECK='Both';
      NO_IO_CHECK='Both';
      NO_ASSERT_CHECK='TRUE';
      NO_DIR_CHECK='TRUE';
      ALLOW_CONNECT='TRUE';
    'VSS_CD8':
      PIN_NUMBER='(0,0,0,0,0,0,0,0,0,0,0,0,0,0,0,0,0,0,0,0,0,0,0,0,0,0,0,0,0,0,0,0,0,0,0,0,CD8,0,0,0)';
      PINUSE='POWER';
      NO_LOAD_CHECK='Both';
      NO_IO_CHECK='Both';
      NO_ASSERT_CHECK='TRUE';
      NO_DIR_CHECK='TRUE';
      ALLOW_CONNECT='TRUE';
    'VSS_CD10':
      PIN_NUMBER='(0,0,0,0,0,0,0,0,0,0,0,0,0,0,0,0,0,0,0,0,0,0,0,0,0,0,0,0,0,0,0,0,0,0,0,0,CD10,0,0,0)';
      PINUSE='POWER';
      NO_LOAD_CHECK='Both';
      NO_IO_CHECK='Both';
      NO_ASSERT_CHECK='TRUE';
      NO_DIR_CHECK='TRUE';
      ALLOW_CONNECT='TRUE';
    'VSS_CD15':
      PIN_NUMBER='(0,0,0,0,0,0,0,0,0,0,0,0,0,0,0,0,0,0,0,0,0,0,0,0,0,0,0,0,0,0,0,0,0,0,0,0,CD15,0,0,0)';
      PINUSE='POWER';
      NO_LOAD_CHECK='Both';
      NO_IO_CHECK='Both';
      NO_ASSERT_CHECK='TRUE';
      NO_DIR_CHECK='TRUE';
      ALLOW_CONNECT='TRUE';
    'VSS_CD17':
      PIN_NUMBER='(0,0,0,0,0,0,0,0,0,0,0,0,0,0,0,0,0,0,0,0,0,0,0,0,0,0,0,0,0,0,0,0,0,0,0,0,CD17,0,0,0)';
      PINUSE='POWER';
      NO_LOAD_CHECK='Both';
      NO_IO_CHECK='Both';
      NO_ASSERT_CHECK='TRUE';
      NO_DIR_CHECK='TRUE';
      ALLOW_CONNECT='TRUE';
    'VSS_CD22':
      PIN_NUMBER='(0,0,0,0,0,0,0,0,0,0,0,0,0,0,0,0,0,0,0,0,0,0,0,0,0,0,0,0,0,0,0,0,0,0,0,0,CD22,0,0,0)';
      PINUSE='POWER';
      NO_LOAD_CHECK='Both';
      NO_IO_CHECK='Both';
      NO_ASSERT_CHECK='TRUE';
      NO_DIR_CHECK='TRUE';
      ALLOW_CONNECT='TRUE';
    'VSS_CD25':
      PIN_NUMBER='(0,0,0,0,0,0,0,0,0,0,0,0,0,0,0,0,0,0,0,0,0,0,0,0,0,0,0,0,0,0,0,0,0,0,0,0,CD25,0,0,0)';
      PINUSE='POWER';
      NO_LOAD_CHECK='Both';
      NO_IO_CHECK='Both';
      NO_ASSERT_CHECK='TRUE';
      NO_DIR_CHECK='TRUE';
      ALLOW_CONNECT='TRUE';
    'VSS_CD28':
      PIN_NUMBER='(0,0,0,0,0,0,0,0,0,0,0,0,0,0,0,0,0,0,0,0,0,0,0,0,0,0,0,0,0,0,0,0,0,0,0,0,CD28,0,0,0)';
      PINUSE='POWER';
      NO_LOAD_CHECK='Both';
      NO_IO_CHECK='Both';
      NO_ASSERT_CHECK='TRUE';
      NO_DIR_CHECK='TRUE';
      ALLOW_CONNECT='TRUE';
    'VSS_CD31':
      PIN_NUMBER='(0,0,0,0,0,0,0,0,0,0,0,0,0,0,0,0,0,0,0,0,0,0,0,0,0,0,0,0,0,0,0,0,0,0,0,0,CD31,0,0,0)';
      PINUSE='POWER';
      NO_LOAD_CHECK='Both';
      NO_IO_CHECK='Both';
      NO_ASSERT_CHECK='TRUE';
      NO_DIR_CHECK='TRUE';
      ALLOW_CONNECT='TRUE';
    'VSS_CD34':
      PIN_NUMBER='(0,0,0,0,0,0,0,0,0,0,0,0,0,0,0,0,0,0,0,0,0,0,0,0,0,0,0,0,0,0,0,0,0,0,0,0,CD34,0,0,0)';
      PINUSE='POWER';
      NO_LOAD_CHECK='Both';
      NO_IO_CHECK='Both';
      NO_ASSERT_CHECK='TRUE';
      NO_DIR_CHECK='TRUE';
      ALLOW_CONNECT='TRUE';
    'VSS_CD37':
      PIN_NUMBER='(0,0,0,0,0,0,0,0,0,0,0,0,0,0,0,0,0,0,0,0,0,0,0,0,0,0,0,0,0,0,0,0,0,0,0,0,CD37,0,0,0)';
      PINUSE='POWER';
      NO_LOAD_CHECK='Both';
      NO_IO_CHECK='Both';
      NO_ASSERT_CHECK='TRUE';
      NO_DIR_CHECK='TRUE';
      ALLOW_CONNECT='TRUE';
    'VSS_CD39':
      PIN_NUMBER='(0,0,0,0,0,0,0,0,0,0,0,0,0,0,0,0,0,0,0,0,0,0,0,0,0,0,0,0,0,0,0,0,0,0,0,0,CD39,0,0,0)';
      PINUSE='POWER';
      NO_LOAD_CHECK='Both';
      NO_IO_CHECK='Both';
      NO_ASSERT_CHECK='TRUE';
      NO_DIR_CHECK='TRUE';
      ALLOW_CONNECT='TRUE';
    'VSS_CD42':
      PIN_NUMBER='(0,0,0,0,0,0,0,0,0,0,0,0,0,0,0,0,0,0,0,0,0,0,0,0,0,0,0,0,0,0,0,0,0,0,0,0,CD42,0,0,0)';
      PINUSE='POWER';
      NO_LOAD_CHECK='Both';
      NO_IO_CHECK='Both';
      NO_ASSERT_CHECK='TRUE';
      NO_DIR_CHECK='TRUE';
      ALLOW_CONNECT='TRUE';
    'VSS_CD45':
      PIN_NUMBER='(0,0,0,0,0,0,0,0,0,0,0,0,0,0,0,0,0,0,0,0,0,0,0,0,0,0,0,0,0,0,0,0,0,0,0,0,CD45,0,0,0)';
      PINUSE='POWER';
      NO_LOAD_CHECK='Both';
      NO_IO_CHECK='Both';
      NO_ASSERT_CHECK='TRUE';
      NO_DIR_CHECK='TRUE';
      ALLOW_CONNECT='TRUE';
    'VSS_CD48':
      PIN_NUMBER='(0,0,0,0,0,0,0,0,0,0,0,0,0,0,0,0,0,0,0,0,0,0,0,0,0,0,0,0,0,0,0,0,0,0,0,0,CD48,0,0,0)';
      PINUSE='POWER';
      NO_LOAD_CHECK='Both';
      NO_IO_CHECK='Both';
      NO_ASSERT_CHECK='TRUE';
      NO_DIR_CHECK='TRUE';
      ALLOW_CONNECT='TRUE';
    'VSS_CD51':
      PIN_NUMBER='(0,0,0,0,0,0,0,0,0,0,0,0,0,0,0,0,0,0,0,0,0,0,0,0,0,0,0,0,0,0,0,0,0,0,0,0,CD51,0,0,0)';
      PINUSE='POWER';
      NO_LOAD_CHECK='Both';
      NO_IO_CHECK='Both';
      NO_ASSERT_CHECK='TRUE';
      NO_DIR_CHECK='TRUE';
      ALLOW_CONNECT='TRUE';
    'VSS_CD54':
      PIN_NUMBER='(0,0,0,0,0,0,0,0,0,0,0,0,0,0,0,0,0,0,0,0,0,0,0,0,0,0,0,0,0,0,0,0,0,0,0,0,CD54,0,0,0)';
      PINUSE='POWER';
      NO_LOAD_CHECK='Both';
      NO_IO_CHECK='Both';
      NO_ASSERT_CHECK='TRUE';
      NO_DIR_CHECK='TRUE';
      ALLOW_CONNECT='TRUE';
    'VSS_CD59':
      PIN_NUMBER='(0,0,0,0,0,0,0,0,0,0,0,0,0,0,0,0,0,0,0,0,0,0,0,0,0,0,0,0,0,0,0,0,0,0,0,0,CD59,0,0,0)';
      PINUSE='POWER';
      NO_LOAD_CHECK='Both';
      NO_IO_CHECK='Both';
      NO_ASSERT_CHECK='TRUE';
      NO_DIR_CHECK='TRUE';
      ALLOW_CONNECT='TRUE';
    'VSS_CD61':
      PIN_NUMBER='(0,0,0,0,0,0,0,0,0,0,0,0,0,0,0,0,0,0,0,0,0,0,0,0,0,0,0,0,0,0,0,0,0,0,0,0,CD61,0,0,0)';
      PINUSE='POWER';
      NO_LOAD_CHECK='Both';
      NO_IO_CHECK='Both';
      NO_ASSERT_CHECK='TRUE';
      NO_DIR_CHECK='TRUE';
      ALLOW_CONNECT='TRUE';
    'VSS_CD66':
      PIN_NUMBER='(0,0,0,0,0,0,0,0,0,0,0,0,0,0,0,0,0,0,0,0,0,0,0,0,0,0,0,0,0,0,0,0,0,0,0,0,CD66,0,0,0)';
      PINUSE='POWER';
      NO_LOAD_CHECK='Both';
      NO_IO_CHECK='Both';
      NO_ASSERT_CHECK='TRUE';
      NO_DIR_CHECK='TRUE';
      ALLOW_CONNECT='TRUE';
    'VSS_CD68':
      PIN_NUMBER='(0,0,0,0,0,0,0,0,0,0,0,0,0,0,0,0,0,0,0,0,0,0,0,0,0,0,0,0,0,0,0,0,0,0,0,0,CD68,0,0,0)';
      PINUSE='POWER';
      NO_LOAD_CHECK='Both';
      NO_IO_CHECK='Both';
      NO_ASSERT_CHECK='TRUE';
      NO_DIR_CHECK='TRUE';
      ALLOW_CONNECT='TRUE';
    'VSS_CD73':
      PIN_NUMBER='(0,0,0,0,0,0,0,0,0,0,0,0,0,0,0,0,0,0,0,0,0,0,0,0,0,0,0,0,0,0,0,0,0,0,0,0,CD73,0,0,0)';
      PINUSE='POWER';
      NO_LOAD_CHECK='Both';
      NO_IO_CHECK='Both';
      NO_ASSERT_CHECK='TRUE';
      NO_DIR_CHECK='TRUE';
      ALLOW_CONNECT='TRUE';
    'VSS_CE1':
      PIN_NUMBER='(0,0,0,0,0,0,0,0,0,0,0,0,0,0,0,0,0,0,0,0,0,0,0,0,0,0,0,0,0,0,0,0,0,0,0,0,CE1,0,0,0)';
      PINUSE='POWER';
      NO_LOAD_CHECK='Both';
      NO_IO_CHECK='Both';
      NO_ASSERT_CHECK='TRUE';
      NO_DIR_CHECK='TRUE';
      ALLOW_CONNECT='TRUE';
    'VSS_CE4':
      PIN_NUMBER='(0,0,0,0,0,0,0,0,0,0,0,0,0,0,0,0,0,0,0,0,0,0,0,0,0,0,0,0,0,0,0,0,0,0,0,0,CE4,0,0,0)';
      PINUSE='POWER';
      NO_LOAD_CHECK='Both';
      NO_IO_CHECK='Both';
      NO_ASSERT_CHECK='TRUE';
      NO_DIR_CHECK='TRUE';
      ALLOW_CONNECT='TRUE';
    'VSS_CE6':
      PIN_NUMBER='(0,0,0,0,0,0,0,0,0,0,0,0,0,0,0,0,0,0,0,0,0,0,0,0,0,0,0,0,0,0,0,0,0,0,0,0,CE6,0,0,0)';
      PINUSE='POWER';
      NO_LOAD_CHECK='Both';
      NO_IO_CHECK='Both';
      NO_ASSERT_CHECK='TRUE';
      NO_DIR_CHECK='TRUE';
      ALLOW_CONNECT='TRUE';
    'VSS_CE8':
      PIN_NUMBER='(0,0,0,0,0,0,0,0,0,0,0,0,0,0,0,0,0,0,0,0,0,0,0,0,0,0,0,0,0,0,0,0,0,0,0,0,CE8,0,0,0)';
      PINUSE='POWER';
      NO_LOAD_CHECK='Both';
      NO_IO_CHECK='Both';
      NO_ASSERT_CHECK='TRUE';
      NO_DIR_CHECK='TRUE';
      ALLOW_CONNECT='TRUE';
    'VSS_CE11':
      PIN_NUMBER='(0,0,0,0,0,0,0,0,0,0,0,0,0,0,0,0,0,0,0,0,0,0,0,0,0,0,0,0,0,0,0,0,0,0,0,0,CE11,0,0,0)';
      PINUSE='POWER';
      NO_LOAD_CHECK='Both';
      NO_IO_CHECK='Both';
      NO_ASSERT_CHECK='TRUE';
      NO_DIR_CHECK='TRUE';
      ALLOW_CONNECT='TRUE';
    'VSS_CE13':
      PIN_NUMBER='(0,0,0,0,0,0,0,0,0,0,0,0,0,0,0,0,0,0,0,0,0,0,0,0,0,0,0,0,0,0,0,0,0,0,0,0,CE13,0,0,0)';
      PINUSE='POWER';
      NO_LOAD_CHECK='Both';
      NO_IO_CHECK='Both';
      NO_ASSERT_CHECK='TRUE';
      NO_DIR_CHECK='TRUE';
      ALLOW_CONNECT='TRUE';
    'VSS_CE15':
      PIN_NUMBER='(0,0,0,0,0,0,0,0,0,0,0,0,0,0,0,0,0,0,0,0,0,0,0,0,0,0,0,0,0,0,0,0,0,0,0,0,CE15,0,0,0)';
      PINUSE='POWER';
      NO_LOAD_CHECK='Both';
      NO_IO_CHECK='Both';
      NO_ASSERT_CHECK='TRUE';
      NO_DIR_CHECK='TRUE';
      ALLOW_CONNECT='TRUE';
    'VSS_CE18':
      PIN_NUMBER='(0,0,0,0,0,0,0,0,0,0,0,0,0,0,0,0,0,0,0,0,0,0,0,0,0,0,0,0,0,0,0,0,0,0,0,0,CE18,0,0,0)';
      PINUSE='POWER';
      NO_LOAD_CHECK='Both';
      NO_IO_CHECK='Both';
      NO_ASSERT_CHECK='TRUE';
      NO_DIR_CHECK='TRUE';
      ALLOW_CONNECT='TRUE';
    'VSS_CE20':
      PIN_NUMBER='(0,0,0,0,0,0,0,0,0,0,0,0,0,0,0,0,0,0,0,0,0,0,0,0,0,0,0,0,0,0,0,0,0,0,0,0,CE20,0,0,0)';
      PINUSE='POWER';
      NO_LOAD_CHECK='Both';
      NO_IO_CHECK='Both';
      NO_ASSERT_CHECK='TRUE';
      NO_DIR_CHECK='TRUE';
      ALLOW_CONNECT='TRUE';
    'VSS_CE22':
      PIN_NUMBER='(0,0,0,0,0,0,0,0,0,0,0,0,0,0,0,0,0,0,0,0,0,0,0,0,0,0,0,0,0,0,0,0,0,0,0,0,CE22,0,0,0)';
      PINUSE='POWER';
      NO_LOAD_CHECK='Both';
      NO_IO_CHECK='Both';
      NO_ASSERT_CHECK='TRUE';
      NO_DIR_CHECK='TRUE';
      ALLOW_CONNECT='TRUE';
    'VSS_CE25':
      PIN_NUMBER='(0,0,0,0,0,0,0,0,0,0,0,0,0,0,0,0,0,0,0,0,0,0,0,0,0,0,0,0,0,0,0,0,0,0,0,0,CE25,0,0,0)';
      PINUSE='POWER';
      NO_LOAD_CHECK='Both';
      NO_IO_CHECK='Both';
      NO_ASSERT_CHECK='TRUE';
      NO_DIR_CHECK='TRUE';
      ALLOW_CONNECT='TRUE';
    'VSS_CE28':
      PIN_NUMBER='(0,0,0,0,0,0,0,0,0,0,0,0,0,0,0,0,0,0,0,0,0,0,0,0,0,0,0,0,0,0,0,0,0,0,0,0,CE28,0,0,0)';
      PINUSE='POWER';
      NO_LOAD_CHECK='Both';
      NO_IO_CHECK='Both';
      NO_ASSERT_CHECK='TRUE';
      NO_DIR_CHECK='TRUE';
      ALLOW_CONNECT='TRUE';
    'VSS_CE31':
      PIN_NUMBER='(0,0,0,0,0,0,0,0,0,0,0,0,0,0,0,0,0,0,0,0,0,0,0,0,0,0,0,0,0,0,0,0,0,0,0,0,CE31,0,0,0)';
      PINUSE='POWER';
      NO_LOAD_CHECK='Both';
      NO_IO_CHECK='Both';
      NO_ASSERT_CHECK='TRUE';
      NO_DIR_CHECK='TRUE';
      ALLOW_CONNECT='TRUE';
    'VSS_CE34':
      PIN_NUMBER='(0,0,0,0,0,0,0,0,0,0,0,0,0,0,0,0,0,0,0,0,0,0,0,0,0,0,0,0,0,0,0,0,0,0,0,0,CE34,0,0,0)';
      PINUSE='POWER';
      NO_LOAD_CHECK='Both';
      NO_IO_CHECK='Both';
      NO_ASSERT_CHECK='TRUE';
      NO_DIR_CHECK='TRUE';
      ALLOW_CONNECT='TRUE';
    'VSS_CE35':
      PIN_NUMBER='(0,0,0,0,0,0,0,0,0,0,0,0,0,0,0,0,0,0,0,0,0,0,0,0,0,0,0,0,0,0,0,0,0,0,0,0,CE35,0,0,0)';
      PINUSE='POWER';
      NO_LOAD_CHECK='Both';
      NO_IO_CHECK='Both';
      NO_ASSERT_CHECK='TRUE';
      NO_DIR_CHECK='TRUE';
      ALLOW_CONNECT='TRUE';
    'VSS_CE36':
      PIN_NUMBER='(0,0,0,0,0,0,0,0,0,0,0,0,0,0,0,0,0,0,0,0,0,0,0,0,0,0,0,0,0,0,0,0,0,0,0,0,CE36,0,0,0)';
      PINUSE='POWER';
      NO_LOAD_CHECK='Both';
      NO_IO_CHECK='Both';
      NO_ASSERT_CHECK='TRUE';
      NO_DIR_CHECK='TRUE';
      ALLOW_CONNECT='TRUE';
    'VSS_CE40':
      PIN_NUMBER='(0,0,0,0,0,0,0,0,0,0,0,0,0,0,0,0,0,0,0,0,0,0,0,0,0,0,0,0,0,0,0,0,0,0,0,0,CE40,0,0,0)';
      PINUSE='POWER';
      NO_LOAD_CHECK='Both';
      NO_IO_CHECK='Both';
      NO_ASSERT_CHECK='TRUE';
      NO_DIR_CHECK='TRUE';
      ALLOW_CONNECT='TRUE';
    'VSS_CE41':
      PIN_NUMBER='(0,0,0,0,0,0,0,0,0,0,0,0,0,0,0,0,0,0,0,0,0,0,0,0,0,0,0,0,0,0,0,0,0,0,0,0,CE41,0,0,0)';
      PINUSE='POWER';
      NO_LOAD_CHECK='Both';
      NO_IO_CHECK='Both';
      NO_ASSERT_CHECK='TRUE';
      NO_DIR_CHECK='TRUE';
      ALLOW_CONNECT='TRUE';
    'VSS_CE42':
      PIN_NUMBER='(0,0,0,0,0,0,0,0,0,0,0,0,0,0,0,0,0,0,0,0,0,0,0,0,0,0,0,0,0,0,0,0,0,0,0,0,CE42,0,0,0)';
      PINUSE='POWER';
      NO_LOAD_CHECK='Both';
      NO_IO_CHECK='Both';
      NO_ASSERT_CHECK='TRUE';
      NO_DIR_CHECK='TRUE';
      ALLOW_CONNECT='TRUE';
    'VSS_CE45':
      PIN_NUMBER='(0,0,0,0,0,0,0,0,0,0,0,0,0,0,0,0,0,0,0,0,0,0,0,0,0,0,0,0,0,0,0,0,0,0,0,0,CE45,0,0,0)';
      PINUSE='POWER';
      NO_LOAD_CHECK='Both';
      NO_IO_CHECK='Both';
      NO_ASSERT_CHECK='TRUE';
      NO_DIR_CHECK='TRUE';
      ALLOW_CONNECT='TRUE';
    'VSS_CE48':
      PIN_NUMBER='(0,0,0,0,0,0,0,0,0,0,0,0,0,0,0,0,0,0,0,0,0,0,0,0,0,0,0,0,0,0,0,0,0,0,0,0,CE48,0,0,0)';
      PINUSE='POWER';
      NO_LOAD_CHECK='Both';
      NO_IO_CHECK='Both';
      NO_ASSERT_CHECK='TRUE';
      NO_DIR_CHECK='TRUE';
      ALLOW_CONNECT='TRUE';
    'VSS_CE51':
      PIN_NUMBER='(0,0,0,0,0,0,0,0,0,0,0,0,0,0,0,0,0,0,0,0,0,0,0,0,0,0,0,0,0,0,0,0,0,0,0,0,CE51,0,0,0)';
      PINUSE='POWER';
      NO_LOAD_CHECK='Both';
      NO_IO_CHECK='Both';
      NO_ASSERT_CHECK='TRUE';
      NO_DIR_CHECK='TRUE';
      ALLOW_CONNECT='TRUE';
    'VSS_CE54':
      PIN_NUMBER='(0,0,0,0,0,0,0,0,0,0,0,0,0,0,0,0,0,0,0,0,0,0,0,0,0,0,0,0,0,0,0,0,0,0,0,0,CE54,0,0,0)';
      PINUSE='POWER';
      NO_LOAD_CHECK='Both';
      NO_IO_CHECK='Both';
      NO_ASSERT_CHECK='TRUE';
      NO_DIR_CHECK='TRUE';
      ALLOW_CONNECT='TRUE';
    'VSS_CE56':
      PIN_NUMBER='(0,0,0,0,0,0,0,0,0,0,0,0,0,0,0,0,0,0,0,0,0,0,0,0,0,0,0,0,0,0,0,0,0,0,0,0,CE56,0,0,0)';
      PINUSE='POWER';
      NO_LOAD_CHECK='Both';
      NO_IO_CHECK='Both';
      NO_ASSERT_CHECK='TRUE';
      NO_DIR_CHECK='TRUE';
      ALLOW_CONNECT='TRUE';
    'VSS_CE58':
      PIN_NUMBER='(0,0,0,0,0,0,0,0,0,0,0,0,0,0,0,0,0,0,0,0,0,0,0,0,0,0,0,0,0,0,0,0,0,0,0,0,CE58,0,0,0)';
      PINUSE='POWER';
      NO_LOAD_CHECK='Both';
      NO_IO_CHECK='Both';
      NO_ASSERT_CHECK='TRUE';
      NO_DIR_CHECK='TRUE';
      ALLOW_CONNECT='TRUE';
    'VSS_CE61':
      PIN_NUMBER='(0,0,0,0,0,0,0,0,0,0,0,0,0,0,0,0,0,0,0,0,0,0,0,0,0,0,0,0,0,0,0,0,0,0,0,0,CE61,0,0,0)';
      PINUSE='POWER';
      NO_LOAD_CHECK='Both';
      NO_IO_CHECK='Both';
      NO_ASSERT_CHECK='TRUE';
      NO_DIR_CHECK='TRUE';
      ALLOW_CONNECT='TRUE';
    'VSS_CE63':
      PIN_NUMBER='(0,0,0,0,0,0,0,0,0,0,0,0,0,0,0,0,0,0,0,0,0,0,0,0,0,0,0,0,0,0,0,0,0,0,0,0,CE63,0,0,0)';
      PINUSE='POWER';
      NO_LOAD_CHECK='Both';
      NO_IO_CHECK='Both';
      NO_ASSERT_CHECK='TRUE';
      NO_DIR_CHECK='TRUE';
      ALLOW_CONNECT='TRUE';
    'VSS_CE65':
      PIN_NUMBER='(0,0,0,0,0,0,0,0,0,0,0,0,0,0,0,0,0,0,0,0,0,0,0,0,0,0,0,0,0,0,0,0,0,0,0,0,CE65,0,0,0)';
      PINUSE='POWER';
      NO_LOAD_CHECK='Both';
      NO_IO_CHECK='Both';
      NO_ASSERT_CHECK='TRUE';
      NO_DIR_CHECK='TRUE';
      ALLOW_CONNECT='TRUE';
    'VSS_CE68':
      PIN_NUMBER='(0,0,0,0,0,0,0,0,0,0,0,0,0,0,0,0,0,0,0,0,0,0,0,0,0,0,0,0,0,0,0,0,0,0,0,0,CE68,0,0,0)';
      PINUSE='POWER';
      NO_LOAD_CHECK='Both';
      NO_IO_CHECK='Both';
      NO_ASSERT_CHECK='TRUE';
      NO_DIR_CHECK='TRUE';
      ALLOW_CONNECT='TRUE';
    'VSS_CE70':
      PIN_NUMBER='(0,0,0,0,0,0,0,0,0,0,0,0,0,0,0,0,0,0,0,0,0,0,0,0,0,0,0,0,0,0,0,0,0,0,0,0,CE70,0,0,0)';
      PINUSE='POWER';
      NO_LOAD_CHECK='Both';
      NO_IO_CHECK='Both';
      NO_ASSERT_CHECK='TRUE';
      NO_DIR_CHECK='TRUE';
      ALLOW_CONNECT='TRUE';
    'VSS_CE72':
      PIN_NUMBER='(0,0,0,0,0,0,0,0,0,0,0,0,0,0,0,0,0,0,0,0,0,0,0,0,0,0,0,0,0,0,0,0,0,0,0,0,CE72,0,0,0)';
      PINUSE='POWER';
      NO_LOAD_CHECK='Both';
      NO_IO_CHECK='Both';
      NO_ASSERT_CHECK='TRUE';
      NO_DIR_CHECK='TRUE';
      ALLOW_CONNECT='TRUE';
    'VSS_CE75':
      PIN_NUMBER='(0,0,0,0,0,0,0,0,0,0,0,0,0,0,0,0,0,0,0,0,0,0,0,0,0,0,0,0,0,0,0,0,0,0,0,0,CE75,0,0,0)';
      PINUSE='POWER';
      NO_LOAD_CHECK='Both';
      NO_IO_CHECK='Both';
      NO_ASSERT_CHECK='TRUE';
      NO_DIR_CHECK='TRUE';
      ALLOW_CONNECT='TRUE';
    'VSS_CF3':
      PIN_NUMBER='(0,0,0,0,0,0,0,0,0,0,0,0,0,0,0,0,0,0,0,0,0,0,0,0,0,0,0,0,0,0,0,0,0,0,0,0,CF3,0,0,0)';
      PINUSE='POWER';
      NO_LOAD_CHECK='Both';
      NO_IO_CHECK='Both';
      NO_ASSERT_CHECK='TRUE';
      NO_DIR_CHECK='TRUE';
      ALLOW_CONNECT='TRUE';
    'VSS_CF5':
      PIN_NUMBER='(0,0,0,0,0,0,0,0,0,0,0,0,0,0,0,0,0,0,0,0,0,0,0,0,0,0,0,0,0,0,0,0,0,0,0,0,CF5,0,0,0)';
      PINUSE='POWER';
      NO_LOAD_CHECK='Both';
      NO_IO_CHECK='Both';
      NO_ASSERT_CHECK='TRUE';
      NO_DIR_CHECK='TRUE';
      ALLOW_CONNECT='TRUE';
    'VSS_CF8':
      PIN_NUMBER='(0,0,0,0,0,0,0,0,0,0,0,0,0,0,0,0,0,0,0,0,0,0,0,0,0,0,0,0,0,0,0,0,0,0,0,0,CF8,0,0,0)';
      PINUSE='POWER';
      NO_LOAD_CHECK='Both';
      NO_IO_CHECK='Both';
      NO_ASSERT_CHECK='TRUE';
      NO_DIR_CHECK='TRUE';
      ALLOW_CONNECT='TRUE';
    'VSS_CF10':
      PIN_NUMBER='(0,0,0,0,0,0,0,0,0,0,0,0,0,0,0,0,0,0,0,0,0,0,0,0,0,0,0,0,0,0,0,0,0,0,0,0,CF10,0,0,0)';
      PINUSE='POWER';
      NO_LOAD_CHECK='Both';
      NO_IO_CHECK='Both';
      NO_ASSERT_CHECK='TRUE';
      NO_DIR_CHECK='TRUE';
      ALLOW_CONNECT='TRUE';
    'VSS_CF12':
      PIN_NUMBER='(0,0,0,0,0,0,0,0,0,0,0,0,0,0,0,0,0,0,0,0,0,0,0,0,0,0,0,0,0,0,0,0,0,0,0,0,CF12,0,0,0)';
      PINUSE='POWER';
      NO_LOAD_CHECK='Both';
      NO_IO_CHECK='Both';
      NO_ASSERT_CHECK='TRUE';
      NO_DIR_CHECK='TRUE';
      ALLOW_CONNECT='TRUE';
    'VSS_CF15':
      PIN_NUMBER='(0,0,0,0,0,0,0,0,0,0,0,0,0,0,0,0,0,0,0,0,0,0,0,0,0,0,0,0,0,0,0,0,0,0,0,0,CF15,0,0,0)';
      PINUSE='POWER';
      NO_LOAD_CHECK='Both';
      NO_IO_CHECK='Both';
      NO_ASSERT_CHECK='TRUE';
      NO_DIR_CHECK='TRUE';
      ALLOW_CONNECT='TRUE';
    'VSS_CF17':
      PIN_NUMBER='(0,0,0,0,0,0,0,0,0,0,0,0,0,0,0,0,0,0,0,0,0,0,0,0,0,0,0,0,0,0,0,0,0,0,0,0,CF17,0,0,0)';
      PINUSE='POWER';
      NO_LOAD_CHECK='Both';
      NO_IO_CHECK='Both';
      NO_ASSERT_CHECK='TRUE';
      NO_DIR_CHECK='TRUE';
      ALLOW_CONNECT='TRUE';
    'VSS_CF19':
      PIN_NUMBER='(0,0,0,0,0,0,0,0,0,0,0,0,0,0,0,0,0,0,0,0,0,0,0,0,0,0,0,0,0,0,0,0,0,0,0,0,CF19,0,0,0)';
      PINUSE='POWER';
      NO_LOAD_CHECK='Both';
      NO_IO_CHECK='Both';
      NO_ASSERT_CHECK='TRUE';
      NO_DIR_CHECK='TRUE';
      ALLOW_CONNECT='TRUE';
    'VSS_CF23':
      PIN_NUMBER='(0,0,0,0,0,0,0,0,0,0,0,0,0,0,0,0,0,0,0,0,0,0,0,0,0,0,0,0,0,0,0,0,0,0,0,0,CF23,0,0,0)';
      PINUSE='POWER';
      NO_LOAD_CHECK='Both';
      NO_IO_CHECK='Both';
      NO_ASSERT_CHECK='TRUE';
      NO_DIR_CHECK='TRUE';
      ALLOW_CONNECT='TRUE';
    'VSS_CF24':
      PIN_NUMBER='(0,0,0,0,0,0,0,0,0,0,0,0,0,0,0,0,0,0,0,0,0,0,0,0,0,0,0,0,0,0,0,0,0,0,0,0,CF24,0,0,0)';
      PINUSE='POWER';
      NO_LOAD_CHECK='Both';
      NO_IO_CHECK='Both';
      NO_ASSERT_CHECK='TRUE';
      NO_DIR_CHECK='TRUE';
      ALLOW_CONNECT='TRUE';
    'VSS_CF25':
      PIN_NUMBER='(0,0,0,0,0,0,0,0,0,0,0,0,0,0,0,0,0,0,0,0,0,0,0,0,0,0,0,0,0,0,0,0,0,0,0,0,CF25,0,0,0)';
      PINUSE='POWER';
      NO_LOAD_CHECK='Both';
      NO_IO_CHECK='Both';
      NO_ASSERT_CHECK='TRUE';
      NO_DIR_CHECK='TRUE';
      ALLOW_CONNECT='TRUE';
    'VSS_CF26':
      PIN_NUMBER='(0,0,0,0,0,0,0,0,0,0,0,0,0,0,0,0,0,0,0,0,0,0,0,0,0,0,0,0,0,0,0,0,0,0,0,0,CF26,0,0,0)';
      PINUSE='POWER';
      NO_LOAD_CHECK='Both';
      NO_IO_CHECK='Both';
      NO_ASSERT_CHECK='TRUE';
      NO_DIR_CHECK='TRUE';
      ALLOW_CONNECT='TRUE';
    'VSS_CF27':
      PIN_NUMBER='(0,0,0,0,0,0,0,0,0,0,0,0,0,0,0,0,0,0,0,0,0,0,0,0,0,0,0,0,0,0,0,0,0,0,0,0,CF27,0,0,0)';
      PINUSE='POWER';
      NO_LOAD_CHECK='Both';
      NO_IO_CHECK='Both';
      NO_ASSERT_CHECK='TRUE';
      NO_DIR_CHECK='TRUE';
      ALLOW_CONNECT='TRUE';
    'VSS_CF28':
      PIN_NUMBER='(0,0,0,0,0,0,0,0,0,0,0,0,0,0,0,0,0,0,0,0,0,0,0,0,0,0,0,0,0,0,0,0,0,0,0,0,CF28,0,0,0)';
      PINUSE='POWER';
      NO_LOAD_CHECK='Both';
      NO_IO_CHECK='Both';
      NO_ASSERT_CHECK='TRUE';
      NO_DIR_CHECK='TRUE';
      ALLOW_CONNECT='TRUE';
    'VSS_CF29':
      PIN_NUMBER='(0,0,0,0,0,0,0,0,0,0,0,0,0,0,0,0,0,0,0,0,0,0,0,0,0,0,0,0,0,0,0,0,0,0,0,0,CF29,0,0,0)';
      PINUSE='POWER';
      NO_LOAD_CHECK='Both';
      NO_IO_CHECK='Both';
      NO_ASSERT_CHECK='TRUE';
      NO_DIR_CHECK='TRUE';
      ALLOW_CONNECT='TRUE';
    'VSS_CF30':
      PIN_NUMBER='(0,0,0,0,0,0,0,0,0,0,0,0,0,0,0,0,0,0,0,0,0,0,0,0,0,0,0,0,0,0,0,0,0,0,0,0,CF30,0,0,0)';
      PINUSE='POWER';
      NO_LOAD_CHECK='Both';
      NO_IO_CHECK='Both';
      NO_ASSERT_CHECK='TRUE';
      NO_DIR_CHECK='TRUE';
      ALLOW_CONNECT='TRUE';
    'VSS_CF31':
      PIN_NUMBER='(0,0,0,0,0,0,0,0,0,0,0,0,0,0,0,0,0,0,0,0,0,0,0,0,0,0,0,0,0,0,0,0,0,0,0,0,CF31,0,0,0)';
      PINUSE='POWER';
      NO_LOAD_CHECK='Both';
      NO_IO_CHECK='Both';
      NO_ASSERT_CHECK='TRUE';
      NO_DIR_CHECK='TRUE';
      ALLOW_CONNECT='TRUE';
    'VSS_CF32':
      PIN_NUMBER='(0,0,0,0,0,0,0,0,0,0,0,0,0,0,0,0,0,0,0,0,0,0,0,0,0,0,0,0,0,0,0,0,0,0,0,0,CF32,0,0,0)';
      PINUSE='POWER';
      NO_LOAD_CHECK='Both';
      NO_IO_CHECK='Both';
      NO_ASSERT_CHECK='TRUE';
      NO_DIR_CHECK='TRUE';
      ALLOW_CONNECT='TRUE';
    'VSS_CF33':
      PIN_NUMBER='(0,0,0,0,0,0,0,0,0,0,0,0,0,0,0,0,0,0,0,0,0,0,0,0,0,0,0,0,0,0,0,0,0,0,0,0,CF33,0,0,0)';
      PINUSE='POWER';
      NO_LOAD_CHECK='Both';
      NO_IO_CHECK='Both';
      NO_ASSERT_CHECK='TRUE';
      NO_DIR_CHECK='TRUE';
      ALLOW_CONNECT='TRUE';
    'VSS_CN56':
      PIN_NUMBER='(0,0,0,0,0,0,0,0,0,0,0,0,0,0,0,0,0,0,0,0,0,0,0,0,0,0,0,0,0,0,0,0,0,0,0,0,0,CN56,0,0)';
      PINUSE='POWER';
      NO_LOAD_CHECK='Both';
      NO_IO_CHECK='Both';
      NO_ASSERT_CHECK='TRUE';
      NO_DIR_CHECK='TRUE';
      ALLOW_CONNECT='TRUE';
    'VSS_CN20':
      PIN_NUMBER='(0,0,0,0,0,0,0,0,0,0,0,0,0,0,0,0,0,0,0,0,0,0,0,0,0,0,0,0,0,0,0,0,0,0,0,0,0,CN20,0,0)';
      PINUSE='POWER';
      NO_LOAD_CHECK='Both';
      NO_IO_CHECK='Both';
      NO_ASSERT_CHECK='TRUE';
      NO_DIR_CHECK='TRUE';
      ALLOW_CONNECT='TRUE';
    'VSS_CM61':
      PIN_NUMBER='(0,0,0,0,0,0,0,0,0,0,0,0,0,0,0,0,0,0,0,0,0,0,0,0,0,0,0,0,0,0,0,0,0,0,0,0,0,CM61,0,0)';
      PINUSE='POWER';
      NO_LOAD_CHECK='Both';
      NO_IO_CHECK='Both';
      NO_ASSERT_CHECK='TRUE';
      NO_DIR_CHECK='TRUE';
      ALLOW_CONNECT='TRUE';
    'VSS_CM34':
      PIN_NUMBER='(0,0,0,0,0,0,0,0,0,0,0,0,0,0,0,0,0,0,0,0,0,0,0,0,0,0,0,0,0,0,0,0,0,0,0,0,0,CM34,0,0)';
      PINUSE='POWER';
      NO_LOAD_CHECK='Both';
      NO_IO_CHECK='Both';
      NO_ASSERT_CHECK='TRUE';
      NO_DIR_CHECK='TRUE';
      ALLOW_CONNECT='TRUE';
    'VSS_CK33':
      PIN_NUMBER='(0,0,0,0,0,0,0,0,0,0,0,0,0,0,0,0,0,0,0,0,0,0,0,0,0,0,0,0,0,0,0,0,0,0,0,0,0,CK33,0,0)';
      PINUSE='POWER';
      NO_LOAD_CHECK='Both';
      NO_IO_CHECK='Both';
      NO_ASSERT_CHECK='TRUE';
      NO_DIR_CHECK='TRUE';
      ALLOW_CONNECT='TRUE';
    'VSS_CK15':
      PIN_NUMBER='(0,0,0,0,0,0,0,0,0,0,0,0,0,0,0,0,0,0,0,0,0,0,0,0,0,0,0,0,0,0,0,0,0,0,0,0,0,CK15,0,0)';
      PINUSE='POWER';
      NO_LOAD_CHECK='Both';
      NO_IO_CHECK='Both';
      NO_ASSERT_CHECK='TRUE';
      NO_DIR_CHECK='TRUE';
      ALLOW_CONNECT='TRUE';
    'VSS_CJ58':
      PIN_NUMBER='(0,0,0,0,0,0,0,0,0,0,0,0,0,0,0,0,0,0,0,0,0,0,0,0,0,0,0,0,0,0,0,0,0,0,0,0,0,CJ58,0,0)';
      PINUSE='POWER';
      NO_LOAD_CHECK='Both';
      NO_IO_CHECK='Both';
      NO_ASSERT_CHECK='TRUE';
      NO_DIR_CHECK='TRUE';
      ALLOW_CONNECT='TRUE';
    'VSS_CJ20':
      PIN_NUMBER='(0,0,0,0,0,0,0,0,0,0,0,0,0,0,0,0,0,0,0,0,0,0,0,0,0,0,0,0,0,0,0,0,0,0,0,0,0,CJ20,0,0)';
      PINUSE='POWER';
      NO_LOAD_CHECK='Both';
      NO_IO_CHECK='Both';
      NO_ASSERT_CHECK='TRUE';
      NO_DIR_CHECK='TRUE';
      ALLOW_CONNECT='TRUE';
    'VSS_CH68':
      PIN_NUMBER='(0,0,0,0,0,0,0,0,0,0,0,0,0,0,0,0,0,0,0,0,0,0,0,0,0,0,0,0,0,0,0,0,0,0,0,0,0,CH68,0,0)';
      PINUSE='POWER';
      NO_LOAD_CHECK='Both';
      NO_IO_CHECK='Both';
      NO_ASSERT_CHECK='TRUE';
      NO_DIR_CHECK='TRUE';
      ALLOW_CONNECT='TRUE';
    'VSS_CH39':
      PIN_NUMBER='(0,0,0,0,0,0,0,0,0,0,0,0,0,0,0,0,0,0,0,0,0,0,0,0,0,0,0,0,0,0,0,0,0,0,0,0,0,CH39,0,0)';
      PINUSE='POWER';
      NO_LOAD_CHECK='Both';
      NO_IO_CHECK='Both';
      NO_ASSERT_CHECK='TRUE';
      NO_DIR_CHECK='TRUE';
      ALLOW_CONNECT='TRUE';
    'VSS_CH10':
      PIN_NUMBER='(0,0,0,0,0,0,0,0,0,0,0,0,0,0,0,0,0,0,0,0,0,0,0,0,0,0,0,0,0,0,0,0,0,0,0,0,0,CH10,0,0)';
      PINUSE='POWER';
      NO_LOAD_CHECK='Both';
      NO_IO_CHECK='Both';
      NO_ASSERT_CHECK='TRUE';
      NO_DIR_CHECK='TRUE';
      ALLOW_CONNECT='TRUE';
    'VSS_CN22':
      PIN_NUMBER='(0,0,0,0,0,0,0,0,0,0,0,0,0,0,0,0,0,0,0,0,0,0,0,0,0,0,0,0,0,0,0,0,0,0,0,0,0,CN22,0,0)';
      PINUSE='POWER';
      NO_LOAD_CHECK='Both';
      NO_IO_CHECK='Both';
      NO_ASSERT_CHECK='TRUE';
      NO_DIR_CHECK='TRUE';
      ALLOW_CONNECT='TRUE';
    'VSS_CM64':
      PIN_NUMBER='(0,0,0,0,0,0,0,0,0,0,0,0,0,0,0,0,0,0,0,0,0,0,0,0,0,0,0,0,0,0,0,0,0,0,0,0,0,CM64,0,0)';
      PINUSE='POWER';
      NO_LOAD_CHECK='Both';
      NO_IO_CHECK='Both';
      NO_ASSERT_CHECK='TRUE';
      NO_DIR_CHECK='TRUE';
      ALLOW_CONNECT='TRUE';
    'VSS_CM37':
      PIN_NUMBER='(0,0,0,0,0,0,0,0,0,0,0,0,0,0,0,0,0,0,0,0,0,0,0,0,0,0,0,0,0,0,0,0,0,0,0,0,0,CM37,0,0)';
      PINUSE='POWER';
      NO_LOAD_CHECK='Both';
      NO_IO_CHECK='Both';
      NO_ASSERT_CHECK='TRUE';
      NO_DIR_CHECK='TRUE';
      ALLOW_CONNECT='TRUE';
    'VSS_CM24':
      PIN_NUMBER='(0,0,0,0,0,0,0,0,0,0,0,0,0,0,0,0,0,0,0,0,0,0,0,0,0,0,0,0,0,0,0,0,0,0,0,0,0,CM24,0,0)';
      PINUSE='POWER';
      NO_LOAD_CHECK='Both';
      NO_IO_CHECK='Both';
      NO_ASSERT_CHECK='TRUE';
      NO_DIR_CHECK='TRUE';
      ALLOW_CONNECT='TRUE';
    'VSS_CK17':
      PIN_NUMBER='(0,0,0,0,0,0,0,0,0,0,0,0,0,0,0,0,0,0,0,0,0,0,0,0,0,0,0,0,0,0,0,0,0,0,0,0,0,CK17,0,0)';
      PINUSE='POWER';
      NO_LOAD_CHECK='Both';
      NO_IO_CHECK='Both';
      NO_ASSERT_CHECK='TRUE';
      NO_DIR_CHECK='TRUE';
      ALLOW_CONNECT='TRUE';
    'VSS_CJ61':
      PIN_NUMBER='(0,0,0,0,0,0,0,0,0,0,0,0,0,0,0,0,0,0,0,0,0,0,0,0,0,0,0,0,0,0,0,0,0,0,0,0,0,CJ61,0,0)';
      PINUSE='POWER';
      NO_LOAD_CHECK='Both';
      NO_IO_CHECK='Both';
      NO_ASSERT_CHECK='TRUE';
      NO_DIR_CHECK='TRUE';
      ALLOW_CONNECT='TRUE';
    'VSS_CJ23':
      PIN_NUMBER='(0,0,0,0,0,0,0,0,0,0,0,0,0,0,0,0,0,0,0,0,0,0,0,0,0,0,0,0,0,0,0,0,0,0,0,0,0,CJ23,0,0)';
      PINUSE='POWER';
      NO_LOAD_CHECK='Both';
      NO_IO_CHECK='Both';
      NO_ASSERT_CHECK='TRUE';
      NO_DIR_CHECK='TRUE';
      ALLOW_CONNECT='TRUE';
    'VSS_CH71':
      PIN_NUMBER='(0,0,0,0,0,0,0,0,0,0,0,0,0,0,0,0,0,0,0,0,0,0,0,0,0,0,0,0,0,0,0,0,0,0,0,0,0,CH71,0,0)';
      PINUSE='POWER';
      NO_LOAD_CHECK='Both';
      NO_IO_CHECK='Both';
      NO_ASSERT_CHECK='TRUE';
      NO_DIR_CHECK='TRUE';
      ALLOW_CONNECT='TRUE';
    'VSS_CH42':
      PIN_NUMBER='(0,0,0,0,0,0,0,0,0,0,0,0,0,0,0,0,0,0,0,0,0,0,0,0,0,0,0,0,0,0,0,0,0,0,0,0,0,CH42,0,0)';
      PINUSE='POWER';
      NO_LOAD_CHECK='Both';
      NO_IO_CHECK='Both';
      NO_ASSERT_CHECK='TRUE';
      NO_DIR_CHECK='TRUE';
      ALLOW_CONNECT='TRUE';
    'VSS_CH12':
      PIN_NUMBER='(0,0,0,0,0,0,0,0,0,0,0,0,0,0,0,0,0,0,0,0,0,0,0,0,0,0,0,0,0,0,0,0,0,0,0,0,0,CH12,0,0)';
      PINUSE='POWER';
      NO_LOAD_CHECK='Both';
      NO_IO_CHECK='Both';
      NO_ASSERT_CHECK='TRUE';
      NO_DIR_CHECK='TRUE';
      ALLOW_CONNECT='TRUE';
    'VSS_CM66':
      PIN_NUMBER='(0,0,0,0,0,0,0,0,0,0,0,0,0,0,0,0,0,0,0,0,0,0,0,0,0,0,0,0,0,0,0,0,0,0,0,0,0,CM66,0,0)';
      PINUSE='POWER';
      NO_LOAD_CHECK='Both';
      NO_IO_CHECK='Both';
      NO_ASSERT_CHECK='TRUE';
      NO_DIR_CHECK='TRUE';
      ALLOW_CONNECT='TRUE';
    'VSS_CM39':
      PIN_NUMBER='(0,0,0,0,0,0,0,0,0,0,0,0,0,0,0,0,0,0,0,0,0,0,0,0,0,0,0,0,0,0,0,0,0,0,0,0,0,CM39,0,0)';
      PINUSE='POWER';
      NO_LOAD_CHECK='Both';
      NO_IO_CHECK='Both';
      NO_ASSERT_CHECK='TRUE';
      NO_DIR_CHECK='TRUE';
      ALLOW_CONNECT='TRUE';
    'VSS_CM25':
      PIN_NUMBER='(0,0,0,0,0,0,0,0,0,0,0,0,0,0,0,0,0,0,0,0,0,0,0,0,0,0,0,0,0,0,0,0,0,0,0,0,0,CM25,0,0)';
      PINUSE='POWER';
      NO_LOAD_CHECK='Both';
      NO_IO_CHECK='Both';
      NO_ASSERT_CHECK='TRUE';
      NO_DIR_CHECK='TRUE';
      ALLOW_CONNECT='TRUE';
    'VSS_CL75':
      PIN_NUMBER='(0,0,0,0,0,0,0,0,0,0,0,0,0,0,0,0,0,0,0,0,0,0,0,0,0,0,0,0,0,0,0,0,0,0,0,0,0,CL75,0,0)';
      PINUSE='POWER';
      NO_LOAD_CHECK='Both';
      NO_IO_CHECK='Both';
      NO_ASSERT_CHECK='TRUE';
      NO_DIR_CHECK='TRUE';
      ALLOW_CONNECT='TRUE';
    'VSS_CJ63':
      PIN_NUMBER='(0,0,0,0,0,0,0,0,0,0,0,0,0,0,0,0,0,0,0,0,0,0,0,0,0,0,0,0,0,0,0,0,0,0,0,0,0,CJ63,0,0)';
      PINUSE='POWER';
      NO_LOAD_CHECK='Both';
      NO_IO_CHECK='Both';
      NO_ASSERT_CHECK='TRUE';
      NO_DIR_CHECK='TRUE';
      ALLOW_CONNECT='TRUE';
    'VSS_CJ31':
      PIN_NUMBER='(0,0,0,0,0,0,0,0,0,0,0,0,0,0,0,0,0,0,0,0,0,0,0,0,0,0,0,0,0,0,0,0,0,0,0,0,0,CJ31,0,0)';
      PINUSE='POWER';
      NO_LOAD_CHECK='Both';
      NO_IO_CHECK='Both';
      NO_ASSERT_CHECK='TRUE';
      NO_DIR_CHECK='TRUE';
      ALLOW_CONNECT='TRUE';
    'VSS_CH73':
      PIN_NUMBER='(0,0,0,0,0,0,0,0,0,0,0,0,0,0,0,0,0,0,0,0,0,0,0,0,0,0,0,0,0,0,0,0,0,0,0,0,0,CH73,0,0)';
      PINUSE='POWER';
      NO_LOAD_CHECK='Both';
      NO_IO_CHECK='Both';
      NO_ASSERT_CHECK='TRUE';
      NO_DIR_CHECK='TRUE';
      ALLOW_CONNECT='TRUE';
    'VSS_CH45':
      PIN_NUMBER='(0,0,0,0,0,0,0,0,0,0,0,0,0,0,0,0,0,0,0,0,0,0,0,0,0,0,0,0,0,0,0,0,0,0,0,0,0,CH45,0,0)';
      PINUSE='POWER';
      NO_LOAD_CHECK='Both';
      NO_IO_CHECK='Both';
      NO_ASSERT_CHECK='TRUE';
      NO_DIR_CHECK='TRUE';
      ALLOW_CONNECT='TRUE';
    'VSS_CH15':
      PIN_NUMBER='(0,0,0,0,0,0,0,0,0,0,0,0,0,0,0,0,0,0,0,0,0,0,0,0,0,0,0,0,0,0,0,0,0,0,0,0,0,CH15,0,0)';
      PINUSE='POWER';
      NO_LOAD_CHECK='Both';
      NO_IO_CHECK='Both';
      NO_ASSERT_CHECK='TRUE';
      NO_DIR_CHECK='TRUE';
      ALLOW_CONNECT='TRUE';
    'VSS_CM42':
      PIN_NUMBER='(0,0,0,0,0,0,0,0,0,0,0,0,0,0,0,0,0,0,0,0,0,0,0,0,0,0,0,0,0,0,0,0,0,0,0,0,0,CM42,0,0)';
      PINUSE='POWER';
      NO_LOAD_CHECK='Both';
      NO_IO_CHECK='Both';
      NO_ASSERT_CHECK='TRUE';
      NO_DIR_CHECK='TRUE';
      ALLOW_CONNECT='TRUE';
    'VSS_CM26':
      PIN_NUMBER='(0,0,0,0,0,0,0,0,0,0,0,0,0,0,0,0,0,0,0,0,0,0,0,0,0,0,0,0,0,0,0,0,0,0,0,0,0,CM26,0,0)';
      PINUSE='POWER';
      NO_LOAD_CHECK='Both';
      NO_IO_CHECK='Both';
      NO_ASSERT_CHECK='TRUE';
      NO_DIR_CHECK='TRUE';
      ALLOW_CONNECT='TRUE';
    'VSS_CM3':
      PIN_NUMBER='(0,0,0,0,0,0,0,0,0,0,0,0,0,0,0,0,0,0,0,0,0,0,0,0,0,0,0,0,0,0,0,0,0,0,0,0,0,CM3,0,0)';
      PINUSE='POWER';
      NO_LOAD_CHECK='Both';
      NO_IO_CHECK='Both';
      NO_ASSERT_CHECK='TRUE';
      NO_DIR_CHECK='TRUE';
      ALLOW_CONNECT='TRUE';
    'VSS_CL51':
      PIN_NUMBER='(0,0,0,0,0,0,0,0,0,0,0,0,0,0,0,0,0,0,0,0,0,0,0,0,0,0,0,0,0,0,0,0,0,0,0,0,0,CL51,0,0)';
      PINUSE='POWER';
      NO_LOAD_CHECK='Both';
      NO_IO_CHECK='Both';
      NO_ASSERT_CHECK='TRUE';
      NO_DIR_CHECK='TRUE';
      ALLOW_CONNECT='TRUE';
    'VSS_CJ34':
      PIN_NUMBER='(0,0,0,0,0,0,0,0,0,0,0,0,0,0,0,0,0,0,0,0,0,0,0,0,0,0,0,0,0,0,0,0,0,0,0,0,0,CJ34,0,0)';
      PINUSE='POWER';
      NO_LOAD_CHECK='Both';
      NO_IO_CHECK='Both';
      NO_ASSERT_CHECK='TRUE';
      NO_DIR_CHECK='TRUE';
      ALLOW_CONNECT='TRUE';
    'VSS_CJ1':
      PIN_NUMBER='(0,0,0,0,0,0,0,0,0,0,0,0,0,0,0,0,0,0,0,0,0,0,0,0,0,0,0,0,0,0,0,0,0,0,0,0,0,CJ1,0,0)';
      PINUSE='POWER';
      NO_LOAD_CHECK='Both';
      NO_IO_CHECK='Both';
      NO_ASSERT_CHECK='TRUE';
      NO_DIR_CHECK='TRUE';
      ALLOW_CONNECT='TRUE';
    'VSS_CH48':
      PIN_NUMBER='(0,0,0,0,0,0,0,0,0,0,0,0,0,0,0,0,0,0,0,0,0,0,0,0,0,0,0,0,0,0,0,0,0,0,0,0,0,CH48,0,0)';
      PINUSE='POWER';
      NO_LOAD_CHECK='Both';
      NO_IO_CHECK='Both';
      NO_ASSERT_CHECK='TRUE';
      NO_DIR_CHECK='TRUE';
      ALLOW_CONNECT='TRUE';
    'VSS_CH17':
      PIN_NUMBER='(0,0,0,0,0,0,0,0,0,0,0,0,0,0,0,0,0,0,0,0,0,0,0,0,0,0,0,0,0,0,0,0,0,0,0,0,0,CH17,0,0)';
      PINUSE='POWER';
      NO_LOAD_CHECK='Both';
      NO_IO_CHECK='Both';
      NO_ASSERT_CHECK='TRUE';
      NO_DIR_CHECK='TRUE';
      ALLOW_CONNECT='TRUE';
    'VSS_CM43':
      PIN_NUMBER='(0,0,0,0,0,0,0,0,0,0,0,0,0,0,0,0,0,0,0,0,0,0,0,0,0,0,0,0,0,0,0,0,0,0,0,0,0,CM43,0,0)';
      PINUSE='POWER';
      NO_LOAD_CHECK='Both';
      NO_IO_CHECK='Both';
      NO_ASSERT_CHECK='TRUE';
      NO_DIR_CHECK='TRUE';
      ALLOW_CONNECT='TRUE';
    'VSS_CM27':
      PIN_NUMBER='(0,0,0,0,0,0,0,0,0,0,0,0,0,0,0,0,0,0,0,0,0,0,0,0,0,0,0,0,0,0,0,0,0,0,0,0,0,CM27,0,0)';
      PINUSE='POWER';
      NO_LOAD_CHECK='Both';
      NO_IO_CHECK='Both';
      NO_ASSERT_CHECK='TRUE';
      NO_DIR_CHECK='TRUE';
      ALLOW_CONNECT='TRUE';
    'VSS_CM5':
      PIN_NUMBER='(0,0,0,0,0,0,0,0,0,0,0,0,0,0,0,0,0,0,0,0,0,0,0,0,0,0,0,0,0,0,0,0,0,0,0,0,0,CM5,0,0)';
      PINUSE='POWER';
      NO_LOAD_CHECK='Both';
      NO_IO_CHECK='Both';
      NO_ASSERT_CHECK='TRUE';
      NO_DIR_CHECK='TRUE';
      ALLOW_CONNECT='TRUE';
    'VSS_CL54':
      PIN_NUMBER='(0,0,0,0,0,0,0,0,0,0,0,0,0,0,0,0,0,0,0,0,0,0,0,0,0,0,0,0,0,0,0,0,0,0,0,0,0,CL54,0,0)';
      PINUSE='POWER';
      NO_LOAD_CHECK='Both';
      NO_IO_CHECK='Both';
      NO_ASSERT_CHECK='TRUE';
      NO_DIR_CHECK='TRUE';
      ALLOW_CONNECT='TRUE';
    'VSS_CL28':
      PIN_NUMBER='(0,0,0,0,0,0,0,0,0,0,0,0,0,0,0,0,0,0,0,0,0,0,0,0,0,0,0,0,0,0,0,0,0,0,0,0,0,CL28,0,0)';
      PINUSE='POWER';
      NO_LOAD_CHECK='Both';
      NO_IO_CHECK='Both';
      NO_ASSERT_CHECK='TRUE';
      NO_DIR_CHECK='TRUE';
      ALLOW_CONNECT='TRUE';
    'VSS_CJ4':
      PIN_NUMBER='(0,0,0,0,0,0,0,0,0,0,0,0,0,0,0,0,0,0,0,0,0,0,0,0,0,0,0,0,0,0,0,0,0,0,0,0,0,CJ4,0,0)';
      PINUSE='POWER';
      NO_LOAD_CHECK='Both';
      NO_IO_CHECK='Both';
      NO_ASSERT_CHECK='TRUE';
      NO_DIR_CHECK='TRUE';
      ALLOW_CONNECT='TRUE';
    'VSS_CH51':
      PIN_NUMBER='(0,0,0,0,0,0,0,0,0,0,0,0,0,0,0,0,0,0,0,0,0,0,0,0,0,0,0,0,0,0,0,0,0,0,0,0,0,CH51,0,0)';
      PINUSE='POWER';
      NO_LOAD_CHECK='Both';
      NO_IO_CHECK='Both';
      NO_ASSERT_CHECK='TRUE';
      NO_DIR_CHECK='TRUE';
      ALLOW_CONNECT='TRUE';
    'VSS_CH19':
      PIN_NUMBER='(0,0,0,0,0,0,0,0,0,0,0,0,0,0,0,0,0,0,0,0,0,0,0,0,0,0,0,0,0,0,0,0,0,0,0,0,0,CH19,0,0)';
      PINUSE='POWER';
      NO_LOAD_CHECK='Both';
      NO_IO_CHECK='Both';
      NO_ASSERT_CHECK='TRUE';
      NO_DIR_CHECK='TRUE';
      ALLOW_CONNECT='TRUE';
    'VSS_CF34':
      PIN_NUMBER='(0,0,0,0,0,0,0,0,0,0,0,0,0,0,0,0,0,0,0,0,0,0,0,0,0,0,0,0,0,0,0,0,0,0,0,0,0,CF34,0,0)';
      PINUSE='POWER';
      NO_LOAD_CHECK='Both';
      NO_IO_CHECK='Both';
      NO_ASSERT_CHECK='TRUE';
      NO_DIR_CHECK='TRUE';
      ALLOW_CONNECT='TRUE';
    'VSS_CF37':
      PIN_NUMBER='(0,0,0,0,0,0,0,0,0,0,0,0,0,0,0,0,0,0,0,0,0,0,0,0,0,0,0,0,0,0,0,0,0,0,0,0,0,CF37,0,0)';
      PINUSE='POWER';
      NO_LOAD_CHECK='Both';
      NO_IO_CHECK='Both';
      NO_ASSERT_CHECK='TRUE';
      NO_DIR_CHECK='TRUE';
      ALLOW_CONNECT='TRUE';
    'VSS_CF39':
      PIN_NUMBER='(0,0,0,0,0,0,0,0,0,0,0,0,0,0,0,0,0,0,0,0,0,0,0,0,0,0,0,0,0,0,0,0,0,0,0,0,0,CF39,0,0)';
      PINUSE='POWER';
      NO_LOAD_CHECK='Both';
      NO_IO_CHECK='Both';
      NO_ASSERT_CHECK='TRUE';
      NO_DIR_CHECK='TRUE';
      ALLOW_CONNECT='TRUE';
    'VSS_CF42':
      PIN_NUMBER='(0,0,0,0,0,0,0,0,0,0,0,0,0,0,0,0,0,0,0,0,0,0,0,0,0,0,0,0,0,0,0,0,0,0,0,0,0,CF42,0,0)';
      PINUSE='POWER';
      NO_LOAD_CHECK='Both';
      NO_IO_CHECK='Both';
      NO_ASSERT_CHECK='TRUE';
      NO_DIR_CHECK='TRUE';
      ALLOW_CONNECT='TRUE';
    'VSS_CF43':
      PIN_NUMBER='(0,0,0,0,0,0,0,0,0,0,0,0,0,0,0,0,0,0,0,0,0,0,0,0,0,0,0,0,0,0,0,0,0,0,0,0,0,CF43,0,0)';
      PINUSE='POWER';
      NO_LOAD_CHECK='Both';
      NO_IO_CHECK='Both';
      NO_ASSERT_CHECK='TRUE';
      NO_DIR_CHECK='TRUE';
      ALLOW_CONNECT='TRUE';
    'VSS_CF44':
      PIN_NUMBER='(0,0,0,0,0,0,0,0,0,0,0,0,0,0,0,0,0,0,0,0,0,0,0,0,0,0,0,0,0,0,0,0,0,0,0,0,0,CF44,0,0)';
      PINUSE='POWER';
      NO_LOAD_CHECK='Both';
      NO_IO_CHECK='Both';
      NO_ASSERT_CHECK='TRUE';
      NO_DIR_CHECK='TRUE';
      ALLOW_CONNECT='TRUE';
    'VSS_CF45':
      PIN_NUMBER='(0,0,0,0,0,0,0,0,0,0,0,0,0,0,0,0,0,0,0,0,0,0,0,0,0,0,0,0,0,0,0,0,0,0,0,0,0,CF45,0,0)';
      PINUSE='POWER';
      NO_LOAD_CHECK='Both';
      NO_IO_CHECK='Both';
      NO_ASSERT_CHECK='TRUE';
      NO_DIR_CHECK='TRUE';
      ALLOW_CONNECT='TRUE';
    'VSS_CF47':
      PIN_NUMBER='(0,0,0,0,0,0,0,0,0,0,0,0,0,0,0,0,0,0,0,0,0,0,0,0,0,0,0,0,0,0,0,0,0,0,0,0,0,CF47,0,0)';
      PINUSE='POWER';
      NO_LOAD_CHECK='Both';
      NO_IO_CHECK='Both';
      NO_ASSERT_CHECK='TRUE';
      NO_DIR_CHECK='TRUE';
      ALLOW_CONNECT='TRUE';
    'VSS_CF48':
      PIN_NUMBER='(0,0,0,0,0,0,0,0,0,0,0,0,0,0,0,0,0,0,0,0,0,0,0,0,0,0,0,0,0,0,0,0,0,0,0,0,0,CF48,0,0)';
      PINUSE='POWER';
      NO_LOAD_CHECK='Both';
      NO_IO_CHECK='Both';
      NO_ASSERT_CHECK='TRUE';
      NO_DIR_CHECK='TRUE';
      ALLOW_CONNECT='TRUE';
    'VSS_CF49':
      PIN_NUMBER='(0,0,0,0,0,0,0,0,0,0,0,0,0,0,0,0,0,0,0,0,0,0,0,0,0,0,0,0,0,0,0,0,0,0,0,0,0,CF49,0,0)';
      PINUSE='POWER';
      NO_LOAD_CHECK='Both';
      NO_IO_CHECK='Both';
      NO_ASSERT_CHECK='TRUE';
      NO_DIR_CHECK='TRUE';
      ALLOW_CONNECT='TRUE';
    'VSS_CF50':
      PIN_NUMBER='(0,0,0,0,0,0,0,0,0,0,0,0,0,0,0,0,0,0,0,0,0,0,0,0,0,0,0,0,0,0,0,0,0,0,0,0,0,CF50,0,0)';
      PINUSE='POWER';
      NO_LOAD_CHECK='Both';
      NO_IO_CHECK='Both';
      NO_ASSERT_CHECK='TRUE';
      NO_DIR_CHECK='TRUE';
      ALLOW_CONNECT='TRUE';
    'VSS_CF51':
      PIN_NUMBER='(0,0,0,0,0,0,0,0,0,0,0,0,0,0,0,0,0,0,0,0,0,0,0,0,0,0,0,0,0,0,0,0,0,0,0,0,0,CF51,0,0)';
      PINUSE='POWER';
      NO_LOAD_CHECK='Both';
      NO_IO_CHECK='Both';
      NO_ASSERT_CHECK='TRUE';
      NO_DIR_CHECK='TRUE';
      ALLOW_CONNECT='TRUE';
    'VSS_CF52':
      PIN_NUMBER='(0,0,0,0,0,0,0,0,0,0,0,0,0,0,0,0,0,0,0,0,0,0,0,0,0,0,0,0,0,0,0,0,0,0,0,0,0,CF52,0,0)';
      PINUSE='POWER';
      NO_LOAD_CHECK='Both';
      NO_IO_CHECK='Both';
      NO_ASSERT_CHECK='TRUE';
      NO_DIR_CHECK='TRUE';
      ALLOW_CONNECT='TRUE';
    'VSS_CF53':
      PIN_NUMBER='(0,0,0,0,0,0,0,0,0,0,0,0,0,0,0,0,0,0,0,0,0,0,0,0,0,0,0,0,0,0,0,0,0,0,0,0,0,CF53,0,0)';
      PINUSE='POWER';
      NO_LOAD_CHECK='Both';
      NO_IO_CHECK='Both';
      NO_ASSERT_CHECK='TRUE';
      NO_DIR_CHECK='TRUE';
      ALLOW_CONNECT='TRUE';
    'VSS_CF57':
      PIN_NUMBER='(0,0,0,0,0,0,0,0,0,0,0,0,0,0,0,0,0,0,0,0,0,0,0,0,0,0,0,0,0,0,0,0,0,0,0,0,0,CF57,0,0)';
      PINUSE='POWER';
      NO_LOAD_CHECK='Both';
      NO_IO_CHECK='Both';
      NO_ASSERT_CHECK='TRUE';
      NO_DIR_CHECK='TRUE';
      ALLOW_CONNECT='TRUE';
    'VSS_CF59':
      PIN_NUMBER='(0,0,0,0,0,0,0,0,0,0,0,0,0,0,0,0,0,0,0,0,0,0,0,0,0,0,0,0,0,0,0,0,0,0,0,0,0,CF59,0,0)';
      PINUSE='POWER';
      NO_LOAD_CHECK='Both';
      NO_IO_CHECK='Both';
      NO_ASSERT_CHECK='TRUE';
      NO_DIR_CHECK='TRUE';
      ALLOW_CONNECT='TRUE';
    'VSS_CF61':
      PIN_NUMBER='(0,0,0,0,0,0,0,0,0,0,0,0,0,0,0,0,0,0,0,0,0,0,0,0,0,0,0,0,0,0,0,0,0,0,0,0,0,CF61,0,0)';
      PINUSE='POWER';
      NO_LOAD_CHECK='Both';
      NO_IO_CHECK='Both';
      NO_ASSERT_CHECK='TRUE';
      NO_DIR_CHECK='TRUE';
      ALLOW_CONNECT='TRUE';
    'VSS_CF64':
      PIN_NUMBER='(0,0,0,0,0,0,0,0,0,0,0,0,0,0,0,0,0,0,0,0,0,0,0,0,0,0,0,0,0,0,0,0,0,0,0,0,0,CF64,0,0)';
      PINUSE='POWER';
      NO_LOAD_CHECK='Both';
      NO_IO_CHECK='Both';
      NO_ASSERT_CHECK='TRUE';
      NO_DIR_CHECK='TRUE';
      ALLOW_CONNECT='TRUE';
    'VSS_CF66':
      PIN_NUMBER='(0,0,0,0,0,0,0,0,0,0,0,0,0,0,0,0,0,0,0,0,0,0,0,0,0,0,0,0,0,0,0,0,0,0,0,0,0,CF66,0,0)';
      PINUSE='POWER';
      NO_LOAD_CHECK='Both';
      NO_IO_CHECK='Both';
      NO_ASSERT_CHECK='TRUE';
      NO_DIR_CHECK='TRUE';
      ALLOW_CONNECT='TRUE';
    'VSS_CF68':
      PIN_NUMBER='(0,0,0,0,0,0,0,0,0,0,0,0,0,0,0,0,0,0,0,0,0,0,0,0,0,0,0,0,0,0,0,0,0,0,0,0,0,CF68,0,0)';
      PINUSE='POWER';
      NO_LOAD_CHECK='Both';
      NO_IO_CHECK='Both';
      NO_ASSERT_CHECK='TRUE';
      NO_DIR_CHECK='TRUE';
      ALLOW_CONNECT='TRUE';
    'VSS_CF71':
      PIN_NUMBER='(0,0,0,0,0,0,0,0,0,0,0,0,0,0,0,0,0,0,0,0,0,0,0,0,0,0,0,0,0,0,0,0,0,0,0,0,0,CF71,0,0)';
      PINUSE='POWER';
      NO_LOAD_CHECK='Both';
      NO_IO_CHECK='Both';
      NO_ASSERT_CHECK='TRUE';
      NO_DIR_CHECK='TRUE';
      ALLOW_CONNECT='TRUE';
    'VSS_CF73':
      PIN_NUMBER='(0,0,0,0,0,0,0,0,0,0,0,0,0,0,0,0,0,0,0,0,0,0,0,0,0,0,0,0,0,0,0,0,0,0,0,0,0,CF73,0,0)';
      PINUSE='POWER';
      NO_LOAD_CHECK='Both';
      NO_IO_CHECK='Both';
      NO_ASSERT_CHECK='TRUE';
      NO_DIR_CHECK='TRUE';
      ALLOW_CONNECT='TRUE';
    'VSS_CG1':
      PIN_NUMBER='(0,0,0,0,0,0,0,0,0,0,0,0,0,0,0,0,0,0,0,0,0,0,0,0,0,0,0,0,0,0,0,0,0,0,0,0,0,CG1,0,0)';
      PINUSE='POWER';
      NO_LOAD_CHECK='Both';
      NO_IO_CHECK='Both';
      NO_ASSERT_CHECK='TRUE';
      NO_DIR_CHECK='TRUE';
      ALLOW_CONNECT='TRUE';
    'VSS_CG6':
      PIN_NUMBER='(0,0,0,0,0,0,0,0,0,0,0,0,0,0,0,0,0,0,0,0,0,0,0,0,0,0,0,0,0,0,0,0,0,0,0,0,0,CG6,0,0)';
      PINUSE='POWER';
      NO_LOAD_CHECK='Both';
      NO_IO_CHECK='Both';
      NO_ASSERT_CHECK='TRUE';
      NO_DIR_CHECK='TRUE';
      ALLOW_CONNECT='TRUE';
    'VSS_CG8':
      PIN_NUMBER='(0,0,0,0,0,0,0,0,0,0,0,0,0,0,0,0,0,0,0,0,0,0,0,0,0,0,0,0,0,0,0,0,0,0,0,0,0,CG8,0,0)';
      PINUSE='POWER';
      NO_LOAD_CHECK='Both';
      NO_IO_CHECK='Both';
      NO_ASSERT_CHECK='TRUE';
      NO_DIR_CHECK='TRUE';
      ALLOW_CONNECT='TRUE';
    'VSS_CG13':
      PIN_NUMBER='(0,0,0,0,0,0,0,0,0,0,0,0,0,0,0,0,0,0,0,0,0,0,0,0,0,0,0,0,0,0,0,0,0,0,0,0,0,CG13,0,0)';
      PINUSE='POWER';
      NO_LOAD_CHECK='Both';
      NO_IO_CHECK='Both';
      NO_ASSERT_CHECK='TRUE';
      NO_DIR_CHECK='TRUE';
      ALLOW_CONNECT='TRUE';
    'VSS_CG15':
      PIN_NUMBER='(0,0,0,0,0,0,0,0,0,0,0,0,0,0,0,0,0,0,0,0,0,0,0,0,0,0,0,0,0,0,0,0,0,0,0,0,0,CG15,0,0)';
      PINUSE='POWER';
      NO_LOAD_CHECK='Both';
      NO_IO_CHECK='Both';
      NO_ASSERT_CHECK='TRUE';
      NO_DIR_CHECK='TRUE';
      ALLOW_CONNECT='TRUE';
    'VSS_CG20':
      PIN_NUMBER='(0,0,0,0,0,0,0,0,0,0,0,0,0,0,0,0,0,0,0,0,0,0,0,0,0,0,0,0,0,0,0,0,0,0,0,0,0,CG20,0,0)';
      PINUSE='POWER';
      NO_LOAD_CHECK='Both';
      NO_IO_CHECK='Both';
      NO_ASSERT_CHECK='TRUE';
      NO_DIR_CHECK='TRUE';
      ALLOW_CONNECT='TRUE';
    'VSS_CG22':
      PIN_NUMBER='(0,0,0,0,0,0,0,0,0,0,0,0,0,0,0,0,0,0,0,0,0,0,0,0,0,0,0,0,0,0,0,0,0,0,0,0,0,CG22,0,0)';
      PINUSE='POWER';
      NO_LOAD_CHECK='Both';
      NO_IO_CHECK='Both';
      NO_ASSERT_CHECK='TRUE';
      NO_DIR_CHECK='TRUE';
      ALLOW_CONNECT='TRUE';
    'VSS_CG25':
      PIN_NUMBER='(0,0,0,0,0,0,0,0,0,0,0,0,0,0,0,0,0,0,0,0,0,0,0,0,0,0,0,0,0,0,0,0,0,0,0,0,0,CG25,0,0)';
      PINUSE='POWER';
      NO_LOAD_CHECK='Both';
      NO_IO_CHECK='Both';
      NO_ASSERT_CHECK='TRUE';
      NO_DIR_CHECK='TRUE';
      ALLOW_CONNECT='TRUE';
    'VSS_CG28':
      PIN_NUMBER='(0,0,0,0,0,0,0,0,0,0,0,0,0,0,0,0,0,0,0,0,0,0,0,0,0,0,0,0,0,0,0,0,0,0,0,0,0,CG28,0,0)';
      PINUSE='POWER';
      NO_LOAD_CHECK='Both';
      NO_IO_CHECK='Both';
      NO_ASSERT_CHECK='TRUE';
      NO_DIR_CHECK='TRUE';
      ALLOW_CONNECT='TRUE';
    'VSS_CG31':
      PIN_NUMBER='(0,0,0,0,0,0,0,0,0,0,0,0,0,0,0,0,0,0,0,0,0,0,0,0,0,0,0,0,0,0,0,0,0,0,0,0,0,CG31,0,0)';
      PINUSE='POWER';
      NO_LOAD_CHECK='Both';
      NO_IO_CHECK='Both';
      NO_ASSERT_CHECK='TRUE';
      NO_DIR_CHECK='TRUE';
      ALLOW_CONNECT='TRUE';
    'VSS_CG34':
      PIN_NUMBER='(0,0,0,0,0,0,0,0,0,0,0,0,0,0,0,0,0,0,0,0,0,0,0,0,0,0,0,0,0,0,0,0,0,0,0,0,0,CG34,0,0)';
      PINUSE='POWER';
      NO_LOAD_CHECK='Both';
      NO_IO_CHECK='Both';
      NO_ASSERT_CHECK='TRUE';
      NO_DIR_CHECK='TRUE';
      ALLOW_CONNECT='TRUE';
    'VSS_CG45':
      PIN_NUMBER='(0,0,0,0,0,0,0,0,0,0,0,0,0,0,0,0,0,0,0,0,0,0,0,0,0,0,0,0,0,0,0,0,0,0,0,0,0,CG45,0,0)';
      PINUSE='POWER';
      NO_LOAD_CHECK='Both';
      NO_IO_CHECK='Both';
      NO_ASSERT_CHECK='TRUE';
      NO_DIR_CHECK='TRUE';
      ALLOW_CONNECT='TRUE';
    'VSS_CG48':
      PIN_NUMBER='(0,0,0,0,0,0,0,0,0,0,0,0,0,0,0,0,0,0,0,0,0,0,0,0,0,0,0,0,0,0,0,0,0,0,0,0,0,CG48,0,0)';
      PINUSE='POWER';
      NO_LOAD_CHECK='Both';
      NO_IO_CHECK='Both';
      NO_ASSERT_CHECK='TRUE';
      NO_DIR_CHECK='TRUE';
      ALLOW_CONNECT='TRUE';
    'VSS_CG51':
      PIN_NUMBER='(0,0,0,0,0,0,0,0,0,0,0,0,0,0,0,0,0,0,0,0,0,0,0,0,0,0,0,0,0,0,0,0,0,0,0,0,0,CG51,0,0)';
      PINUSE='POWER';
      NO_LOAD_CHECK='Both';
      NO_IO_CHECK='Both';
      NO_ASSERT_CHECK='TRUE';
      NO_DIR_CHECK='TRUE';
      ALLOW_CONNECT='TRUE';
    'VSS_CG54':
      PIN_NUMBER='(0,0,0,0,0,0,0,0,0,0,0,0,0,0,0,0,0,0,0,0,0,0,0,0,0,0,0,0,0,0,0,0,0,0,0,0,0,CG54,0,0)';
      PINUSE='POWER';
      NO_LOAD_CHECK='Both';
      NO_IO_CHECK='Both';
      NO_ASSERT_CHECK='TRUE';
      NO_DIR_CHECK='TRUE';
      ALLOW_CONNECT='TRUE';
    'VSS_CG56':
      PIN_NUMBER='(0,0,0,0,0,0,0,0,0,0,0,0,0,0,0,0,0,0,0,0,0,0,0,0,0,0,0,0,0,0,0,0,0,0,0,0,0,CG56,0,0)';
      PINUSE='POWER';
      NO_LOAD_CHECK='Both';
      NO_IO_CHECK='Both';
      NO_ASSERT_CHECK='TRUE';
      NO_DIR_CHECK='TRUE';
      ALLOW_CONNECT='TRUE';
    'VSS_CG61':
      PIN_NUMBER='(0,0,0,0,0,0,0,0,0,0,0,0,0,0,0,0,0,0,0,0,0,0,0,0,0,0,0,0,0,0,0,0,0,0,0,0,0,CG61,0,0)';
      PINUSE='POWER';
      NO_LOAD_CHECK='Both';
      NO_IO_CHECK='Both';
      NO_ASSERT_CHECK='TRUE';
      NO_DIR_CHECK='TRUE';
      ALLOW_CONNECT='TRUE';
    'VSS_CG63':
      PIN_NUMBER='(0,0,0,0,0,0,0,0,0,0,0,0,0,0,0,0,0,0,0,0,0,0,0,0,0,0,0,0,0,0,0,0,0,0,0,0,0,CG63,0,0)';
      PINUSE='POWER';
      NO_LOAD_CHECK='Both';
      NO_IO_CHECK='Both';
      NO_ASSERT_CHECK='TRUE';
      NO_DIR_CHECK='TRUE';
      ALLOW_CONNECT='TRUE';
    'VSS_CG68':
      PIN_NUMBER='(0,0,0,0,0,0,0,0,0,0,0,0,0,0,0,0,0,0,0,0,0,0,0,0,0,0,0,0,0,0,0,0,0,0,0,0,0,CG68,0,0)';
      PINUSE='POWER';
      NO_LOAD_CHECK='Both';
      NO_IO_CHECK='Both';
      NO_ASSERT_CHECK='TRUE';
      NO_DIR_CHECK='TRUE';
      ALLOW_CONNECT='TRUE';
    'VSS_CG70':
      PIN_NUMBER='(0,0,0,0,0,0,0,0,0,0,0,0,0,0,0,0,0,0,0,0,0,0,0,0,0,0,0,0,0,0,0,0,0,0,0,0,0,CG70,0,0)';
      PINUSE='POWER';
      NO_LOAD_CHECK='Both';
      NO_IO_CHECK='Both';
      NO_ASSERT_CHECK='TRUE';
      NO_DIR_CHECK='TRUE';
      ALLOW_CONNECT='TRUE';
    'VSS_CG75':
      PIN_NUMBER='(0,0,0,0,0,0,0,0,0,0,0,0,0,0,0,0,0,0,0,0,0,0,0,0,0,0,0,0,0,0,0,0,0,0,0,0,0,CG75,0,0)';
      PINUSE='POWER';
      NO_LOAD_CHECK='Both';
      NO_IO_CHECK='Both';
      NO_ASSERT_CHECK='TRUE';
      NO_DIR_CHECK='TRUE';
      ALLOW_CONNECT='TRUE';
    'VSS_CH3':
      PIN_NUMBER='(0,0,0,0,0,0,0,0,0,0,0,0,0,0,0,0,0,0,0,0,0,0,0,0,0,0,0,0,0,0,0,0,0,0,0,0,0,CH3,0,0)';
      PINUSE='POWER';
      NO_LOAD_CHECK='Both';
      NO_IO_CHECK='Both';
      NO_ASSERT_CHECK='TRUE';
      NO_DIR_CHECK='TRUE';
      ALLOW_CONNECT='TRUE';
    'VSS_CH5':
      PIN_NUMBER='(0,0,0,0,0,0,0,0,0,0,0,0,0,0,0,0,0,0,0,0,0,0,0,0,0,0,0,0,0,0,0,0,0,0,0,0,0,CH5,0,0)';
      PINUSE='POWER';
      NO_LOAD_CHECK='Both';
      NO_IO_CHECK='Both';
      NO_ASSERT_CHECK='TRUE';
      NO_DIR_CHECK='TRUE';
      ALLOW_CONNECT='TRUE';
    'VSS_CH8':
      PIN_NUMBER='(0,0,0,0,0,0,0,0,0,0,0,0,0,0,0,0,0,0,0,0,0,0,0,0,0,0,0,0,0,0,0,0,0,0,0,0,0,CH8,0,0)';
      PINUSE='POWER';
      NO_LOAD_CHECK='Both';
      NO_IO_CHECK='Both';
      NO_ASSERT_CHECK='TRUE';
      NO_DIR_CHECK='TRUE';
      ALLOW_CONNECT='TRUE';
    'VSS_CH22':
      PIN_NUMBER='(0,0,0,0,0,0,0,0,0,0,0,0,0,0,0,0,0,0,0,0,0,0,0,0,0,0,0,0,0,0,0,0,0,0,0,0,0,CH22,0,0)';
      PINUSE='POWER';
      NO_LOAD_CHECK='Both';
      NO_IO_CHECK='Both';
      NO_ASSERT_CHECK='TRUE';
      NO_DIR_CHECK='TRUE';
      ALLOW_CONNECT='TRUE';
    'VSS_CH25':
      PIN_NUMBER='(0,0,0,0,0,0,0,0,0,0,0,0,0,0,0,0,0,0,0,0,0,0,0,0,0,0,0,0,0,0,0,0,0,0,0,0,0,CH25,0,0)';
      PINUSE='POWER';
      NO_LOAD_CHECK='Both';
      NO_IO_CHECK='Both';
      NO_ASSERT_CHECK='TRUE';
      NO_DIR_CHECK='TRUE';
      ALLOW_CONNECT='TRUE';
    'VSS_CH28':
      PIN_NUMBER='(0,0,0,0,0,0,0,0,0,0,0,0,0,0,0,0,0,0,0,0,0,0,0,0,0,0,0,0,0,0,0,0,0,0,0,0,0,CH28,0,0)';
      PINUSE='POWER';
      NO_LOAD_CHECK='Both';
      NO_IO_CHECK='Both';
      NO_ASSERT_CHECK='TRUE';
      NO_DIR_CHECK='TRUE';
      ALLOW_CONNECT='TRUE';
    'VSS_CH31':
      PIN_NUMBER='(0,0,0,0,0,0,0,0,0,0,0,0,0,0,0,0,0,0,0,0,0,0,0,0,0,0,0,0,0,0,0,0,0,0,0,0,0,CH31,0,0)';
      PINUSE='POWER';
      NO_LOAD_CHECK='Both';
      NO_IO_CHECK='Both';
      NO_ASSERT_CHECK='TRUE';
      NO_DIR_CHECK='TRUE';
      ALLOW_CONNECT='TRUE';
    'VSS_CH34':
      PIN_NUMBER='(0,0,0,0,0,0,0,0,0,0,0,0,0,0,0,0,0,0,0,0,0,0,0,0,0,0,0,0,0,0,0,0,0,0,0,0,0,CH34,0,0)';
      PINUSE='POWER';
      NO_LOAD_CHECK='Both';
      NO_IO_CHECK='Both';
      NO_ASSERT_CHECK='TRUE';
      NO_DIR_CHECK='TRUE';
      ALLOW_CONNECT='TRUE';
    'VSS_CH37':
      PIN_NUMBER='(0,0,0,0,0,0,0,0,0,0,0,0,0,0,0,0,0,0,0,0,0,0,0,0,0,0,0,0,0,0,0,0,0,0,0,0,0,CH37,0,0)';
      PINUSE='POWER';
      NO_LOAD_CHECK='Both';
      NO_IO_CHECK='Both';
      NO_ASSERT_CHECK='TRUE';
      NO_DIR_CHECK='TRUE';
      ALLOW_CONNECT='TRUE';
    'VSS_CH54':
      PIN_NUMBER='(0,0,0,0,0,0,0,0,0,0,0,0,0,0,0,0,0,0,0,0,0,0,0,0,0,0,0,0,0,0,0,0,0,0,0,0,0,CH54,0,0)';
      PINUSE='POWER';
      NO_LOAD_CHECK='Both';
      NO_IO_CHECK='Both';
      NO_ASSERT_CHECK='TRUE';
      NO_DIR_CHECK='TRUE';
      ALLOW_CONNECT='TRUE';
    'VSS_CH57':
      PIN_NUMBER='(0,0,0,0,0,0,0,0,0,0,0,0,0,0,0,0,0,0,0,0,0,0,0,0,0,0,0,0,0,0,0,0,0,0,0,0,0,CH57,0,0)';
      PINUSE='POWER';
      NO_LOAD_CHECK='Both';
      NO_IO_CHECK='Both';
      NO_ASSERT_CHECK='TRUE';
      NO_DIR_CHECK='TRUE';
      ALLOW_CONNECT='TRUE';
    'VSS_CH59':
      PIN_NUMBER='(0,0,0,0,0,0,0,0,0,0,0,0,0,0,0,0,0,0,0,0,0,0,0,0,0,0,0,0,0,0,0,0,0,0,0,0,0,CH59,0,0)';
      PINUSE='POWER';
      NO_LOAD_CHECK='Both';
      NO_IO_CHECK='Both';
      NO_ASSERT_CHECK='TRUE';
      NO_DIR_CHECK='TRUE';
      ALLOW_CONNECT='TRUE';
    'VSS_CH61':
      PIN_NUMBER='(0,0,0,0,0,0,0,0,0,0,0,0,0,0,0,0,0,0,0,0,0,0,0,0,0,0,0,0,0,0,0,0,0,0,0,0,0,CH61,0,0)';
      PINUSE='POWER';
      NO_LOAD_CHECK='Both';
      NO_IO_CHECK='Both';
      NO_ASSERT_CHECK='TRUE';
      NO_DIR_CHECK='TRUE';
      ALLOW_CONNECT='TRUE';
    'VSS_CH64':
      PIN_NUMBER='(0,0,0,0,0,0,0,0,0,0,0,0,0,0,0,0,0,0,0,0,0,0,0,0,0,0,0,0,0,0,0,0,0,0,0,0,0,CH64,0,0)';
      PINUSE='POWER';
      NO_LOAD_CHECK='Both';
      NO_IO_CHECK='Both';
      NO_ASSERT_CHECK='TRUE';
      NO_DIR_CHECK='TRUE';
      ALLOW_CONNECT='TRUE';
    'VSS_CH66':
      PIN_NUMBER='(0,0,0,0,0,0,0,0,0,0,0,0,0,0,0,0,0,0,0,0,0,0,0,0,0,0,0,0,0,0,0,0,0,0,0,0,0,CH66,0,0)';
      PINUSE='POWER';
      NO_LOAD_CHECK='Both';
      NO_IO_CHECK='Both';
      NO_ASSERT_CHECK='TRUE';
      NO_DIR_CHECK='TRUE';
      ALLOW_CONNECT='TRUE';
    'VSS_CJ6':
      PIN_NUMBER='(0,0,0,0,0,0,0,0,0,0,0,0,0,0,0,0,0,0,0,0,0,0,0,0,0,0,0,0,0,0,0,0,0,0,0,0,0,CJ6,0,0)';
      PINUSE='POWER';
      NO_LOAD_CHECK='Both';
      NO_IO_CHECK='Both';
      NO_ASSERT_CHECK='TRUE';
      NO_DIR_CHECK='TRUE';
      ALLOW_CONNECT='TRUE';
    'VSS_CJ8':
      PIN_NUMBER='(0,0,0,0,0,0,0,0,0,0,0,0,0,0,0,0,0,0,0,0,0,0,0,0,0,0,0,0,0,0,0,0,0,0,0,0,0,CJ8,0,0)';
      PINUSE='POWER';
      NO_LOAD_CHECK='Both';
      NO_IO_CHECK='Both';
      NO_ASSERT_CHECK='TRUE';
      NO_DIR_CHECK='TRUE';
      ALLOW_CONNECT='TRUE';
    'VSS_CJ11':
      PIN_NUMBER='(0,0,0,0,0,0,0,0,0,0,0,0,0,0,0,0,0,0,0,0,0,0,0,0,0,0,0,0,0,0,0,0,0,0,0,0,0,CJ11,0,0)';
      PINUSE='POWER';
      NO_LOAD_CHECK='Both';
      NO_IO_CHECK='Both';
      NO_ASSERT_CHECK='TRUE';
      NO_DIR_CHECK='TRUE';
      ALLOW_CONNECT='TRUE';
    'VSS_CJ13':
      PIN_NUMBER='(0,0,0,0,0,0,0,0,0,0,0,0,0,0,0,0,0,0,0,0,0,0,0,0,0,0,0,0,0,0,0,0,0,0,0,0,0,CJ13,0,0)';
      PINUSE='POWER';
      NO_LOAD_CHECK='Both';
      NO_IO_CHECK='Both';
      NO_ASSERT_CHECK='TRUE';
      NO_DIR_CHECK='TRUE';
      ALLOW_CONNECT='TRUE';
    'VSS_CJ15':
      PIN_NUMBER='(0,0,0,0,0,0,0,0,0,0,0,0,0,0,0,0,0,0,0,0,0,0,0,0,0,0,0,0,0,0,0,0,0,0,0,0,0,CJ15,0,0)';
      PINUSE='POWER';
      NO_LOAD_CHECK='Both';
      NO_IO_CHECK='Both';
      NO_ASSERT_CHECK='TRUE';
      NO_DIR_CHECK='TRUE';
      ALLOW_CONNECT='TRUE';
    'VSS_CJ18':
      PIN_NUMBER='(0,0,0,0,0,0,0,0,0,0,0,0,0,0,0,0,0,0,0,0,0,0,0,0,0,0,0,0,0,0,0,0,0,0,0,0,0,CJ18,0,0)';
      PINUSE='POWER';
      NO_LOAD_CHECK='Both';
      NO_IO_CHECK='Both';
      NO_ASSERT_CHECK='TRUE';
      NO_DIR_CHECK='TRUE';
      ALLOW_CONNECT='TRUE';
    'VSS_CJ35':
      PIN_NUMBER='(0,0,0,0,0,0,0,0,0,0,0,0,0,0,0,0,0,0,0,0,0,0,0,0,0,0,0,0,0,0,0,0,0,0,0,0,0,CJ35,0,0)';
      PINUSE='POWER';
      NO_LOAD_CHECK='Both';
      NO_IO_CHECK='Both';
      NO_ASSERT_CHECK='TRUE';
      NO_DIR_CHECK='TRUE';
      ALLOW_CONNECT='TRUE';
    'VSS_CJ36':
      PIN_NUMBER='(0,0,0,0,0,0,0,0,0,0,0,0,0,0,0,0,0,0,0,0,0,0,0,0,0,0,0,0,0,0,0,0,0,0,0,0,0,CJ36,0,0)';
      PINUSE='POWER';
      NO_LOAD_CHECK='Both';
      NO_IO_CHECK='Both';
      NO_ASSERT_CHECK='TRUE';
      NO_DIR_CHECK='TRUE';
      ALLOW_CONNECT='TRUE';
    'VSS_CJ40':
      PIN_NUMBER='(0,0,0,0,0,0,0,0,0,0,0,0,0,0,0,0,0,0,0,0,0,0,0,0,0,0,0,0,0,0,0,0,0,0,0,0,0,CJ40,0,0)';
      PINUSE='POWER';
      NO_LOAD_CHECK='Both';
      NO_IO_CHECK='Both';
      NO_ASSERT_CHECK='TRUE';
      NO_DIR_CHECK='TRUE';
      ALLOW_CONNECT='TRUE';
    'VSS_CJ41':
      PIN_NUMBER='(0,0,0,0,0,0,0,0,0,0,0,0,0,0,0,0,0,0,0,0,0,0,0,0,0,0,0,0,0,0,0,0,0,0,0,0,0,CJ41,0,0)';
      PINUSE='POWER';
      NO_LOAD_CHECK='Both';
      NO_IO_CHECK='Both';
      NO_ASSERT_CHECK='TRUE';
      NO_DIR_CHECK='TRUE';
      ALLOW_CONNECT='TRUE';
    'VSS_CJ42':
      PIN_NUMBER='(0,0,0,0,0,0,0,0,0,0,0,0,0,0,0,0,0,0,0,0,0,0,0,0,0,0,0,0,0,0,0,0,0,0,0,0,0,CJ42,0,0)';
      PINUSE='POWER';
      NO_LOAD_CHECK='Both';
      NO_IO_CHECK='Both';
      NO_ASSERT_CHECK='TRUE';
      NO_DIR_CHECK='TRUE';
      ALLOW_CONNECT='TRUE';
    'VSS_CJ45':
      PIN_NUMBER='(0,0,0,0,0,0,0,0,0,0,0,0,0,0,0,0,0,0,0,0,0,0,0,0,0,0,0,0,0,0,0,0,0,0,0,0,0,CJ45,0,0)';
      PINUSE='POWER';
      NO_LOAD_CHECK='Both';
      NO_IO_CHECK='Both';
      NO_ASSERT_CHECK='TRUE';
      NO_DIR_CHECK='TRUE';
      ALLOW_CONNECT='TRUE';
    'VSS_CJ56':
      PIN_NUMBER='(0,0,0,0,0,0,0,0,0,0,0,0,0,0,0,0,0,0,0,0,0,0,0,0,0,0,0,0,0,0,0,0,0,0,0,0,0,CJ56,0,0)';
      PINUSE='POWER';
      NO_LOAD_CHECK='Both';
      NO_IO_CHECK='Both';
      NO_ASSERT_CHECK='TRUE';
      NO_DIR_CHECK='TRUE';
      ALLOW_CONNECT='TRUE';
    'VSS_CJ65':
      PIN_NUMBER='(0,0,0,0,0,0,0,0,0,0,0,0,0,0,0,0,0,0,0,0,0,0,0,0,0,0,0,0,0,0,0,0,0,0,0,0,0,CJ65,0,0)';
      PINUSE='POWER';
      NO_LOAD_CHECK='Both';
      NO_IO_CHECK='Both';
      NO_ASSERT_CHECK='TRUE';
      NO_DIR_CHECK='TRUE';
      ALLOW_CONNECT='TRUE';
    'VSS_CJ68':
      PIN_NUMBER='(0,0,0,0,0,0,0,0,0,0,0,0,0,0,0,0,0,0,0,0,0,0,0,0,0,0,0,0,0,0,0,0,0,0,0,0,0,CJ68,0,0)';
      PINUSE='POWER';
      NO_LOAD_CHECK='Both';
      NO_IO_CHECK='Both';
      NO_ASSERT_CHECK='TRUE';
      NO_DIR_CHECK='TRUE';
      ALLOW_CONNECT='TRUE';
    'VSS_CJ70':
      PIN_NUMBER='(0,0,0,0,0,0,0,0,0,0,0,0,0,0,0,0,0,0,0,0,0,0,0,0,0,0,0,0,0,0,0,0,0,0,0,0,0,CJ70,0,0)';
      PINUSE='POWER';
      NO_LOAD_CHECK='Both';
      NO_IO_CHECK='Both';
      NO_ASSERT_CHECK='TRUE';
      NO_DIR_CHECK='TRUE';
      ALLOW_CONNECT='TRUE';
    'VSS_CJ72':
      PIN_NUMBER='(0,0,0,0,0,0,0,0,0,0,0,0,0,0,0,0,0,0,0,0,0,0,0,0,0,0,0,0,0,0,0,0,0,0,0,0,0,CJ72,0,0)';
      PINUSE='POWER';
      NO_LOAD_CHECK='Both';
      NO_IO_CHECK='Both';
      NO_ASSERT_CHECK='TRUE';
      NO_DIR_CHECK='TRUE';
      ALLOW_CONNECT='TRUE';
    'VSS_CJ75':
      PIN_NUMBER='(0,0,0,0,0,0,0,0,0,0,0,0,0,0,0,0,0,0,0,0,0,0,0,0,0,0,0,0,0,0,0,0,0,0,0,0,0,CJ75,0,0)';
      PINUSE='POWER';
      NO_LOAD_CHECK='Both';
      NO_IO_CHECK='Both';
      NO_ASSERT_CHECK='TRUE';
      NO_DIR_CHECK='TRUE';
      ALLOW_CONNECT='TRUE';
    'VSS_CK3':
      PIN_NUMBER='(0,0,0,0,0,0,0,0,0,0,0,0,0,0,0,0,0,0,0,0,0,0,0,0,0,0,0,0,0,0,0,0,0,0,0,0,0,CK3,0,0)';
      PINUSE='POWER';
      NO_LOAD_CHECK='Both';
      NO_IO_CHECK='Both';
      NO_ASSERT_CHECK='TRUE';
      NO_DIR_CHECK='TRUE';
      ALLOW_CONNECT='TRUE';
    'VSS_CK8':
      PIN_NUMBER='(0,0,0,0,0,0,0,0,0,0,0,0,0,0,0,0,0,0,0,0,0,0,0,0,0,0,0,0,0,0,0,0,0,0,0,0,0,CK8,0,0)';
      PINUSE='POWER';
      NO_LOAD_CHECK='Both';
      NO_IO_CHECK='Both';
      NO_ASSERT_CHECK='TRUE';
      NO_DIR_CHECK='TRUE';
      ALLOW_CONNECT='TRUE';
    'VSS_CK22':
      PIN_NUMBER='(0,0,0,0,0,0,0,0,0,0,0,0,0,0,0,0,0,0,0,0,0,0,0,0,0,0,0,0,0,0,0,0,0,0,0,0,0,CK22,0,0)';
      PINUSE='POWER';
      NO_LOAD_CHECK='Both';
      NO_IO_CHECK='Both';
      NO_ASSERT_CHECK='TRUE';
      NO_DIR_CHECK='TRUE';
      ALLOW_CONNECT='TRUE';
    'VSS_CK23':
      PIN_NUMBER='(0,0,0,0,0,0,0,0,0,0,0,0,0,0,0,0,0,0,0,0,0,0,0,0,0,0,0,0,0,0,0,0,0,0,0,0,0,CK23,0,0)';
      PINUSE='POWER';
      NO_LOAD_CHECK='Both';
      NO_IO_CHECK='Both';
      NO_ASSERT_CHECK='TRUE';
      NO_DIR_CHECK='TRUE';
      ALLOW_CONNECT='TRUE';
    'VSS_CK24':
      PIN_NUMBER='(0,0,0,0,0,0,0,0,0,0,0,0,0,0,0,0,0,0,0,0,0,0,0,0,0,0,0,0,0,0,0,0,0,0,0,0,0,CK24,0,0)';
      PINUSE='POWER';
      NO_LOAD_CHECK='Both';
      NO_IO_CHECK='Both';
      NO_ASSERT_CHECK='TRUE';
      NO_DIR_CHECK='TRUE';
      ALLOW_CONNECT='TRUE';
    'VSS_CK25':
      PIN_NUMBER='(0,0,0,0,0,0,0,0,0,0,0,0,0,0,0,0,0,0,0,0,0,0,0,0,0,0,0,0,0,0,0,0,0,0,0,0,0,CK25,0,0)';
      PINUSE='POWER';
      NO_LOAD_CHECK='Both';
      NO_IO_CHECK='Both';
      NO_ASSERT_CHECK='TRUE';
      NO_DIR_CHECK='TRUE';
      ALLOW_CONNECT='TRUE';
    'VSS_CK26':
      PIN_NUMBER='(0,0,0,0,0,0,0,0,0,0,0,0,0,0,0,0,0,0,0,0,0,0,0,0,0,0,0,0,0,0,0,0,0,0,0,0,0,CK26,0,0)';
      PINUSE='POWER';
      NO_LOAD_CHECK='Both';
      NO_IO_CHECK='Both';
      NO_ASSERT_CHECK='TRUE';
      NO_DIR_CHECK='TRUE';
      ALLOW_CONNECT='TRUE';
    'VSS_CK27':
      PIN_NUMBER='(0,0,0,0,0,0,0,0,0,0,0,0,0,0,0,0,0,0,0,0,0,0,0,0,0,0,0,0,0,0,0,0,0,0,0,0,0,CK27,0,0)';
      PINUSE='POWER';
      NO_LOAD_CHECK='Both';
      NO_IO_CHECK='Both';
      NO_ASSERT_CHECK='TRUE';
      NO_DIR_CHECK='TRUE';
      ALLOW_CONNECT='TRUE';
    'VSS_CK28':
      PIN_NUMBER='(0,0,0,0,0,0,0,0,0,0,0,0,0,0,0,0,0,0,0,0,0,0,0,0,0,0,0,0,0,0,0,0,0,0,0,0,0,CK28,0,0)';
      PINUSE='POWER';
      NO_LOAD_CHECK='Both';
      NO_IO_CHECK='Both';
      NO_ASSERT_CHECK='TRUE';
      NO_DIR_CHECK='TRUE';
      ALLOW_CONNECT='TRUE';
    'VSS_CK32':
      PIN_NUMBER='(0,0,0,0,0,0,0,0,0,0,0,0,0,0,0,0,0,0,0,0,0,0,0,0,0,0,0,0,0,0,0,0,0,0,0,0,0,CK32,0,0)';
      PINUSE='POWER';
      NO_LOAD_CHECK='Both';
      NO_IO_CHECK='Both';
      NO_ASSERT_CHECK='TRUE';
      NO_DIR_CHECK='TRUE';
      ALLOW_CONNECT='TRUE';
    'VSS_CK34':
      PIN_NUMBER='(0,0,0,0,0,0,0,0,0,0,0,0,0,0,0,0,0,0,0,0,0,0,0,0,0,0,0,0,0,0,0,0,0,0,0,0,0,CK34,0,0)';
      PINUSE='POWER';
      NO_LOAD_CHECK='Both';
      NO_IO_CHECK='Both';
      NO_ASSERT_CHECK='TRUE';
      NO_DIR_CHECK='TRUE';
      ALLOW_CONNECT='TRUE';
    'VSS_CK37':
      PIN_NUMBER='(0,0,0,0,0,0,0,0,0,0,0,0,0,0,0,0,0,0,0,0,0,0,0,0,0,0,0,0,0,0,0,0,0,0,0,0,0,CK37,0,0)';
      PINUSE='POWER';
      NO_LOAD_CHECK='Both';
      NO_IO_CHECK='Both';
      NO_ASSERT_CHECK='TRUE';
      NO_DIR_CHECK='TRUE';
      ALLOW_CONNECT='TRUE';
    'VSS_CK39':
      PIN_NUMBER='(0,0,0,0,0,0,0,0,0,0,0,0,0,0,0,0,0,0,0,0,0,0,0,0,0,0,0,0,0,0,0,0,0,0,0,0,0,CK39,0,0)';
      PINUSE='POWER';
      NO_LOAD_CHECK='Both';
      NO_IO_CHECK='Both';
      NO_ASSERT_CHECK='TRUE';
      NO_DIR_CHECK='TRUE';
      ALLOW_CONNECT='TRUE';
    'VSS_CK42':
      PIN_NUMBER='(0,0,0,0,0,0,0,0,0,0,0,0,0,0,0,0,0,0,0,0,0,0,0,0,0,0,0,0,0,0,0,0,0,0,0,0,0,CK42,0,0)';
      PINUSE='POWER';
      NO_LOAD_CHECK='Both';
      NO_IO_CHECK='Both';
      NO_ASSERT_CHECK='TRUE';
      NO_DIR_CHECK='TRUE';
      ALLOW_CONNECT='TRUE';
    'VSS_CK43':
      PIN_NUMBER='(0,0,0,0,0,0,0,0,0,0,0,0,0,0,0,0,0,0,0,0,0,0,0,0,0,0,0,0,0,0,0,0,0,0,0,0,0,CK43,0,0)';
      PINUSE='POWER';
      NO_LOAD_CHECK='Both';
      NO_IO_CHECK='Both';
      NO_ASSERT_CHECK='TRUE';
      NO_DIR_CHECK='TRUE';
      ALLOW_CONNECT='TRUE';
    'VSS_CK44':
      PIN_NUMBER='(0,0,0,0,0,0,0,0,0,0,0,0,0,0,0,0,0,0,0,0,0,0,0,0,0,0,0,0,0,0,0,0,0,0,0,0,0,CK44,0,0)';
      PINUSE='POWER';
      NO_LOAD_CHECK='Both';
      NO_IO_CHECK='Both';
      NO_ASSERT_CHECK='TRUE';
      NO_DIR_CHECK='TRUE';
      ALLOW_CONNECT='TRUE';
    'VSS_CK45':
      PIN_NUMBER='(0,0,0,0,0,0,0,0,0,0,0,0,0,0,0,0,0,0,0,0,0,0,0,0,0,0,0,0,0,0,0,0,0,0,0,0,0,CK45,0,0)';
      PINUSE='POWER';
      NO_LOAD_CHECK='Both';
      NO_IO_CHECK='Both';
      NO_ASSERT_CHECK='TRUE';
      NO_DIR_CHECK='TRUE';
      ALLOW_CONNECT='TRUE';
    'VSS_CK48':
      PIN_NUMBER='(0,0,0,0,0,0,0,0,0,0,0,0,0,0,0,0,0,0,0,0,0,0,0,0,0,0,0,0,0,0,0,0,0,0,0,0,0,CK48,0,0)';
      PINUSE='POWER';
      NO_LOAD_CHECK='Both';
      NO_IO_CHECK='Both';
      NO_ASSERT_CHECK='TRUE';
      NO_DIR_CHECK='TRUE';
      ALLOW_CONNECT='TRUE';
    'VSS_CK49':
      PIN_NUMBER='(0,0,0,0,0,0,0,0,0,0,0,0,0,0,0,0,0,0,0,0,0,0,0,0,0,0,0,0,0,0,0,0,0,0,0,0,0,CK49,0,0)';
      PINUSE='POWER';
      NO_LOAD_CHECK='Both';
      NO_IO_CHECK='Both';
      NO_ASSERT_CHECK='TRUE';
      NO_DIR_CHECK='TRUE';
      ALLOW_CONNECT='TRUE';
    'VSS_CK50':
      PIN_NUMBER='(0,0,0,0,0,0,0,0,0,0,0,0,0,0,0,0,0,0,0,0,0,0,0,0,0,0,0,0,0,0,0,0,0,0,0,0,0,CK50,0,0)';
      PINUSE='POWER';
      NO_LOAD_CHECK='Both';
      NO_IO_CHECK='Both';
      NO_ASSERT_CHECK='TRUE';
      NO_DIR_CHECK='TRUE';
      ALLOW_CONNECT='TRUE';
    'VSS_CK51':
      PIN_NUMBER='(0,0,0,0,0,0,0,0,0,0,0,0,0,0,0,0,0,0,0,0,0,0,0,0,0,0,0,0,0,0,0,0,0,0,0,0,0,CK51,0,0)';
      PINUSE='POWER';
      NO_LOAD_CHECK='Both';
      NO_IO_CHECK='Both';
      NO_ASSERT_CHECK='TRUE';
      NO_DIR_CHECK='TRUE';
      ALLOW_CONNECT='TRUE';
    'VSS_CK52':
      PIN_NUMBER='(0,0,0,0,0,0,0,0,0,0,0,0,0,0,0,0,0,0,0,0,0,0,0,0,0,0,0,0,0,0,0,0,0,0,0,0,0,CK52,0,0)';
      PINUSE='POWER';
      NO_LOAD_CHECK='Both';
      NO_IO_CHECK='Both';
      NO_ASSERT_CHECK='TRUE';
      NO_DIR_CHECK='TRUE';
      ALLOW_CONNECT='TRUE';
    'VSS_CK53':
      PIN_NUMBER='(0,0,0,0,0,0,0,0,0,0,0,0,0,0,0,0,0,0,0,0,0,0,0,0,0,0,0,0,0,0,0,0,0,0,0,0,0,CK53,0,0)';
      PINUSE='POWER';
      NO_LOAD_CHECK='Both';
      NO_IO_CHECK='Both';
      NO_ASSERT_CHECK='TRUE';
      NO_DIR_CHECK='TRUE';
      ALLOW_CONNECT='TRUE';
    'VSS_CK54':
      PIN_NUMBER='(0,0,0,0,0,0,0,0,0,0,0,0,0,0,0,0,0,0,0,0,0,0,0,0,0,0,0,0,0,0,0,0,0,0,0,0,0,CK54,0,0)';
      PINUSE='POWER';
      NO_LOAD_CHECK='Both';
      NO_IO_CHECK='Both';
      NO_ASSERT_CHECK='TRUE';
      NO_DIR_CHECK='TRUE';
      ALLOW_CONNECT='TRUE';
    'VSS_CK59':
      PIN_NUMBER='(0,0,0,0,0,0,0,0,0,0,0,0,0,0,0,0,0,0,0,0,0,0,0,0,0,0,0,0,0,0,0,0,0,0,0,0,0,CK59,0,0)';
      PINUSE='POWER';
      NO_LOAD_CHECK='Both';
      NO_IO_CHECK='Both';
      NO_ASSERT_CHECK='TRUE';
      NO_DIR_CHECK='TRUE';
      ALLOW_CONNECT='TRUE';
    'VSS_CK61':
      PIN_NUMBER='(0,0,0,0,0,0,0,0,0,0,0,0,0,0,0,0,0,0,0,0,0,0,0,0,0,0,0,0,0,0,0,0,0,0,0,0,0,CK61,0,0)';
      PINUSE='POWER';
      NO_LOAD_CHECK='Both';
      NO_IO_CHECK='Both';
      NO_ASSERT_CHECK='TRUE';
      NO_DIR_CHECK='TRUE';
      ALLOW_CONNECT='TRUE';
    'VSS_CK66':
      PIN_NUMBER='(0,0,0,0,0,0,0,0,0,0,0,0,0,0,0,0,0,0,0,0,0,0,0,0,0,0,0,0,0,0,0,0,0,0,0,0,0,CK66,0,0)';
      PINUSE='POWER';
      NO_LOAD_CHECK='Both';
      NO_IO_CHECK='Both';
      NO_ASSERT_CHECK='TRUE';
      NO_DIR_CHECK='TRUE';
      ALLOW_CONNECT='TRUE';
    'VSS_CK68':
      PIN_NUMBER='(0,0,0,0,0,0,0,0,0,0,0,0,0,0,0,0,0,0,0,0,0,0,0,0,0,0,0,0,0,0,0,0,0,0,0,0,0,CK68,0,0)';
      PINUSE='POWER';
      NO_LOAD_CHECK='Both';
      NO_IO_CHECK='Both';
      NO_ASSERT_CHECK='TRUE';
      NO_DIR_CHECK='TRUE';
      ALLOW_CONNECT='TRUE';
    'VSS_CK73':
      PIN_NUMBER='(0,0,0,0,0,0,0,0,0,0,0,0,0,0,0,0,0,0,0,0,0,0,0,0,0,0,0,0,0,0,0,0,0,0,0,0,0,CK73,0,0)';
      PINUSE='POWER';
      NO_LOAD_CHECK='Both';
      NO_IO_CHECK='Both';
      NO_ASSERT_CHECK='TRUE';
      NO_DIR_CHECK='TRUE';
      ALLOW_CONNECT='TRUE';
    'VSS_CL1':
      PIN_NUMBER='(0,0,0,0,0,0,0,0,0,0,0,0,0,0,0,0,0,0,0,0,0,0,0,0,0,0,0,0,0,0,0,0,0,0,0,0,0,CL1,0,0)';
      PINUSE='POWER';
      NO_LOAD_CHECK='Both';
      NO_IO_CHECK='Both';
      NO_ASSERT_CHECK='TRUE';
      NO_DIR_CHECK='TRUE';
      ALLOW_CONNECT='TRUE';
    'VSS_CL4':
      PIN_NUMBER='(0,0,0,0,0,0,0,0,0,0,0,0,0,0,0,0,0,0,0,0,0,0,0,0,0,0,0,0,0,0,0,0,0,0,0,0,0,CL4,0,0)';
      PINUSE='POWER';
      NO_LOAD_CHECK='Both';
      NO_IO_CHECK='Both';
      NO_ASSERT_CHECK='TRUE';
      NO_DIR_CHECK='TRUE';
      ALLOW_CONNECT='TRUE';
    'VSS_CL6':
      PIN_NUMBER='(0,0,0,0,0,0,0,0,0,0,0,0,0,0,0,0,0,0,0,0,0,0,0,0,0,0,0,0,0,0,0,0,0,0,0,0,0,CL6,0,0)';
      PINUSE='POWER';
      NO_LOAD_CHECK='Both';
      NO_IO_CHECK='Both';
      NO_ASSERT_CHECK='TRUE';
      NO_DIR_CHECK='TRUE';
      ALLOW_CONNECT='TRUE';
    'VSS_CL8':
      PIN_NUMBER='(0,0,0,0,0,0,0,0,0,0,0,0,0,0,0,0,0,0,0,0,0,0,0,0,0,0,0,0,0,0,0,0,0,0,0,0,0,CL8,0,0)';
      PINUSE='POWER';
      NO_LOAD_CHECK='Both';
      NO_IO_CHECK='Both';
      NO_ASSERT_CHECK='TRUE';
      NO_DIR_CHECK='TRUE';
      ALLOW_CONNECT='TRUE';
    'VSS_CL11':
      PIN_NUMBER='(0,0,0,0,0,0,0,0,0,0,0,0,0,0,0,0,0,0,0,0,0,0,0,0,0,0,0,0,0,0,0,0,0,0,0,0,0,CL11,0,0)';
      PINUSE='POWER';
      NO_LOAD_CHECK='Both';
      NO_IO_CHECK='Both';
      NO_ASSERT_CHECK='TRUE';
      NO_DIR_CHECK='TRUE';
      ALLOW_CONNECT='TRUE';
    'VSS_CL13':
      PIN_NUMBER='(0,0,0,0,0,0,0,0,0,0,0,0,0,0,0,0,0,0,0,0,0,0,0,0,0,0,0,0,0,0,0,0,0,0,0,0,0,CL13,0,0)';
      PINUSE='POWER';
      NO_LOAD_CHECK='Both';
      NO_IO_CHECK='Both';
      NO_ASSERT_CHECK='TRUE';
      NO_DIR_CHECK='TRUE';
      ALLOW_CONNECT='TRUE';
    'VSS_CL15':
      PIN_NUMBER='(0,0,0,0,0,0,0,0,0,0,0,0,0,0,0,0,0,0,0,0,0,0,0,0,0,0,0,0,0,0,0,0,0,0,0,0,0,CL15,0,0)';
      PINUSE='POWER';
      NO_LOAD_CHECK='Both';
      NO_IO_CHECK='Both';
      NO_ASSERT_CHECK='TRUE';
      NO_DIR_CHECK='TRUE';
      ALLOW_CONNECT='TRUE';
    'VSS_CL18':
      PIN_NUMBER='(0,0,0,0,0,0,0,0,0,0,0,0,0,0,0,0,0,0,0,0,0,0,0,0,0,0,0,0,0,0,0,0,0,0,0,0,0,CL18,0,0)';
      PINUSE='POWER';
      NO_LOAD_CHECK='Both';
      NO_IO_CHECK='Both';
      NO_ASSERT_CHECK='TRUE';
      NO_DIR_CHECK='TRUE';
      ALLOW_CONNECT='TRUE';
    'VSS_CL20':
      PIN_NUMBER='(0,0,0,0,0,0,0,0,0,0,0,0,0,0,0,0,0,0,0,0,0,0,0,0,0,0,0,0,0,0,0,0,0,0,0,0,0,CL20,0,0)';
      PINUSE='POWER';
      NO_LOAD_CHECK='Both';
      NO_IO_CHECK='Both';
      NO_ASSERT_CHECK='TRUE';
      NO_DIR_CHECK='TRUE';
      ALLOW_CONNECT='TRUE';
    'VSS_CL22':
      PIN_NUMBER='(0,0,0,0,0,0,0,0,0,0,0,0,0,0,0,0,0,0,0,0,0,0,0,0,0,0,0,0,0,0,0,0,0,0,0,0,0,CL22,0,0)';
      PINUSE='POWER';
      NO_LOAD_CHECK='Both';
      NO_IO_CHECK='Both';
      NO_ASSERT_CHECK='TRUE';
      NO_DIR_CHECK='TRUE';
      ALLOW_CONNECT='TRUE';
    'VSS_CL25':
      PIN_NUMBER='(0,0,0,0,0,0,0,0,0,0,0,0,0,0,0,0,0,0,0,0,0,0,0,0,0,0,0,0,0,0,0,0,0,0,0,0,0,CL25,0,0)';
      PINUSE='POWER';
      NO_LOAD_CHECK='Both';
      NO_IO_CHECK='Both';
      NO_ASSERT_CHECK='TRUE';
      NO_DIR_CHECK='TRUE';
      ALLOW_CONNECT='TRUE';
    'VSS_CL31':
      PIN_NUMBER='(0,0,0,0,0,0,0,0,0,0,0,0,0,0,0,0,0,0,0,0,0,0,0,0,0,0,0,0,0,0,0,0,0,0,0,0,0,CL31,0,0)';
      PINUSE='POWER';
      NO_LOAD_CHECK='Both';
      NO_IO_CHECK='Both';
      NO_ASSERT_CHECK='TRUE';
      NO_DIR_CHECK='TRUE';
      ALLOW_CONNECT='TRUE';
    'VSS_CL34':
      PIN_NUMBER='(0,0,0,0,0,0,0,0,0,0,0,0,0,0,0,0,0,0,0,0,0,0,0,0,0,0,0,0,0,0,0,0,0,0,0,0,0,CL34,0,0)';
      PINUSE='POWER';
      NO_LOAD_CHECK='Both';
      NO_IO_CHECK='Both';
      NO_ASSERT_CHECK='TRUE';
      NO_DIR_CHECK='TRUE';
      ALLOW_CONNECT='TRUE';
    'VSS_CL35':
      PIN_NUMBER='(0,0,0,0,0,0,0,0,0,0,0,0,0,0,0,0,0,0,0,0,0,0,0,0,0,0,0,0,0,0,0,0,0,0,0,0,0,CL35,0,0)';
      PINUSE='POWER';
      NO_LOAD_CHECK='Both';
      NO_IO_CHECK='Both';
      NO_ASSERT_CHECK='TRUE';
      NO_DIR_CHECK='TRUE';
      ALLOW_CONNECT='TRUE';
    'VSS_CL36':
      PIN_NUMBER='(0,0,0,0,0,0,0,0,0,0,0,0,0,0,0,0,0,0,0,0,0,0,0,0,0,0,0,0,0,0,0,0,0,0,0,0,0,CL36,0,0)';
      PINUSE='POWER';
      NO_LOAD_CHECK='Both';
      NO_IO_CHECK='Both';
      NO_ASSERT_CHECK='TRUE';
      NO_DIR_CHECK='TRUE';
      ALLOW_CONNECT='TRUE';
    'VSS_CL40':
      PIN_NUMBER='(0,0,0,0,0,0,0,0,0,0,0,0,0,0,0,0,0,0,0,0,0,0,0,0,0,0,0,0,0,0,0,0,0,0,0,0,0,CL40,0,0)';
      PINUSE='POWER';
      NO_LOAD_CHECK='Both';
      NO_IO_CHECK='Both';
      NO_ASSERT_CHECK='TRUE';
      NO_DIR_CHECK='TRUE';
      ALLOW_CONNECT='TRUE';
    'VSS_CL41':
      PIN_NUMBER='(0,0,0,0,0,0,0,0,0,0,0,0,0,0,0,0,0,0,0,0,0,0,0,0,0,0,0,0,0,0,0,0,0,0,0,0,0,CL41,0,0)';
      PINUSE='POWER';
      NO_LOAD_CHECK='Both';
      NO_IO_CHECK='Both';
      NO_ASSERT_CHECK='TRUE';
      NO_DIR_CHECK='TRUE';
      ALLOW_CONNECT='TRUE';
    'VSS_CL42':
      PIN_NUMBER='(0,0,0,0,0,0,0,0,0,0,0,0,0,0,0,0,0,0,0,0,0,0,0,0,0,0,0,0,0,0,0,0,0,0,0,0,0,CL42,0,0)';
      PINUSE='POWER';
      NO_LOAD_CHECK='Both';
      NO_IO_CHECK='Both';
      NO_ASSERT_CHECK='TRUE';
      NO_DIR_CHECK='TRUE';
      ALLOW_CONNECT='TRUE';
    'VSS_CL45':
      PIN_NUMBER='(0,0,0,0,0,0,0,0,0,0,0,0,0,0,0,0,0,0,0,0,0,0,0,0,0,0,0,0,0,0,0,0,0,0,0,0,0,CL45,0,0)';
      PINUSE='POWER';
      NO_LOAD_CHECK='Both';
      NO_IO_CHECK='Both';
      NO_ASSERT_CHECK='TRUE';
      NO_DIR_CHECK='TRUE';
      ALLOW_CONNECT='TRUE';
    'VSS_CL48':
      PIN_NUMBER='(0,0,0,0,0,0,0,0,0,0,0,0,0,0,0,0,0,0,0,0,0,0,0,0,0,0,0,0,0,0,0,0,0,0,0,0,0,CL48,0,0)';
      PINUSE='POWER';
      NO_LOAD_CHECK='Both';
      NO_IO_CHECK='Both';
      NO_ASSERT_CHECK='TRUE';
      NO_DIR_CHECK='TRUE';
      ALLOW_CONNECT='TRUE';
    'VSS_CL56':
      PIN_NUMBER='(0,0,0,0,0,0,0,0,0,0,0,0,0,0,0,0,0,0,0,0,0,0,0,0,0,0,0,0,0,0,0,0,0,0,0,0,0,CL56,0,0)';
      PINUSE='POWER';
      NO_LOAD_CHECK='Both';
      NO_IO_CHECK='Both';
      NO_ASSERT_CHECK='TRUE';
      NO_DIR_CHECK='TRUE';
      ALLOW_CONNECT='TRUE';
    'VSS_CL58':
      PIN_NUMBER='(0,0,0,0,0,0,0,0,0,0,0,0,0,0,0,0,0,0,0,0,0,0,0,0,0,0,0,0,0,0,0,0,0,0,0,0,0,CL58,0,0)';
      PINUSE='POWER';
      NO_LOAD_CHECK='Both';
      NO_IO_CHECK='Both';
      NO_ASSERT_CHECK='TRUE';
      NO_DIR_CHECK='TRUE';
      ALLOW_CONNECT='TRUE';
    'VSS_CL61':
      PIN_NUMBER='(0,0,0,0,0,0,0,0,0,0,0,0,0,0,0,0,0,0,0,0,0,0,0,0,0,0,0,0,0,0,0,0,0,0,0,0,0,CL61,0,0)';
      PINUSE='POWER';
      NO_LOAD_CHECK='Both';
      NO_IO_CHECK='Both';
      NO_ASSERT_CHECK='TRUE';
      NO_DIR_CHECK='TRUE';
      ALLOW_CONNECT='TRUE';
    'VSS_CL63':
      PIN_NUMBER='(0,0,0,0,0,0,0,0,0,0,0,0,0,0,0,0,0,0,0,0,0,0,0,0,0,0,0,0,0,0,0,0,0,0,0,0,0,CL63,0,0)';
      PINUSE='POWER';
      NO_LOAD_CHECK='Both';
      NO_IO_CHECK='Both';
      NO_ASSERT_CHECK='TRUE';
      NO_DIR_CHECK='TRUE';
      ALLOW_CONNECT='TRUE';
    'VSS_CL65':
      PIN_NUMBER='(0,0,0,0,0,0,0,0,0,0,0,0,0,0,0,0,0,0,0,0,0,0,0,0,0,0,0,0,0,0,0,0,0,0,0,0,0,CL65,0,0)';
      PINUSE='POWER';
      NO_LOAD_CHECK='Both';
      NO_IO_CHECK='Both';
      NO_ASSERT_CHECK='TRUE';
      NO_DIR_CHECK='TRUE';
      ALLOW_CONNECT='TRUE';
    'VSS_CL68':
      PIN_NUMBER='(0,0,0,0,0,0,0,0,0,0,0,0,0,0,0,0,0,0,0,0,0,0,0,0,0,0,0,0,0,0,0,0,0,0,0,0,0,CL68,0,0)';
      PINUSE='POWER';
      NO_LOAD_CHECK='Both';
      NO_IO_CHECK='Both';
      NO_ASSERT_CHECK='TRUE';
      NO_DIR_CHECK='TRUE';
      ALLOW_CONNECT='TRUE';
    'VSS_CL70':
      PIN_NUMBER='(0,0,0,0,0,0,0,0,0,0,0,0,0,0,0,0,0,0,0,0,0,0,0,0,0,0,0,0,0,0,0,0,0,0,0,0,0,CL70,0,0)';
      PINUSE='POWER';
      NO_LOAD_CHECK='Both';
      NO_IO_CHECK='Both';
      NO_ASSERT_CHECK='TRUE';
      NO_DIR_CHECK='TRUE';
      ALLOW_CONNECT='TRUE';
    'VSS_CL72':
      PIN_NUMBER='(0,0,0,0,0,0,0,0,0,0,0,0,0,0,0,0,0,0,0,0,0,0,0,0,0,0,0,0,0,0,0,0,0,0,0,0,0,CL72,0,0)';
      PINUSE='POWER';
      NO_LOAD_CHECK='Both';
      NO_IO_CHECK='Both';
      NO_ASSERT_CHECK='TRUE';
      NO_DIR_CHECK='TRUE';
      ALLOW_CONNECT='TRUE';
    'VSS_CM8':
      PIN_NUMBER='(0,0,0,0,0,0,0,0,0,0,0,0,0,0,0,0,0,0,0,0,0,0,0,0,0,0,0,0,0,0,0,0,0,0,0,0,0,CM8,0,0)';
      PINUSE='POWER';
      NO_LOAD_CHECK='Both';
      NO_IO_CHECK='Both';
      NO_ASSERT_CHECK='TRUE';
      NO_DIR_CHECK='TRUE';
      ALLOW_CONNECT='TRUE';
    'VSS_CM10':
      PIN_NUMBER='(0,0,0,0,0,0,0,0,0,0,0,0,0,0,0,0,0,0,0,0,0,0,0,0,0,0,0,0,0,0,0,0,0,0,0,0,0,CM10,0,0)';
      PINUSE='POWER';
      NO_LOAD_CHECK='Both';
      NO_IO_CHECK='Both';
      NO_ASSERT_CHECK='TRUE';
      NO_DIR_CHECK='TRUE';
      ALLOW_CONNECT='TRUE';
    'VSS_CM12':
      PIN_NUMBER='(0,0,0,0,0,0,0,0,0,0,0,0,0,0,0,0,0,0,0,0,0,0,0,0,0,0,0,0,0,0,0,0,0,0,0,0,0,CM12,0,0)';
      PINUSE='POWER';
      NO_LOAD_CHECK='Both';
      NO_IO_CHECK='Both';
      NO_ASSERT_CHECK='TRUE';
      NO_DIR_CHECK='TRUE';
      ALLOW_CONNECT='TRUE';
    'VSS_CM15':
      PIN_NUMBER='(0,0,0,0,0,0,0,0,0,0,0,0,0,0,0,0,0,0,0,0,0,0,0,0,0,0,0,0,0,0,0,0,0,0,0,0,0,CM15,0,0)';
      PINUSE='POWER';
      NO_LOAD_CHECK='Both';
      NO_IO_CHECK='Both';
      NO_ASSERT_CHECK='TRUE';
      NO_DIR_CHECK='TRUE';
      ALLOW_CONNECT='TRUE';
    'VSS_CM17':
      PIN_NUMBER='(0,0,0,0,0,0,0,0,0,0,0,0,0,0,0,0,0,0,0,0,0,0,0,0,0,0,0,0,0,0,0,0,0,0,0,0,0,CM17,0,0)';
      PINUSE='POWER';
      NO_LOAD_CHECK='Both';
      NO_IO_CHECK='Both';
      NO_ASSERT_CHECK='TRUE';
      NO_DIR_CHECK='TRUE';
      ALLOW_CONNECT='TRUE';
    'VSS_CM19':
      PIN_NUMBER='(0,0,0,0,0,0,0,0,0,0,0,0,0,0,0,0,0,0,0,0,0,0,0,0,0,0,0,0,0,0,0,0,0,0,0,0,0,CM19,0,0)';
      PINUSE='POWER';
      NO_LOAD_CHECK='Both';
      NO_IO_CHECK='Both';
      NO_ASSERT_CHECK='TRUE';
      NO_DIR_CHECK='TRUE';
      ALLOW_CONNECT='TRUE';
    'VSS_CM23':
      PIN_NUMBER='(0,0,0,0,0,0,0,0,0,0,0,0,0,0,0,0,0,0,0,0,0,0,0,0,0,0,0,0,0,0,0,0,0,0,0,0,0,CM23,0,0)';
      PINUSE='POWER';
      NO_LOAD_CHECK='Both';
      NO_IO_CHECK='Both';
      NO_ASSERT_CHECK='TRUE';
      NO_DIR_CHECK='TRUE';
      ALLOW_CONNECT='TRUE';
    'VSS_CM28':
      PIN_NUMBER='(0,0,0,0,0,0,0,0,0,0,0,0,0,0,0,0,0,0,0,0,0,0,0,0,0,0,0,0,0,0,0,0,0,0,0,0,0,CM28,0,0)';
      PINUSE='POWER';
      NO_LOAD_CHECK='Both';
      NO_IO_CHECK='Both';
      NO_ASSERT_CHECK='TRUE';
      NO_DIR_CHECK='TRUE';
      ALLOW_CONNECT='TRUE';
    'VSS_CM29':
      PIN_NUMBER='(0,0,0,0,0,0,0,0,0,0,0,0,0,0,0,0,0,0,0,0,0,0,0,0,0,0,0,0,0,0,0,0,0,0,0,0,0,CM29,0,0)';
      PINUSE='POWER';
      NO_LOAD_CHECK='Both';
      NO_IO_CHECK='Both';
      NO_ASSERT_CHECK='TRUE';
      NO_DIR_CHECK='TRUE';
      ALLOW_CONNECT='TRUE';
    'VSS_CM30':
      PIN_NUMBER='(0,0,0,0,0,0,0,0,0,0,0,0,0,0,0,0,0,0,0,0,0,0,0,0,0,0,0,0,0,0,0,0,0,0,0,0,0,CM30,0,0)';
      PINUSE='POWER';
      NO_LOAD_CHECK='Both';
      NO_IO_CHECK='Both';
      NO_ASSERT_CHECK='TRUE';
      NO_DIR_CHECK='TRUE';
      ALLOW_CONNECT='TRUE';
    'VSS_CM31':
      PIN_NUMBER='(0,0,0,0,0,0,0,0,0,0,0,0,0,0,0,0,0,0,0,0,0,0,0,0,0,0,0,0,0,0,0,0,0,0,0,0,0,CM31,0,0)';
      PINUSE='POWER';
      NO_LOAD_CHECK='Both';
      NO_IO_CHECK='Both';
      NO_ASSERT_CHECK='TRUE';
      NO_DIR_CHECK='TRUE';
      ALLOW_CONNECT='TRUE';
    'VSS_CM32':
      PIN_NUMBER='(0,0,0,0,0,0,0,0,0,0,0,0,0,0,0,0,0,0,0,0,0,0,0,0,0,0,0,0,0,0,0,0,0,0,0,0,0,CM32,0,0)';
      PINUSE='POWER';
      NO_LOAD_CHECK='Both';
      NO_IO_CHECK='Both';
      NO_ASSERT_CHECK='TRUE';
      NO_DIR_CHECK='TRUE';
      ALLOW_CONNECT='TRUE';
    'VSS_CM33':
      PIN_NUMBER='(0,0,0,0,0,0,0,0,0,0,0,0,0,0,0,0,0,0,0,0,0,0,0,0,0,0,0,0,0,0,0,0,0,0,0,0,0,CM33,0,0)';
      PINUSE='POWER';
      NO_LOAD_CHECK='Both';
      NO_IO_CHECK='Both';
      NO_ASSERT_CHECK='TRUE';
      NO_DIR_CHECK='TRUE';
      ALLOW_CONNECT='TRUE';
    'VSS_CM44':
      PIN_NUMBER='(0,0,0,0,0,0,0,0,0,0,0,0,0,0,0,0,0,0,0,0,0,0,0,0,0,0,0,0,0,0,0,0,0,0,0,0,0,CM44,0,0)';
      PINUSE='POWER';
      NO_LOAD_CHECK='Both';
      NO_IO_CHECK='Both';
      NO_ASSERT_CHECK='TRUE';
      NO_DIR_CHECK='TRUE';
      ALLOW_CONNECT='TRUE';
    'VSS_CM45':
      PIN_NUMBER='(0,0,0,0,0,0,0,0,0,0,0,0,0,0,0,0,0,0,0,0,0,0,0,0,0,0,0,0,0,0,0,0,0,0,0,0,0,CM45,0,0)';
      PINUSE='POWER';
      NO_LOAD_CHECK='Both';
      NO_IO_CHECK='Both';
      NO_ASSERT_CHECK='TRUE';
      NO_DIR_CHECK='TRUE';
      ALLOW_CONNECT='TRUE';
    'VSS_CM46':
      PIN_NUMBER='(0,0,0,0,0,0,0,0,0,0,0,0,0,0,0,0,0,0,0,0,0,0,0,0,0,0,0,0,0,0,0,0,0,0,0,0,0,CM46,0,0)';
      PINUSE='POWER';
      NO_LOAD_CHECK='Both';
      NO_IO_CHECK='Both';
      NO_ASSERT_CHECK='TRUE';
      NO_DIR_CHECK='TRUE';
      ALLOW_CONNECT='TRUE';
    'VSS_CM47':
      PIN_NUMBER='(0,0,0,0,0,0,0,0,0,0,0,0,0,0,0,0,0,0,0,0,0,0,0,0,0,0,0,0,0,0,0,0,0,0,0,0,0,CM47,0,0)';
      PINUSE='POWER';
      NO_LOAD_CHECK='Both';
      NO_IO_CHECK='Both';
      NO_ASSERT_CHECK='TRUE';
      NO_DIR_CHECK='TRUE';
      ALLOW_CONNECT='TRUE';
    'VSS_CM48':
      PIN_NUMBER='(0,0,0,0,0,0,0,0,0,0,0,0,0,0,0,0,0,0,0,0,0,0,0,0,0,0,0,0,0,0,0,0,0,0,0,0,0,CM48,0,0)';
      PINUSE='POWER';
      NO_LOAD_CHECK='Both';
      NO_IO_CHECK='Both';
      NO_ASSERT_CHECK='TRUE';
      NO_DIR_CHECK='TRUE';
      ALLOW_CONNECT='TRUE';
    'VSS_CM49':
      PIN_NUMBER='(0,0,0,0,0,0,0,0,0,0,0,0,0,0,0,0,0,0,0,0,0,0,0,0,0,0,0,0,0,0,0,0,0,0,0,0,0,CM49,0,0)';
      PINUSE='POWER';
      NO_LOAD_CHECK='Both';
      NO_IO_CHECK='Both';
      NO_ASSERT_CHECK='TRUE';
      NO_DIR_CHECK='TRUE';
      ALLOW_CONNECT='TRUE';
    'VSS_CM51':
      PIN_NUMBER='(0,0,0,0,0,0,0,0,0,0,0,0,0,0,0,0,0,0,0,0,0,0,0,0,0,0,0,0,0,0,0,0,0,0,0,0,0,CM51,0,0)';
      PINUSE='POWER';
      NO_LOAD_CHECK='Both';
      NO_IO_CHECK='Both';
      NO_ASSERT_CHECK='TRUE';
      NO_DIR_CHECK='TRUE';
      ALLOW_CONNECT='TRUE';
    'VSS_CM52':
      PIN_NUMBER='(0,0,0,0,0,0,0,0,0,0,0,0,0,0,0,0,0,0,0,0,0,0,0,0,0,0,0,0,0,0,0,0,0,0,0,0,0,CM52,0,0)';
      PINUSE='POWER';
      NO_LOAD_CHECK='Both';
      NO_IO_CHECK='Both';
      NO_ASSERT_CHECK='TRUE';
      NO_DIR_CHECK='TRUE';
      ALLOW_CONNECT='TRUE';
    'VSS_CM53':
      PIN_NUMBER='(0,0,0,0,0,0,0,0,0,0,0,0,0,0,0,0,0,0,0,0,0,0,0,0,0,0,0,0,0,0,0,0,0,0,0,0,0,CM53,0,0)';
      PINUSE='POWER';
      NO_LOAD_CHECK='Both';
      NO_IO_CHECK='Both';
      NO_ASSERT_CHECK='TRUE';
      NO_DIR_CHECK='TRUE';
      ALLOW_CONNECT='TRUE';
    'VSS_CM57':
      PIN_NUMBER='(0,0,0,0,0,0,0,0,0,0,0,0,0,0,0,0,0,0,0,0,0,0,0,0,0,0,0,0,0,0,0,0,0,0,0,0,0,CM57,0,0)';
      PINUSE='POWER';
      NO_LOAD_CHECK='Both';
      NO_IO_CHECK='Both';
      NO_ASSERT_CHECK='TRUE';
      NO_DIR_CHECK='TRUE';
      ALLOW_CONNECT='TRUE';
    'VSS_CM59':
      PIN_NUMBER='(0,0,0,0,0,0,0,0,0,0,0,0,0,0,0,0,0,0,0,0,0,0,0,0,0,0,0,0,0,0,0,0,0,0,0,0,0,CM59,0,0)';
      PINUSE='POWER';
      NO_LOAD_CHECK='Both';
      NO_IO_CHECK='Both';
      NO_ASSERT_CHECK='TRUE';
      NO_DIR_CHECK='TRUE';
      ALLOW_CONNECT='TRUE';
    'VSS_CM68':
      PIN_NUMBER='(0,0,0,0,0,0,0,0,0,0,0,0,0,0,0,0,0,0,0,0,0,0,0,0,0,0,0,0,0,0,0,0,0,0,0,0,0,CM68,0,0)';
      PINUSE='POWER';
      NO_LOAD_CHECK='Both';
      NO_IO_CHECK='Both';
      NO_ASSERT_CHECK='TRUE';
      NO_DIR_CHECK='TRUE';
      ALLOW_CONNECT='TRUE';
    'VSS_CM71':
      PIN_NUMBER='(0,0,0,0,0,0,0,0,0,0,0,0,0,0,0,0,0,0,0,0,0,0,0,0,0,0,0,0,0,0,0,0,0,0,0,0,0,CM71,0,0)';
      PINUSE='POWER';
      NO_LOAD_CHECK='Both';
      NO_IO_CHECK='Both';
      NO_ASSERT_CHECK='TRUE';
      NO_DIR_CHECK='TRUE';
      ALLOW_CONNECT='TRUE';
    'VSS_CM73':
      PIN_NUMBER='(0,0,0,0,0,0,0,0,0,0,0,0,0,0,0,0,0,0,0,0,0,0,0,0,0,0,0,0,0,0,0,0,0,0,0,0,0,CM73,0,0)';
      PINUSE='POWER';
      NO_LOAD_CHECK='Both';
      NO_IO_CHECK='Both';
      NO_ASSERT_CHECK='TRUE';
      NO_DIR_CHECK='TRUE';
      ALLOW_CONNECT='TRUE';
    'VSS_CN1':
      PIN_NUMBER='(0,0,0,0,0,0,0,0,0,0,0,0,0,0,0,0,0,0,0,0,0,0,0,0,0,0,0,0,0,0,0,0,0,0,0,0,0,CN1,0,0)';
      PINUSE='POWER';
      NO_LOAD_CHECK='Both';
      NO_IO_CHECK='Both';
      NO_ASSERT_CHECK='TRUE';
      NO_DIR_CHECK='TRUE';
      ALLOW_CONNECT='TRUE';
    'VSS_CN6':
      PIN_NUMBER='(0,0,0,0,0,0,0,0,0,0,0,0,0,0,0,0,0,0,0,0,0,0,0,0,0,0,0,0,0,0,0,0,0,0,0,0,0,CN6,0,0)';
      PINUSE='POWER';
      NO_LOAD_CHECK='Both';
      NO_IO_CHECK='Both';
      NO_ASSERT_CHECK='TRUE';
      NO_DIR_CHECK='TRUE';
      ALLOW_CONNECT='TRUE';
    'VSS_CN8':
      PIN_NUMBER='(0,0,0,0,0,0,0,0,0,0,0,0,0,0,0,0,0,0,0,0,0,0,0,0,0,0,0,0,0,0,0,0,0,0,0,0,0,CN8,0,0)';
      PINUSE='POWER';
      NO_LOAD_CHECK='Both';
      NO_IO_CHECK='Both';
      NO_ASSERT_CHECK='TRUE';
      NO_DIR_CHECK='TRUE';
      ALLOW_CONNECT='TRUE';
    'VSS_CN13':
      PIN_NUMBER='(0,0,0,0,0,0,0,0,0,0,0,0,0,0,0,0,0,0,0,0,0,0,0,0,0,0,0,0,0,0,0,0,0,0,0,0,0,CN13,0,0)';
      PINUSE='POWER';
      NO_LOAD_CHECK='Both';
      NO_IO_CHECK='Both';
      NO_ASSERT_CHECK='TRUE';
      NO_DIR_CHECK='TRUE';
      ALLOW_CONNECT='TRUE';
    'VSS_CN15':
      PIN_NUMBER='(0,0,0,0,0,0,0,0,0,0,0,0,0,0,0,0,0,0,0,0,0,0,0,0,0,0,0,0,0,0,0,0,0,0,0,0,0,CN15,0,0)';
      PINUSE='POWER';
      NO_LOAD_CHECK='Both';
      NO_IO_CHECK='Both';
      NO_ASSERT_CHECK='TRUE';
      NO_DIR_CHECK='TRUE';
      ALLOW_CONNECT='TRUE';
    'VSS_CN25':
      PIN_NUMBER='(0,0,0,0,0,0,0,0,0,0,0,0,0,0,0,0,0,0,0,0,0,0,0,0,0,0,0,0,0,0,0,0,0,0,0,0,0,CN25,0,0)';
      PINUSE='POWER';
      NO_LOAD_CHECK='Both';
      NO_IO_CHECK='Both';
      NO_ASSERT_CHECK='TRUE';
      NO_DIR_CHECK='TRUE';
      ALLOW_CONNECT='TRUE';
    'VSS_CN28':
      PIN_NUMBER='(0,0,0,0,0,0,0,0,0,0,0,0,0,0,0,0,0,0,0,0,0,0,0,0,0,0,0,0,0,0,0,0,0,0,0,0,0,CN28,0,0)';
      PINUSE='POWER';
      NO_LOAD_CHECK='Both';
      NO_IO_CHECK='Both';
      NO_ASSERT_CHECK='TRUE';
      NO_DIR_CHECK='TRUE';
      ALLOW_CONNECT='TRUE';
    'VSS_CN31':
      PIN_NUMBER='(0,0,0,0,0,0,0,0,0,0,0,0,0,0,0,0,0,0,0,0,0,0,0,0,0,0,0,0,0,0,0,0,0,0,0,0,0,CN31,0,0)';
      PINUSE='POWER';
      NO_LOAD_CHECK='Both';
      NO_IO_CHECK='Both';
      NO_ASSERT_CHECK='TRUE';
      NO_DIR_CHECK='TRUE';
      ALLOW_CONNECT='TRUE';
    'VSS_CN34':
      PIN_NUMBER='(0,0,0,0,0,0,0,0,0,0,0,0,0,0,0,0,0,0,0,0,0,0,0,0,0,0,0,0,0,0,0,0,0,0,0,0,0,CN34,0,0)';
      PINUSE='POWER';
      NO_LOAD_CHECK='Both';
      NO_IO_CHECK='Both';
      NO_ASSERT_CHECK='TRUE';
      NO_DIR_CHECK='TRUE';
      ALLOW_CONNECT='TRUE';
    'VSS_CN42':
      PIN_NUMBER='(0,0,0,0,0,0,0,0,0,0,0,0,0,0,0,0,0,0,0,0,0,0,0,0,0,0,0,0,0,0,0,0,0,0,0,0,0,CN42,0,0)';
      PINUSE='POWER';
      NO_LOAD_CHECK='Both';
      NO_IO_CHECK='Both';
      NO_ASSERT_CHECK='TRUE';
      NO_DIR_CHECK='TRUE';
      ALLOW_CONNECT='TRUE';
    'VSS_CN45':
      PIN_NUMBER='(0,0,0,0,0,0,0,0,0,0,0,0,0,0,0,0,0,0,0,0,0,0,0,0,0,0,0,0,0,0,0,0,0,0,0,0,0,CN45,0,0)';
      PINUSE='POWER';
      NO_LOAD_CHECK='Both';
      NO_IO_CHECK='Both';
      NO_ASSERT_CHECK='TRUE';
      NO_DIR_CHECK='TRUE';
      ALLOW_CONNECT='TRUE';
    'VSS_CN48':
      PIN_NUMBER='(0,0,0,0,0,0,0,0,0,0,0,0,0,0,0,0,0,0,0,0,0,0,0,0,0,0,0,0,0,0,0,0,0,0,0,0,0,CN48,0,0)';
      PINUSE='POWER';
      NO_LOAD_CHECK='Both';
      NO_IO_CHECK='Both';
      NO_ASSERT_CHECK='TRUE';
      NO_DIR_CHECK='TRUE';
      ALLOW_CONNECT='TRUE';
    'VSS_CN51':
      PIN_NUMBER='(0,0,0,0,0,0,0,0,0,0,0,0,0,0,0,0,0,0,0,0,0,0,0,0,0,0,0,0,0,0,0,0,0,0,0,0,0,CN51,0,0)';
      PINUSE='POWER';
      NO_LOAD_CHECK='Both';
      NO_IO_CHECK='Both';
      NO_ASSERT_CHECK='TRUE';
      NO_DIR_CHECK='TRUE';
      ALLOW_CONNECT='TRUE';
    'VSS_CN61':
      PIN_NUMBER='(0,0,0,0,0,0,0,0,0,0,0,0,0,0,0,0,0,0,0,0,0,0,0,0,0,0,0,0,0,0,0,0,0,0,0,0,0,CN61,0,0)';
      PINUSE='POWER';
      NO_LOAD_CHECK='Both';
      NO_IO_CHECK='Both';
      NO_ASSERT_CHECK='TRUE';
      NO_DIR_CHECK='TRUE';
      ALLOW_CONNECT='TRUE';
    'VSS_CN63':
      PIN_NUMBER='(0,0,0,0,0,0,0,0,0,0,0,0,0,0,0,0,0,0,0,0,0,0,0,0,0,0,0,0,0,0,0,0,0,0,0,0,0,CN63,0,0)';
      PINUSE='POWER';
      NO_LOAD_CHECK='Both';
      NO_IO_CHECK='Both';
      NO_ASSERT_CHECK='TRUE';
      NO_DIR_CHECK='TRUE';
      ALLOW_CONNECT='TRUE';
    'VSS_CN68':
      PIN_NUMBER='(0,0,0,0,0,0,0,0,0,0,0,0,0,0,0,0,0,0,0,0,0,0,0,0,0,0,0,0,0,0,0,0,0,0,0,0,0,CN68,0,0)';
      PINUSE='POWER';
      NO_LOAD_CHECK='Both';
      NO_IO_CHECK='Both';
      NO_ASSERT_CHECK='TRUE';
      NO_DIR_CHECK='TRUE';
      ALLOW_CONNECT='TRUE';
    'VSS_CN70':
      PIN_NUMBER='(0,0,0,0,0,0,0,0,0,0,0,0,0,0,0,0,0,0,0,0,0,0,0,0,0,0,0,0,0,0,0,0,0,0,0,0,0,CN70,0,0)';
      PINUSE='POWER';
      NO_LOAD_CHECK='Both';
      NO_IO_CHECK='Both';
      NO_ASSERT_CHECK='TRUE';
      NO_DIR_CHECK='TRUE';
      ALLOW_CONNECT='TRUE';
    'VSS_CN75':
      PIN_NUMBER='(0,0,0,0,0,0,0,0,0,0,0,0,0,0,0,0,0,0,0,0,0,0,0,0,0,0,0,0,0,0,0,0,0,0,0,0,0,CN75,0,0)';
      PINUSE='POWER';
      NO_LOAD_CHECK='Both';
      NO_IO_CHECK='Both';
      NO_ASSERT_CHECK='TRUE';
      NO_DIR_CHECK='TRUE';
      ALLOW_CONNECT='TRUE';
    'VSS_CP3':
      PIN_NUMBER='(0,0,0,0,0,0,0,0,0,0,0,0,0,0,0,0,0,0,0,0,0,0,0,0,0,0,0,0,0,0,0,0,0,0,0,0,0,CP3,0,0)';
      PINUSE='POWER';
      NO_LOAD_CHECK='Both';
      NO_IO_CHECK='Both';
      NO_ASSERT_CHECK='TRUE';
      NO_DIR_CHECK='TRUE';
      ALLOW_CONNECT='TRUE';
    'VSS_CP5':
      PIN_NUMBER='(0,0,0,0,0,0,0,0,0,0,0,0,0,0,0,0,0,0,0,0,0,0,0,0,0,0,0,0,0,0,0,0,0,0,0,0,0,CP5,0,0)';
      PINUSE='POWER';
      NO_LOAD_CHECK='Both';
      NO_IO_CHECK='Both';
      NO_ASSERT_CHECK='TRUE';
      NO_DIR_CHECK='TRUE';
      ALLOW_CONNECT='TRUE';
    'VSS_CP8':
      PIN_NUMBER='(0,0,0,0,0,0,0,0,0,0,0,0,0,0,0,0,0,0,0,0,0,0,0,0,0,0,0,0,0,0,0,0,0,0,0,0,0,CP8,0,0)';
      PINUSE='POWER';
      NO_LOAD_CHECK='Both';
      NO_IO_CHECK='Both';
      NO_ASSERT_CHECK='TRUE';
      NO_DIR_CHECK='TRUE';
      ALLOW_CONNECT='TRUE';
    'VSS_CP10':
      PIN_NUMBER='(0,0,0,0,0,0,0,0,0,0,0,0,0,0,0,0,0,0,0,0,0,0,0,0,0,0,0,0,0,0,0,0,0,0,0,0,0,CP10,0,0)';
      PINUSE='POWER';
      NO_LOAD_CHECK='Both';
      NO_IO_CHECK='Both';
      NO_ASSERT_CHECK='TRUE';
      NO_DIR_CHECK='TRUE';
      ALLOW_CONNECT='TRUE';
    'VSS_CP12':
      PIN_NUMBER='(0,0,0,0,0,0,0,0,0,0,0,0,0,0,0,0,0,0,0,0,0,0,0,0,0,0,0,0,0,0,0,0,0,0,0,0,0,CP12,0,0)';
      PINUSE='POWER';
      NO_LOAD_CHECK='Both';
      NO_IO_CHECK='Both';
      NO_ASSERT_CHECK='TRUE';
      NO_DIR_CHECK='TRUE';
      ALLOW_CONNECT='TRUE';
    'VSS_CP15':
      PIN_NUMBER='(0,0,0,0,0,0,0,0,0,0,0,0,0,0,0,0,0,0,0,0,0,0,0,0,0,0,0,0,0,0,0,0,0,0,0,0,0,CP15,0,0)';
      PINUSE='POWER';
      NO_LOAD_CHECK='Both';
      NO_IO_CHECK='Both';
      NO_ASSERT_CHECK='TRUE';
      NO_DIR_CHECK='TRUE';
      ALLOW_CONNECT='TRUE';
    'VSS_CP17':
      PIN_NUMBER='(0,0,0,0,0,0,0,0,0,0,0,0,0,0,0,0,0,0,0,0,0,0,0,0,0,0,0,0,0,0,0,0,0,0,0,0,0,CP17,0,0)';
      PINUSE='POWER';
      NO_LOAD_CHECK='Both';
      NO_IO_CHECK='Both';
      NO_ASSERT_CHECK='TRUE';
      NO_DIR_CHECK='TRUE';
      ALLOW_CONNECT='TRUE';
    'VSS_CP19':
      PIN_NUMBER='(0,0,0,0,0,0,0,0,0,0,0,0,0,0,0,0,0,0,0,0,0,0,0,0,0,0,0,0,0,0,0,0,0,0,0,0,0,CP19,0,0)';
      PINUSE='POWER';
      NO_LOAD_CHECK='Both';
      NO_IO_CHECK='Both';
      NO_ASSERT_CHECK='TRUE';
      NO_DIR_CHECK='TRUE';
      ALLOW_CONNECT='TRUE';
    'VSS_CP22':
      PIN_NUMBER='(0,0,0,0,0,0,0,0,0,0,0,0,0,0,0,0,0,0,0,0,0,0,0,0,0,0,0,0,0,0,0,0,0,0,0,0,0,0,CP22,0)';
      PINUSE='POWER';
      NO_LOAD_CHECK='Both';
      NO_IO_CHECK='Both';
      NO_ASSERT_CHECK='TRUE';
      NO_DIR_CHECK='TRUE';
      ALLOW_CONNECT='TRUE';
    'VSS_CP42':
      PIN_NUMBER='(0,0,0,0,0,0,0,0,0,0,0,0,0,0,0,0,0,0,0,0,0,0,0,0,0,0,0,0,0,0,0,0,0,0,0,0,0,0,CP42,0)';
      PINUSE='POWER';
      NO_LOAD_CHECK='Both';
      NO_IO_CHECK='Both';
      NO_ASSERT_CHECK='TRUE';
      NO_DIR_CHECK='TRUE';
      ALLOW_CONNECT='TRUE';
    'VSS_CP45':
      PIN_NUMBER='(0,0,0,0,0,0,0,0,0,0,0,0,0,0,0,0,0,0,0,0,0,0,0,0,0,0,0,0,0,0,0,0,0,0,0,0,0,0,CP45,0)';
      PINUSE='POWER';
      NO_LOAD_CHECK='Both';
      NO_IO_CHECK='Both';
      NO_ASSERT_CHECK='TRUE';
      NO_DIR_CHECK='TRUE';
      ALLOW_CONNECT='TRUE';
    'VSS_CP48':
      PIN_NUMBER='(0,0,0,0,0,0,0,0,0,0,0,0,0,0,0,0,0,0,0,0,0,0,0,0,0,0,0,0,0,0,0,0,0,0,0,0,0,0,CP48,0)';
      PINUSE='POWER';
      NO_LOAD_CHECK='Both';
      NO_IO_CHECK='Both';
      NO_ASSERT_CHECK='TRUE';
      NO_DIR_CHECK='TRUE';
      ALLOW_CONNECT='TRUE';
    'VSS_CP51':
      PIN_NUMBER='(0,0,0,0,0,0,0,0,0,0,0,0,0,0,0,0,0,0,0,0,0,0,0,0,0,0,0,0,0,0,0,0,0,0,0,0,0,0,CP51,0)';
      PINUSE='POWER';
      NO_LOAD_CHECK='Both';
      NO_IO_CHECK='Both';
      NO_ASSERT_CHECK='TRUE';
      NO_DIR_CHECK='TRUE';
      ALLOW_CONNECT='TRUE';
    'VSS_CP54':
      PIN_NUMBER='(0,0,0,0,0,0,0,0,0,0,0,0,0,0,0,0,0,0,0,0,0,0,0,0,0,0,0,0,0,0,0,0,0,0,0,0,0,0,CP54,0)';
      PINUSE='POWER';
      NO_LOAD_CHECK='Both';
      NO_IO_CHECK='Both';
      NO_ASSERT_CHECK='TRUE';
      NO_DIR_CHECK='TRUE';
      ALLOW_CONNECT='TRUE';
    'VSS_CP71':
      PIN_NUMBER='(0,0,0,0,0,0,0,0,0,0,0,0,0,0,0,0,0,0,0,0,0,0,0,0,0,0,0,0,0,0,0,0,0,0,0,0,0,0,CP71,0)';
      PINUSE='POWER';
      NO_LOAD_CHECK='Both';
      NO_IO_CHECK='Both';
      NO_ASSERT_CHECK='TRUE';
      NO_DIR_CHECK='TRUE';
      ALLOW_CONNECT='TRUE';
    'VSS_CP73':
      PIN_NUMBER='(0,0,0,0,0,0,0,0,0,0,0,0,0,0,0,0,0,0,0,0,0,0,0,0,0,0,0,0,0,0,0,0,0,0,0,0,0,0,CP73,0)';
      PINUSE='POWER';
      NO_LOAD_CHECK='Both';
      NO_IO_CHECK='Both';
      NO_ASSERT_CHECK='TRUE';
      NO_DIR_CHECK='TRUE';
      ALLOW_CONNECT='TRUE';
    'VSS_CR1':
      PIN_NUMBER='(0,0,0,0,0,0,0,0,0,0,0,0,0,0,0,0,0,0,0,0,0,0,0,0,0,0,0,0,0,0,0,0,0,0,0,0,0,0,CR1,0)';
      PINUSE='POWER';
      NO_LOAD_CHECK='Both';
      NO_IO_CHECK='Both';
      NO_ASSERT_CHECK='TRUE';
      NO_DIR_CHECK='TRUE';
      ALLOW_CONNECT='TRUE';
    'VSS_CR4':
      PIN_NUMBER='(0,0,0,0,0,0,0,0,0,0,0,0,0,0,0,0,0,0,0,0,0,0,0,0,0,0,0,0,0,0,0,0,0,0,0,0,0,0,CR4,0)';
      PINUSE='POWER';
      NO_LOAD_CHECK='Both';
      NO_IO_CHECK='Both';
      NO_ASSERT_CHECK='TRUE';
      NO_DIR_CHECK='TRUE';
      ALLOW_CONNECT='TRUE';
    'VSS_CR6':
      PIN_NUMBER='(0,0,0,0,0,0,0,0,0,0,0,0,0,0,0,0,0,0,0,0,0,0,0,0,0,0,0,0,0,0,0,0,0,0,0,0,0,0,CR6,0)';
      PINUSE='POWER';
      NO_LOAD_CHECK='Both';
      NO_IO_CHECK='Both';
      NO_ASSERT_CHECK='TRUE';
      NO_DIR_CHECK='TRUE';
      ALLOW_CONNECT='TRUE';
    'VSS_CR22':
      PIN_NUMBER='(0,0,0,0,0,0,0,0,0,0,0,0,0,0,0,0,0,0,0,0,0,0,0,0,0,0,0,0,0,0,0,0,0,0,0,0,0,0,CR22,0)';
      PINUSE='POWER';
      NO_LOAD_CHECK='Both';
      NO_IO_CHECK='Both';
      NO_ASSERT_CHECK='TRUE';
      NO_DIR_CHECK='TRUE';
      ALLOW_CONNECT='TRUE';
    'VSS_CR25':
      PIN_NUMBER='(0,0,0,0,0,0,0,0,0,0,0,0,0,0,0,0,0,0,0,0,0,0,0,0,0,0,0,0,0,0,0,0,0,0,0,0,0,0,CR25,0)';
      PINUSE='POWER';
      NO_LOAD_CHECK='Both';
      NO_IO_CHECK='Both';
      NO_ASSERT_CHECK='TRUE';
      NO_DIR_CHECK='TRUE';
      ALLOW_CONNECT='TRUE';
    'VSS_CR28':
      PIN_NUMBER='(0,0,0,0,0,0,0,0,0,0,0,0,0,0,0,0,0,0,0,0,0,0,0,0,0,0,0,0,0,0,0,0,0,0,0,0,0,0,CR28,0)';
      PINUSE='POWER';
      NO_LOAD_CHECK='Both';
      NO_IO_CHECK='Both';
      NO_ASSERT_CHECK='TRUE';
      NO_DIR_CHECK='TRUE';
      ALLOW_CONNECT='TRUE';
    'VSS_CR31':
      PIN_NUMBER='(0,0,0,0,0,0,0,0,0,0,0,0,0,0,0,0,0,0,0,0,0,0,0,0,0,0,0,0,0,0,0,0,0,0,0,0,0,0,CR31,0)';
      PINUSE='POWER';
      NO_LOAD_CHECK='Both';
      NO_IO_CHECK='Both';
      NO_ASSERT_CHECK='TRUE';
      NO_DIR_CHECK='TRUE';
      ALLOW_CONNECT='TRUE';
    'VSS_CR34':
      PIN_NUMBER='(0,0,0,0,0,0,0,0,0,0,0,0,0,0,0,0,0,0,0,0,0,0,0,0,0,0,0,0,0,0,0,0,0,0,0,0,0,0,CR34,0)';
      PINUSE='POWER';
      NO_LOAD_CHECK='Both';
      NO_IO_CHECK='Both';
      NO_ASSERT_CHECK='TRUE';
      NO_DIR_CHECK='TRUE';
      ALLOW_CONNECT='TRUE';
    'VSS_CR48':
      PIN_NUMBER='(0,0,0,0,0,0,0,0,0,0,0,0,0,0,0,0,0,0,0,0,0,0,0,0,0,0,0,0,0,0,0,0,0,0,0,0,0,0,CR48,0)';
      PINUSE='POWER';
      NO_LOAD_CHECK='Both';
      NO_IO_CHECK='Both';
      NO_ASSERT_CHECK='TRUE';
      NO_DIR_CHECK='TRUE';
      ALLOW_CONNECT='TRUE';
    'VSS_CR51':
      PIN_NUMBER='(0,0,0,0,0,0,0,0,0,0,0,0,0,0,0,0,0,0,0,0,0,0,0,0,0,0,0,0,0,0,0,0,0,0,0,0,0,0,CR51,0)';
      PINUSE='POWER';
      NO_LOAD_CHECK='Both';
      NO_IO_CHECK='Both';
      NO_ASSERT_CHECK='TRUE';
      NO_DIR_CHECK='TRUE';
      ALLOW_CONNECT='TRUE';
    'VSS_CR54':
      PIN_NUMBER='(0,0,0,0,0,0,0,0,0,0,0,0,0,0,0,0,0,0,0,0,0,0,0,0,0,0,0,0,0,0,0,0,0,0,0,0,0,0,CR54,0)';
      PINUSE='POWER';
      NO_LOAD_CHECK='Both';
      NO_IO_CHECK='Both';
      NO_ASSERT_CHECK='TRUE';
      NO_DIR_CHECK='TRUE';
      ALLOW_CONNECT='TRUE';
    'VSS_CR56':
      PIN_NUMBER='(0,0,0,0,0,0,0,0,0,0,0,0,0,0,0,0,0,0,0,0,0,0,0,0,0,0,0,0,0,0,0,0,0,0,0,0,0,0,CR56,0)';
      PINUSE='POWER';
      NO_LOAD_CHECK='Both';
      NO_IO_CHECK='Both';
      NO_ASSERT_CHECK='TRUE';
      NO_DIR_CHECK='TRUE';
      ALLOW_CONNECT='TRUE';
    'VSS_CR58':
      PIN_NUMBER='(0,0,0,0,0,0,0,0,0,0,0,0,0,0,0,0,0,0,0,0,0,0,0,0,0,0,0,0,0,0,0,0,0,0,0,0,0,0,CR58,0)';
      PINUSE='POWER';
      NO_LOAD_CHECK='Both';
      NO_IO_CHECK='Both';
      NO_ASSERT_CHECK='TRUE';
      NO_DIR_CHECK='TRUE';
      ALLOW_CONNECT='TRUE';
    'VSS_CR75':
      PIN_NUMBER='(0,0,0,0,0,0,0,0,0,0,0,0,0,0,0,0,0,0,0,0,0,0,0,0,0,0,0,0,0,0,0,0,0,0,0,0,0,0,CR75,0)';
      PINUSE='POWER';
      NO_LOAD_CHECK='Both';
      NO_IO_CHECK='Both';
      NO_ASSERT_CHECK='TRUE';
      NO_DIR_CHECK='TRUE';
      ALLOW_CONNECT='TRUE';
    'VSS_CT3':
      PIN_NUMBER='(0,0,0,0,0,0,0,0,0,0,0,0,0,0,0,0,0,0,0,0,0,0,0,0,0,0,0,0,0,0,0,0,0,0,0,0,0,0,CT3,0)';
      PINUSE='POWER';
      NO_LOAD_CHECK='Both';
      NO_IO_CHECK='Both';
      NO_ASSERT_CHECK='TRUE';
      NO_DIR_CHECK='TRUE';
      ALLOW_CONNECT='TRUE';
    'VSS_CT8':
      PIN_NUMBER='(0,0,0,0,0,0,0,0,0,0,0,0,0,0,0,0,0,0,0,0,0,0,0,0,0,0,0,0,0,0,0,0,0,0,0,0,0,0,CT8,0)';
      PINUSE='POWER';
      NO_LOAD_CHECK='Both';
      NO_IO_CHECK='Both';
      NO_ASSERT_CHECK='TRUE';
      NO_DIR_CHECK='TRUE';
      ALLOW_CONNECT='TRUE';
    'VSS_CT10':
      PIN_NUMBER='(0,0,0,0,0,0,0,0,0,0,0,0,0,0,0,0,0,0,0,0,0,0,0,0,0,0,0,0,0,0,0,0,0,0,0,0,0,0,CT10,0)';
      PINUSE='POWER';
      NO_LOAD_CHECK='Both';
      NO_IO_CHECK='Both';
      NO_ASSERT_CHECK='TRUE';
      NO_DIR_CHECK='TRUE';
      ALLOW_CONNECT='TRUE';
    'VSS_CT15':
      PIN_NUMBER='(0,0,0,0,0,0,0,0,0,0,0,0,0,0,0,0,0,0,0,0,0,0,0,0,0,0,0,0,0,0,0,0,0,0,0,0,0,0,CT15,0)';
      PINUSE='POWER';
      NO_LOAD_CHECK='Both';
      NO_IO_CHECK='Both';
      NO_ASSERT_CHECK='TRUE';
      NO_DIR_CHECK='TRUE';
      ALLOW_CONNECT='TRUE';
    'VSS_CT48':
      PIN_NUMBER='(0,0,0,0,0,0,0,0,0,0,0,0,0,0,0,0,0,0,0,0,0,0,0,0,0,0,0,0,0,0,0,0,0,0,0,0,0,0,CT48,0)';
      PINUSE='POWER';
      NO_LOAD_CHECK='Both';
      NO_IO_CHECK='Both';
      NO_ASSERT_CHECK='TRUE';
      NO_DIR_CHECK='TRUE';
      ALLOW_CONNECT='TRUE';
    'VSS_CT73':
      PIN_NUMBER='(0,0,0,0,0,0,0,0,0,0,0,0,0,0,0,0,0,0,0,0,0,0,0,0,0,0,0,0,0,0,0,0,0,0,0,0,0,0,CT73,0)';
      PINUSE='POWER';
      NO_LOAD_CHECK='Both';
      NO_IO_CHECK='Both';
      NO_ASSERT_CHECK='TRUE';
      NO_DIR_CHECK='TRUE';
      ALLOW_CONNECT='TRUE';
    'VSS_CU1':
      PIN_NUMBER='(0,0,0,0,0,0,0,0,0,0,0,0,0,0,0,0,0,0,0,0,0,0,0,0,0,0,0,0,0,0,0,0,0,0,0,0,0,0,CU1,0)';
      PINUSE='POWER';
      NO_LOAD_CHECK='Both';
      NO_IO_CHECK='Both';
      NO_ASSERT_CHECK='TRUE';
      NO_DIR_CHECK='TRUE';
      ALLOW_CONNECT='TRUE';
    'VSS_CU22':
      PIN_NUMBER='(0,0,0,0,0,0,0,0,0,0,0,0,0,0,0,0,0,0,0,0,0,0,0,0,0,0,0,0,0,0,0,0,0,0,0,0,0,0,CU22,0)';
      PINUSE='POWER';
      NO_LOAD_CHECK='Both';
      NO_IO_CHECK='Both';
      NO_ASSERT_CHECK='TRUE';
      NO_DIR_CHECK='TRUE';
      ALLOW_CONNECT='TRUE';
    'VSS_CU25':
      PIN_NUMBER='(0,0,0,0,0,0,0,0,0,0,0,0,0,0,0,0,0,0,0,0,0,0,0,0,0,0,0,0,0,0,0,0,0,0,0,0,0,0,CU25,0)';
      PINUSE='POWER';
      NO_LOAD_CHECK='Both';
      NO_IO_CHECK='Both';
      NO_ASSERT_CHECK='TRUE';
      NO_DIR_CHECK='TRUE';
      ALLOW_CONNECT='TRUE';
    'VSS_CU28':
      PIN_NUMBER='(0,0,0,0,0,0,0,0,0,0,0,0,0,0,0,0,0,0,0,0,0,0,0,0,0,0,0,0,0,0,0,0,0,0,0,0,0,0,CU28,0)';
      PINUSE='POWER';
      NO_LOAD_CHECK='Both';
      NO_IO_CHECK='Both';
      NO_ASSERT_CHECK='TRUE';
      NO_DIR_CHECK='TRUE';
      ALLOW_CONNECT='TRUE';
    'VSS_CU56':
      PIN_NUMBER='(0,0,0,0,0,0,0,0,0,0,0,0,0,0,0,0,0,0,0,0,0,0,0,0,0,0,0,0,0,0,0,0,0,0,0,0,0,0,CU56,0)';
      PINUSE='POWER';
      NO_LOAD_CHECK='Both';
      NO_IO_CHECK='Both';
      NO_ASSERT_CHECK='TRUE';
      NO_DIR_CHECK='TRUE';
      ALLOW_CONNECT='TRUE';
    'VSS_CU61':
      PIN_NUMBER='(0,0,0,0,0,0,0,0,0,0,0,0,0,0,0,0,0,0,0,0,0,0,0,0,0,0,0,0,0,0,0,0,0,0,0,0,0,0,CU61,0)';
      PINUSE='POWER';
      NO_LOAD_CHECK='Both';
      NO_IO_CHECK='Both';
      NO_ASSERT_CHECK='TRUE';
      NO_DIR_CHECK='TRUE';
      ALLOW_CONNECT='TRUE';
    'VSS_CU63':
      PIN_NUMBER='(0,0,0,0,0,0,0,0,0,0,0,0,0,0,0,0,0,0,0,0,0,0,0,0,0,0,0,0,0,0,0,0,0,0,0,0,0,0,CU63,0)';
      PINUSE='POWER';
      NO_LOAD_CHECK='Both';
      NO_IO_CHECK='Both';
      NO_ASSERT_CHECK='TRUE';
      NO_DIR_CHECK='TRUE';
      ALLOW_CONNECT='TRUE';
    'VSS_CV5':
      PIN_NUMBER='(0,0,0,0,0,0,0,0,0,0,0,0,0,0,0,0,0,0,0,0,0,0,0,0,0,0,0,0,0,0,0,0,0,0,0,0,0,0,CV5,0)';
      PINUSE='POWER';
      NO_LOAD_CHECK='Both';
      NO_IO_CHECK='Both';
      NO_ASSERT_CHECK='TRUE';
      NO_DIR_CHECK='TRUE';
      ALLOW_CONNECT='TRUE';
    'VSS_CV8':
      PIN_NUMBER='(0,0,0,0,0,0,0,0,0,0,0,0,0,0,0,0,0,0,0,0,0,0,0,0,0,0,0,0,0,0,0,0,0,0,0,0,0,0,CV8,0)';
      PINUSE='POWER';
      NO_LOAD_CHECK='Both';
      NO_IO_CHECK='Both';
      NO_ASSERT_CHECK='TRUE';
      NO_DIR_CHECK='TRUE';
      ALLOW_CONNECT='TRUE';
    'VSS_CV10':
      PIN_NUMBER='(0,0,0,0,0,0,0,0,0,0,0,0,0,0,0,0,0,0,0,0,0,0,0,0,0,0,0,0,0,0,0,0,0,0,0,0,0,0,CV10,0)';
      PINUSE='POWER';
      NO_LOAD_CHECK='Both';
      NO_IO_CHECK='Both';
      NO_ASSERT_CHECK='TRUE';
      NO_DIR_CHECK='TRUE';
      ALLOW_CONNECT='TRUE';
    'VSS_CV12':
      PIN_NUMBER='(0,0,0,0,0,0,0,0,0,0,0,0,0,0,0,0,0,0,0,0,0,0,0,0,0,0,0,0,0,0,0,0,0,0,0,0,0,0,CV12,0)';
      PINUSE='POWER';
      NO_LOAD_CHECK='Both';
      NO_IO_CHECK='Both';
      NO_ASSERT_CHECK='TRUE';
      NO_DIR_CHECK='TRUE';
      ALLOW_CONNECT='TRUE';
    'VSS_CV15':
      PIN_NUMBER='(0,0,0,0,0,0,0,0,0,0,0,0,0,0,0,0,0,0,0,0,0,0,0,0,0,0,0,0,0,0,0,0,0,0,0,0,0,0,CV15,0)';
      PINUSE='POWER';
      NO_LOAD_CHECK='Both';
      NO_IO_CHECK='Both';
      NO_ASSERT_CHECK='TRUE';
      NO_DIR_CHECK='TRUE';
      ALLOW_CONNECT='TRUE';
    'VSS_CV34':
      PIN_NUMBER='(0,0,0,0,0,0,0,0,0,0,0,0,0,0,0,0,0,0,0,0,0,0,0,0,0,0,0,0,0,0,0,0,0,0,0,0,0,0,CV34,0)';
      PINUSE='POWER';
      NO_LOAD_CHECK='Both';
      NO_IO_CHECK='Both';
      NO_ASSERT_CHECK='TRUE';
      NO_DIR_CHECK='TRUE';
      ALLOW_CONNECT='TRUE';
    'VSS_CV37':
      PIN_NUMBER='(0,0,0,0,0,0,0,0,0,0,0,0,0,0,0,0,0,0,0,0,0,0,0,0,0,0,0,0,0,0,0,0,0,0,0,0,0,0,CV37,0)';
      PINUSE='POWER';
      NO_LOAD_CHECK='Both';
      NO_IO_CHECK='Both';
      NO_ASSERT_CHECK='TRUE';
      NO_DIR_CHECK='TRUE';
      ALLOW_CONNECT='TRUE';
    'VSS_CV39':
      PIN_NUMBER='(0,0,0,0,0,0,0,0,0,0,0,0,0,0,0,0,0,0,0,0,0,0,0,0,0,0,0,0,0,0,0,0,0,0,0,0,0,0,CV39,0)';
      PINUSE='POWER';
      NO_LOAD_CHECK='Both';
      NO_IO_CHECK='Both';
      NO_ASSERT_CHECK='TRUE';
      NO_DIR_CHECK='TRUE';
      ALLOW_CONNECT='TRUE';
    'VSS_CV42':
      PIN_NUMBER='(0,0,0,0,0,0,0,0,0,0,0,0,0,0,0,0,0,0,0,0,0,0,0,0,0,0,0,0,0,0,0,0,0,0,0,0,0,0,CV42,0)';
      PINUSE='POWER';
      NO_LOAD_CHECK='Both';
      NO_IO_CHECK='Both';
      NO_ASSERT_CHECK='TRUE';
      NO_DIR_CHECK='TRUE';
      ALLOW_CONNECT='TRUE';
    'VSS_CV45':
      PIN_NUMBER='(0,0,0,0,0,0,0,0,0,0,0,0,0,0,0,0,0,0,0,0,0,0,0,0,0,0,0,0,0,0,0,0,0,0,0,0,0,0,CV45,0)';
      PINUSE='POWER';
      NO_LOAD_CHECK='Both';
      NO_IO_CHECK='Both';
      NO_ASSERT_CHECK='TRUE';
      NO_DIR_CHECK='TRUE';
      ALLOW_CONNECT='TRUE';
    'VSS_CV64':
      PIN_NUMBER='(0,0,0,0,0,0,0,0,0,0,0,0,0,0,0,0,0,0,0,0,0,0,0,0,0,0,0,0,0,0,0,0,0,0,0,0,0,0,CV64,0)';
      PINUSE='POWER';
      NO_LOAD_CHECK='Both';
      NO_IO_CHECK='Both';
      NO_ASSERT_CHECK='TRUE';
      NO_DIR_CHECK='TRUE';
      ALLOW_CONNECT='TRUE';
    'VSS_CV66':
      PIN_NUMBER='(0,0,0,0,0,0,0,0,0,0,0,0,0,0,0,0,0,0,0,0,0,0,0,0,0,0,0,0,0,0,0,0,0,0,0,0,0,0,CV66,0)';
      PINUSE='POWER';
      NO_LOAD_CHECK='Both';
      NO_IO_CHECK='Both';
      NO_ASSERT_CHECK='TRUE';
      NO_DIR_CHECK='TRUE';
      ALLOW_CONNECT='TRUE';
    'VSS_CV68':
      PIN_NUMBER='(0,0,0,0,0,0,0,0,0,0,0,0,0,0,0,0,0,0,0,0,0,0,0,0,0,0,0,0,0,0,0,0,0,0,0,0,0,0,CV68,0)';
      PINUSE='POWER';
      NO_LOAD_CHECK='Both';
      NO_IO_CHECK='Both';
      NO_ASSERT_CHECK='TRUE';
      NO_DIR_CHECK='TRUE';
      ALLOW_CONNECT='TRUE';
    'VSS_CV71':
      PIN_NUMBER='(0,0,0,0,0,0,0,0,0,0,0,0,0,0,0,0,0,0,0,0,0,0,0,0,0,0,0,0,0,0,0,0,0,0,0,0,0,0,CV71,0)';
      PINUSE='POWER';
      NO_LOAD_CHECK='Both';
      NO_IO_CHECK='Both';
      NO_ASSERT_CHECK='TRUE';
      NO_DIR_CHECK='TRUE';
      ALLOW_CONNECT='TRUE';
    'VSS_CV73':
      PIN_NUMBER='(0,0,0,0,0,0,0,0,0,0,0,0,0,0,0,0,0,0,0,0,0,0,0,0,0,0,0,0,0,0,0,0,0,0,0,0,0,0,CV73,0)';
      PINUSE='POWER';
      NO_LOAD_CHECK='Both';
      NO_IO_CHECK='Both';
      NO_ASSERT_CHECK='TRUE';
      NO_DIR_CHECK='TRUE';
      ALLOW_CONNECT='TRUE';
    'VSS_CW22':
      PIN_NUMBER='(0,0,0,0,0,0,0,0,0,0,0,0,0,0,0,0,0,0,0,0,0,0,0,0,0,0,0,0,0,0,0,0,0,0,0,0,0,0,CW22,0)';
      PINUSE='POWER';
      NO_LOAD_CHECK='Both';
      NO_IO_CHECK='Both';
      NO_ASSERT_CHECK='TRUE';
      NO_DIR_CHECK='TRUE';
      ALLOW_CONNECT='TRUE';
    'VSS_CW25':
      PIN_NUMBER='(0,0,0,0,0,0,0,0,0,0,0,0,0,0,0,0,0,0,0,0,0,0,0,0,0,0,0,0,0,0,0,0,0,0,0,0,0,0,CW25,0)';
      PINUSE='POWER';
      NO_LOAD_CHECK='Both';
      NO_IO_CHECK='Both';
      NO_ASSERT_CHECK='TRUE';
      NO_DIR_CHECK='TRUE';
      ALLOW_CONNECT='TRUE';
    'VSS_CW28':
      PIN_NUMBER='(0,0,0,0,0,0,0,0,0,0,0,0,0,0,0,0,0,0,0,0,0,0,0,0,0,0,0,0,0,0,0,0,0,0,0,0,0,0,CW28,0)';
      PINUSE='POWER';
      NO_LOAD_CHECK='Both';
      NO_IO_CHECK='Both';
      NO_ASSERT_CHECK='TRUE';
      NO_DIR_CHECK='TRUE';
      ALLOW_CONNECT='TRUE';
    'VSS_CW31':
      PIN_NUMBER='(0,0,0,0,0,0,0,0,0,0,0,0,0,0,0,0,0,0,0,0,0,0,0,0,0,0,0,0,0,0,0,0,0,0,0,0,0,0,CW31,0)';
      PINUSE='POWER';
      NO_LOAD_CHECK='Both';
      NO_IO_CHECK='Both';
      NO_ASSERT_CHECK='TRUE';
      NO_DIR_CHECK='TRUE';
      ALLOW_CONNECT='TRUE';
    'VSS_CW34':
      PIN_NUMBER='(0,0,0,0,0,0,0,0,0,0,0,0,0,0,0,0,0,0,0,0,0,0,0,0,0,0,0,0,0,0,0,0,0,0,0,0,0,0,CW34,0)';
      PINUSE='POWER';
      NO_LOAD_CHECK='Both';
      NO_IO_CHECK='Both';
      NO_ASSERT_CHECK='TRUE';
      NO_DIR_CHECK='TRUE';
      ALLOW_CONNECT='TRUE';
    'VSS_CY32':
      PIN_NUMBER='(0,0,0,0,0,0,0,0,0,0,0,0,0,0,0,0,0,0,0,0,0,0,0,0,0,0,0,0,0,0,0,0,0,0,0,0,0,0,CY32,0)';
      PINUSE='POWER';
      NO_LOAD_CHECK='Both';
      NO_IO_CHECK='Both';
      NO_ASSERT_CHECK='TRUE';
      NO_DIR_CHECK='TRUE';
      ALLOW_CONNECT='TRUE';
    'VSS_CY47':
      PIN_NUMBER='(0,0,0,0,0,0,0,0,0,0,0,0,0,0,0,0,0,0,0,0,0,0,0,0,0,0,0,0,0,0,0,0,0,0,0,0,0,0,CY47,0)';
      PINUSE='POWER';
      NO_LOAD_CHECK='Both';
      NO_IO_CHECK='Both';
      NO_ASSERT_CHECK='TRUE';
      NO_DIR_CHECK='TRUE';
      ALLOW_CONNECT='TRUE';
    'VSS_CY48':
      PIN_NUMBER='(0,0,0,0,0,0,0,0,0,0,0,0,0,0,0,0,0,0,0,0,0,0,0,0,0,0,0,0,0,0,0,0,0,0,0,0,0,0,CY48,0)';
      PINUSE='POWER';
      NO_LOAD_CHECK='Both';
      NO_IO_CHECK='Both';
      NO_ASSERT_CHECK='TRUE';
      NO_DIR_CHECK='TRUE';
      ALLOW_CONNECT='TRUE';
    'VSS_CY64':
      PIN_NUMBER='(0,0,0,0,0,0,0,0,0,0,0,0,0,0,0,0,0,0,0,0,0,0,0,0,0,0,0,0,0,0,0,0,0,0,0,0,0,0,CY64,0)';
      PINUSE='POWER';
      NO_LOAD_CHECK='Both';
      NO_IO_CHECK='Both';
      NO_ASSERT_CHECK='TRUE';
      NO_DIR_CHECK='TRUE';
      ALLOW_CONNECT='TRUE';
    'VSS_CY66':
      PIN_NUMBER='(0,0,0,0,0,0,0,0,0,0,0,0,0,0,0,0,0,0,0,0,0,0,0,0,0,0,0,0,0,0,0,0,0,0,0,0,0,0,CY66,0)';
      PINUSE='POWER';
      NO_LOAD_CHECK='Both';
      NO_IO_CHECK='Both';
      NO_ASSERT_CHECK='TRUE';
      NO_DIR_CHECK='TRUE';
      ALLOW_CONNECT='TRUE';
    'VSS_CY68':
      PIN_NUMBER='(0,0,0,0,0,0,0,0,0,0,0,0,0,0,0,0,0,0,0,0,0,0,0,0,0,0,0,0,0,0,0,0,0,0,0,0,0,0,CY68,0)';
      PINUSE='POWER';
      NO_LOAD_CHECK='Both';
      NO_IO_CHECK='Both';
      NO_ASSERT_CHECK='TRUE';
      NO_DIR_CHECK='TRUE';
      ALLOW_CONNECT='TRUE';
    'VSS_DA13':
      PIN_NUMBER='(0,0,0,0,0,0,0,0,0,0,0,0,0,0,0,0,0,0,0,0,0,0,0,0,0,0,0,0,0,0,0,0,0,0,0,0,0,0,DA13,0)';
      PINUSE='POWER';
      NO_LOAD_CHECK='Both';
      NO_IO_CHECK='Both';
      NO_ASSERT_CHECK='TRUE';
      NO_DIR_CHECK='TRUE';
      ALLOW_CONNECT='TRUE';
    'VSS_DA15':
      PIN_NUMBER='(0,0,0,0,0,0,0,0,0,0,0,0,0,0,0,0,0,0,0,0,0,0,0,0,0,0,0,0,0,0,0,0,0,0,0,0,0,0,DA15,0)';
      PINUSE='POWER';
      NO_LOAD_CHECK='Both';
      NO_IO_CHECK='Both';
      NO_ASSERT_CHECK='TRUE';
      NO_DIR_CHECK='TRUE';
      ALLOW_CONNECT='TRUE';
    'VSS_DA18':
      PIN_NUMBER='(0,0,0,0,0,0,0,0,0,0,0,0,0,0,0,0,0,0,0,0,0,0,0,0,0,0,0,0,0,0,0,0,0,0,0,0,0,0,DA18,0)';
      PINUSE='POWER';
      NO_LOAD_CHECK='Both';
      NO_IO_CHECK='Both';
      NO_ASSERT_CHECK='TRUE';
      NO_DIR_CHECK='TRUE';
      ALLOW_CONNECT='TRUE';
    'VSS_DA20':
      PIN_NUMBER='(0,0,0,0,0,0,0,0,0,0,0,0,0,0,0,0,0,0,0,0,0,0,0,0,0,0,0,0,0,0,0,0,0,0,0,0,0,0,DA20,0)';
      PINUSE='POWER';
      NO_LOAD_CHECK='Both';
      NO_IO_CHECK='Both';
      NO_ASSERT_CHECK='TRUE';
      NO_DIR_CHECK='TRUE';
      ALLOW_CONNECT='TRUE';
    'VSS_DA45':
      PIN_NUMBER='(0,0,0,0,0,0,0,0,0,0,0,0,0,0,0,0,0,0,0,0,0,0,0,0,0,0,0,0,0,0,0,0,0,0,0,0,0,0,DA45,0)';
      PINUSE='POWER';
      NO_LOAD_CHECK='Both';
      NO_IO_CHECK='Both';
      NO_ASSERT_CHECK='TRUE';
      NO_DIR_CHECK='TRUE';
      ALLOW_CONNECT='TRUE';
    'VSS_DA48':
      PIN_NUMBER='(0,0,0,0,0,0,0,0,0,0,0,0,0,0,0,0,0,0,0,0,0,0,0,0,0,0,0,0,0,0,0,0,0,0,0,0,0,0,DA48,0)';
      PINUSE='POWER';
      NO_LOAD_CHECK='Both';
      NO_IO_CHECK='Both';
      NO_ASSERT_CHECK='TRUE';
      NO_DIR_CHECK='TRUE';
      ALLOW_CONNECT='TRUE';
    'VSS_DA51':
      PIN_NUMBER='(0,0,0,0,0,0,0,0,0,0,0,0,0,0,0,0,0,0,0,0,0,0,0,0,0,0,0,0,0,0,0,0,0,0,0,0,0,0,DA51,0)';
      PINUSE='POWER';
      NO_LOAD_CHECK='Both';
      NO_IO_CHECK='Both';
      NO_ASSERT_CHECK='TRUE';
      NO_DIR_CHECK='TRUE';
      ALLOW_CONNECT='TRUE';
    'VSS_DA54':
      PIN_NUMBER='(0,0,0,0,0,0,0,0,0,0,0,0,0,0,0,0,0,0,0,0,0,0,0,0,0,0,0,0,0,0,0,0,0,0,0,0,0,0,DA54,0)';
      PINUSE='POWER';
      NO_LOAD_CHECK='Both';
      NO_IO_CHECK='Both';
      NO_ASSERT_CHECK='TRUE';
      NO_DIR_CHECK='TRUE';
      ALLOW_CONNECT='TRUE';
    'VSS_CP25':
      PIN_NUMBER='(0,0,0,0,0,0,0,0,0,0,0,0,0,0,0,0,0,0,0,0,0,0,0,0,0,0,0,0,0,0,0,0,0,0,0,0,0,0,CP25,0)';
      PINUSE='POWER';
      NO_LOAD_CHECK='Both';
      NO_IO_CHECK='Both';
      NO_ASSERT_CHECK='TRUE';
      NO_DIR_CHECK='TRUE';
      ALLOW_CONNECT='TRUE';
    'VSS_CP28':
      PIN_NUMBER='(0,0,0,0,0,0,0,0,0,0,0,0,0,0,0,0,0,0,0,0,0,0,0,0,0,0,0,0,0,0,0,0,0,0,0,0,0,0,CP28,0)';
      PINUSE='POWER';
      NO_LOAD_CHECK='Both';
      NO_IO_CHECK='Both';
      NO_ASSERT_CHECK='TRUE';
      NO_DIR_CHECK='TRUE';
      ALLOW_CONNECT='TRUE';
    'VSS_CP31':
      PIN_NUMBER='(0,0,0,0,0,0,0,0,0,0,0,0,0,0,0,0,0,0,0,0,0,0,0,0,0,0,0,0,0,0,0,0,0,0,0,0,0,0,CP31,0)';
      PINUSE='POWER';
      NO_LOAD_CHECK='Both';
      NO_IO_CHECK='Both';
      NO_ASSERT_CHECK='TRUE';
      NO_DIR_CHECK='TRUE';
      ALLOW_CONNECT='TRUE';
    'VSS_CP34':
      PIN_NUMBER='(0,0,0,0,0,0,0,0,0,0,0,0,0,0,0,0,0,0,0,0,0,0,0,0,0,0,0,0,0,0,0,0,0,0,0,0,0,0,CP34,0)';
      PINUSE='POWER';
      NO_LOAD_CHECK='Both';
      NO_IO_CHECK='Both';
      NO_ASSERT_CHECK='TRUE';
      NO_DIR_CHECK='TRUE';
      ALLOW_CONNECT='TRUE';
    'VSS_CP37':
      PIN_NUMBER='(0,0,0,0,0,0,0,0,0,0,0,0,0,0,0,0,0,0,0,0,0,0,0,0,0,0,0,0,0,0,0,0,0,0,0,0,0,0,CP37,0)';
      PINUSE='POWER';
      NO_LOAD_CHECK='Both';
      NO_IO_CHECK='Both';
      NO_ASSERT_CHECK='TRUE';
      NO_DIR_CHECK='TRUE';
      ALLOW_CONNECT='TRUE';
    'VSS_CP39':
      PIN_NUMBER='(0,0,0,0,0,0,0,0,0,0,0,0,0,0,0,0,0,0,0,0,0,0,0,0,0,0,0,0,0,0,0,0,0,0,0,0,0,0,CP39,0)';
      PINUSE='POWER';
      NO_LOAD_CHECK='Both';
      NO_IO_CHECK='Both';
      NO_ASSERT_CHECK='TRUE';
      NO_DIR_CHECK='TRUE';
      ALLOW_CONNECT='TRUE';
    'VSS_CP57':
      PIN_NUMBER='(0,0,0,0,0,0,0,0,0,0,0,0,0,0,0,0,0,0,0,0,0,0,0,0,0,0,0,0,0,0,0,0,0,0,0,0,0,0,CP57,0)';
      PINUSE='POWER';
      NO_LOAD_CHECK='Both';
      NO_IO_CHECK='Both';
      NO_ASSERT_CHECK='TRUE';
      NO_DIR_CHECK='TRUE';
      ALLOW_CONNECT='TRUE';
    'VSS_CP59':
      PIN_NUMBER='(0,0,0,0,0,0,0,0,0,0,0,0,0,0,0,0,0,0,0,0,0,0,0,0,0,0,0,0,0,0,0,0,0,0,0,0,0,0,CP59,0)';
      PINUSE='POWER';
      NO_LOAD_CHECK='Both';
      NO_IO_CHECK='Both';
      NO_ASSERT_CHECK='TRUE';
      NO_DIR_CHECK='TRUE';
      ALLOW_CONNECT='TRUE';
    'VSS_CP61':
      PIN_NUMBER='(0,0,0,0,0,0,0,0,0,0,0,0,0,0,0,0,0,0,0,0,0,0,0,0,0,0,0,0,0,0,0,0,0,0,0,0,0,0,CP61,0)';
      PINUSE='POWER';
      NO_LOAD_CHECK='Both';
      NO_IO_CHECK='Both';
      NO_ASSERT_CHECK='TRUE';
      NO_DIR_CHECK='TRUE';
      ALLOW_CONNECT='TRUE';
    'VSS_CP64':
      PIN_NUMBER='(0,0,0,0,0,0,0,0,0,0,0,0,0,0,0,0,0,0,0,0,0,0,0,0,0,0,0,0,0,0,0,0,0,0,0,0,0,0,CP64,0)';
      PINUSE='POWER';
      NO_LOAD_CHECK='Both';
      NO_IO_CHECK='Both';
      NO_ASSERT_CHECK='TRUE';
      NO_DIR_CHECK='TRUE';
      ALLOW_CONNECT='TRUE';
    'VSS_CP66':
      PIN_NUMBER='(0,0,0,0,0,0,0,0,0,0,0,0,0,0,0,0,0,0,0,0,0,0,0,0,0,0,0,0,0,0,0,0,0,0,0,0,0,0,CP66,0)';
      PINUSE='POWER';
      NO_LOAD_CHECK='Both';
      NO_IO_CHECK='Both';
      NO_ASSERT_CHECK='TRUE';
      NO_DIR_CHECK='TRUE';
      ALLOW_CONNECT='TRUE';
    'VSS_CP68':
      PIN_NUMBER='(0,0,0,0,0,0,0,0,0,0,0,0,0,0,0,0,0,0,0,0,0,0,0,0,0,0,0,0,0,0,0,0,0,0,0,0,0,0,CP68,0)';
      PINUSE='POWER';
      NO_LOAD_CHECK='Both';
      NO_IO_CHECK='Both';
      NO_ASSERT_CHECK='TRUE';
      NO_DIR_CHECK='TRUE';
      ALLOW_CONNECT='TRUE';
    'VSS_CR8':
      PIN_NUMBER='(0,0,0,0,0,0,0,0,0,0,0,0,0,0,0,0,0,0,0,0,0,0,0,0,0,0,0,0,0,0,0,0,0,0,0,0,0,0,CR8,0)';
      PINUSE='POWER';
      NO_LOAD_CHECK='Both';
      NO_IO_CHECK='Both';
      NO_ASSERT_CHECK='TRUE';
      NO_DIR_CHECK='TRUE';
      ALLOW_CONNECT='TRUE';
    'VSS_CR11':
      PIN_NUMBER='(0,0,0,0,0,0,0,0,0,0,0,0,0,0,0,0,0,0,0,0,0,0,0,0,0,0,0,0,0,0,0,0,0,0,0,0,0,0,CR11,0)';
      PINUSE='POWER';
      NO_LOAD_CHECK='Both';
      NO_IO_CHECK='Both';
      NO_ASSERT_CHECK='TRUE';
      NO_DIR_CHECK='TRUE';
      ALLOW_CONNECT='TRUE';
    'VSS_CR13':
      PIN_NUMBER='(0,0,0,0,0,0,0,0,0,0,0,0,0,0,0,0,0,0,0,0,0,0,0,0,0,0,0,0,0,0,0,0,0,0,0,0,0,0,CR13,0)';
      PINUSE='POWER';
      NO_LOAD_CHECK='Both';
      NO_IO_CHECK='Both';
      NO_ASSERT_CHECK='TRUE';
      NO_DIR_CHECK='TRUE';
      ALLOW_CONNECT='TRUE';
    'VSS_CR15':
      PIN_NUMBER='(0,0,0,0,0,0,0,0,0,0,0,0,0,0,0,0,0,0,0,0,0,0,0,0,0,0,0,0,0,0,0,0,0,0,0,0,0,0,CR15,0)';
      PINUSE='POWER';
      NO_LOAD_CHECK='Both';
      NO_IO_CHECK='Both';
      NO_ASSERT_CHECK='TRUE';
      NO_DIR_CHECK='TRUE';
      ALLOW_CONNECT='TRUE';
    'VSS_CR18':
      PIN_NUMBER='(0,0,0,0,0,0,0,0,0,0,0,0,0,0,0,0,0,0,0,0,0,0,0,0,0,0,0,0,0,0,0,0,0,0,0,0,0,0,CR18,0)';
      PINUSE='POWER';
      NO_LOAD_CHECK='Both';
      NO_IO_CHECK='Both';
      NO_ASSERT_CHECK='TRUE';
      NO_DIR_CHECK='TRUE';
      ALLOW_CONNECT='TRUE';
    'VSS_CR20':
      PIN_NUMBER='(0,0,0,0,0,0,0,0,0,0,0,0,0,0,0,0,0,0,0,0,0,0,0,0,0,0,0,0,0,0,0,0,0,0,0,0,0,0,CR20,0)';
      PINUSE='POWER';
      NO_LOAD_CHECK='Both';
      NO_IO_CHECK='Both';
      NO_ASSERT_CHECK='TRUE';
      NO_DIR_CHECK='TRUE';
      ALLOW_CONNECT='TRUE';
    'VSS_CR35':
      PIN_NUMBER='(0,0,0,0,0,0,0,0,0,0,0,0,0,0,0,0,0,0,0,0,0,0,0,0,0,0,0,0,0,0,0,0,0,0,0,0,0,0,CR35,0)';
      PINUSE='POWER';
      NO_LOAD_CHECK='Both';
      NO_IO_CHECK='Both';
      NO_ASSERT_CHECK='TRUE';
      NO_DIR_CHECK='TRUE';
      ALLOW_CONNECT='TRUE';
    'VSS_CR36':
      PIN_NUMBER='(0,0,0,0,0,0,0,0,0,0,0,0,0,0,0,0,0,0,0,0,0,0,0,0,0,0,0,0,0,0,0,0,0,0,0,0,0,0,CR36,0)';
      PINUSE='POWER';
      NO_LOAD_CHECK='Both';
      NO_IO_CHECK='Both';
      NO_ASSERT_CHECK='TRUE';
      NO_DIR_CHECK='TRUE';
      ALLOW_CONNECT='TRUE';
    'VSS_CR40':
      PIN_NUMBER='(0,0,0,0,0,0,0,0,0,0,0,0,0,0,0,0,0,0,0,0,0,0,0,0,0,0,0,0,0,0,0,0,0,0,0,0,0,0,CR40,0)';
      PINUSE='POWER';
      NO_LOAD_CHECK='Both';
      NO_IO_CHECK='Both';
      NO_ASSERT_CHECK='TRUE';
      NO_DIR_CHECK='TRUE';
      ALLOW_CONNECT='TRUE';
    'VSS_CR41':
      PIN_NUMBER='(0,0,0,0,0,0,0,0,0,0,0,0,0,0,0,0,0,0,0,0,0,0,0,0,0,0,0,0,0,0,0,0,0,0,0,0,0,0,CR41,0)';
      PINUSE='POWER';
      NO_LOAD_CHECK='Both';
      NO_IO_CHECK='Both';
      NO_ASSERT_CHECK='TRUE';
      NO_DIR_CHECK='TRUE';
      ALLOW_CONNECT='TRUE';
    'VSS_CR42':
      PIN_NUMBER='(0,0,0,0,0,0,0,0,0,0,0,0,0,0,0,0,0,0,0,0,0,0,0,0,0,0,0,0,0,0,0,0,0,0,0,0,0,0,CR42,0)';
      PINUSE='POWER';
      NO_LOAD_CHECK='Both';
      NO_IO_CHECK='Both';
      NO_ASSERT_CHECK='TRUE';
      NO_DIR_CHECK='TRUE';
      ALLOW_CONNECT='TRUE';
    'VSS_CR45':
      PIN_NUMBER='(0,0,0,0,0,0,0,0,0,0,0,0,0,0,0,0,0,0,0,0,0,0,0,0,0,0,0,0,0,0,0,0,0,0,0,0,0,0,CR45,0)';
      PINUSE='POWER';
      NO_LOAD_CHECK='Both';
      NO_IO_CHECK='Both';
      NO_ASSERT_CHECK='TRUE';
      NO_DIR_CHECK='TRUE';
      ALLOW_CONNECT='TRUE';
    'VSS_CR61':
      PIN_NUMBER='(0,0,0,0,0,0,0,0,0,0,0,0,0,0,0,0,0,0,0,0,0,0,0,0,0,0,0,0,0,0,0,0,0,0,0,0,0,0,CR61,0)';
      PINUSE='POWER';
      NO_LOAD_CHECK='Both';
      NO_IO_CHECK='Both';
      NO_ASSERT_CHECK='TRUE';
      NO_DIR_CHECK='TRUE';
      ALLOW_CONNECT='TRUE';
    'VSS_CR63':
      PIN_NUMBER='(0,0,0,0,0,0,0,0,0,0,0,0,0,0,0,0,0,0,0,0,0,0,0,0,0,0,0,0,0,0,0,0,0,0,0,0,0,0,CR63,0)';
      PINUSE='POWER';
      NO_LOAD_CHECK='Both';
      NO_IO_CHECK='Both';
      NO_ASSERT_CHECK='TRUE';
      NO_DIR_CHECK='TRUE';
      ALLOW_CONNECT='TRUE';
    'VSS_CR65':
      PIN_NUMBER='(0,0,0,0,0,0,0,0,0,0,0,0,0,0,0,0,0,0,0,0,0,0,0,0,0,0,0,0,0,0,0,0,0,0,0,0,0,0,CR65,0)';
      PINUSE='POWER';
      NO_LOAD_CHECK='Both';
      NO_IO_CHECK='Both';
      NO_ASSERT_CHECK='TRUE';
      NO_DIR_CHECK='TRUE';
      ALLOW_CONNECT='TRUE';
    'VSS_CR68':
      PIN_NUMBER='(0,0,0,0,0,0,0,0,0,0,0,0,0,0,0,0,0,0,0,0,0,0,0,0,0,0,0,0,0,0,0,0,0,0,0,0,0,0,CR68,0)';
      PINUSE='POWER';
      NO_LOAD_CHECK='Both';
      NO_IO_CHECK='Both';
      NO_ASSERT_CHECK='TRUE';
      NO_DIR_CHECK='TRUE';
      ALLOW_CONNECT='TRUE';
    'VSS_CR70':
      PIN_NUMBER='(0,0,0,0,0,0,0,0,0,0,0,0,0,0,0,0,0,0,0,0,0,0,0,0,0,0,0,0,0,0,0,0,0,0,0,0,0,0,CR70,0)';
      PINUSE='POWER';
      NO_LOAD_CHECK='Both';
      NO_IO_CHECK='Both';
      NO_ASSERT_CHECK='TRUE';
      NO_DIR_CHECK='TRUE';
      ALLOW_CONNECT='TRUE';
    'VSS_CR72':
      PIN_NUMBER='(0,0,0,0,0,0,0,0,0,0,0,0,0,0,0,0,0,0,0,0,0,0,0,0,0,0,0,0,0,0,0,0,0,0,0,0,0,0,CR72,0)';
      PINUSE='POWER';
      NO_LOAD_CHECK='Both';
      NO_IO_CHECK='Both';
      NO_ASSERT_CHECK='TRUE';
      NO_DIR_CHECK='TRUE';
      ALLOW_CONNECT='TRUE';
    'VSS_CT17':
      PIN_NUMBER='(0,0,0,0,0,0,0,0,0,0,0,0,0,0,0,0,0,0,0,0,0,0,0,0,0,0,0,0,0,0,0,0,0,0,0,0,0,0,CT17,0)';
      PINUSE='POWER';
      NO_LOAD_CHECK='Both';
      NO_IO_CHECK='Both';
      NO_ASSERT_CHECK='TRUE';
      NO_DIR_CHECK='TRUE';
      ALLOW_CONNECT='TRUE';
    'VSS_CT23':
      PIN_NUMBER='(0,0,0,0,0,0,0,0,0,0,0,0,0,0,0,0,0,0,0,0,0,0,0,0,0,0,0,0,0,0,0,0,0,0,0,0,0,0,CT23,0)';
      PINUSE='POWER';
      NO_LOAD_CHECK='Both';
      NO_IO_CHECK='Both';
      NO_ASSERT_CHECK='TRUE';
      NO_DIR_CHECK='TRUE';
      ALLOW_CONNECT='TRUE';
    'VSS_CT24':
      PIN_NUMBER='(0,0,0,0,0,0,0,0,0,0,0,0,0,0,0,0,0,0,0,0,0,0,0,0,0,0,0,0,0,0,0,0,0,0,0,0,0,0,CT24,0)';
      PINUSE='POWER';
      NO_LOAD_CHECK='Both';
      NO_IO_CHECK='Both';
      NO_ASSERT_CHECK='TRUE';
      NO_DIR_CHECK='TRUE';
      ALLOW_CONNECT='TRUE';
    'VSS_CT25':
      PIN_NUMBER='(0,0,0,0,0,0,0,0,0,0,0,0,0,0,0,0,0,0,0,0,0,0,0,0,0,0,0,0,0,0,0,0,0,0,0,0,0,0,CT25,0)';
      PINUSE='POWER';
      NO_LOAD_CHECK='Both';
      NO_IO_CHECK='Both';
      NO_ASSERT_CHECK='TRUE';
      NO_DIR_CHECK='TRUE';
      ALLOW_CONNECT='TRUE';
    'VSS_CT26':
      PIN_NUMBER='(0,0,0,0,0,0,0,0,0,0,0,0,0,0,0,0,0,0,0,0,0,0,0,0,0,0,0,0,0,0,0,0,0,0,0,0,0,0,CT26,0)';
      PINUSE='POWER';
      NO_LOAD_CHECK='Both';
      NO_IO_CHECK='Both';
      NO_ASSERT_CHECK='TRUE';
      NO_DIR_CHECK='TRUE';
      ALLOW_CONNECT='TRUE';
    'VSS_CT27':
      PIN_NUMBER='(0,0,0,0,0,0,0,0,0,0,0,0,0,0,0,0,0,0,0,0,0,0,0,0,0,0,0,0,0,0,0,0,0,0,0,0,0,0,CT27,0)';
      PINUSE='POWER';
      NO_LOAD_CHECK='Both';
      NO_IO_CHECK='Both';
      NO_ASSERT_CHECK='TRUE';
      NO_DIR_CHECK='TRUE';
      ALLOW_CONNECT='TRUE';
    'VSS_CT28':
      PIN_NUMBER='(0,0,0,0,0,0,0,0,0,0,0,0,0,0,0,0,0,0,0,0,0,0,0,0,0,0,0,0,0,0,0,0,0,0,0,0,0,0,CT28,0)';
      PINUSE='POWER';
      NO_LOAD_CHECK='Both';
      NO_IO_CHECK='Both';
      NO_ASSERT_CHECK='TRUE';
      NO_DIR_CHECK='TRUE';
      ALLOW_CONNECT='TRUE';
    'VSS_CT29':
      PIN_NUMBER='(0,0,0,0,0,0,0,0,0,0,0,0,0,0,0,0,0,0,0,0,0,0,0,0,0,0,0,0,0,0,0,0,0,0,0,0,0,0,CT29,0)';
      PINUSE='POWER';
      NO_LOAD_CHECK='Both';
      NO_IO_CHECK='Both';
      NO_ASSERT_CHECK='TRUE';
      NO_DIR_CHECK='TRUE';
      ALLOW_CONNECT='TRUE';
    'VSS_CT30':
      PIN_NUMBER='(0,0,0,0,0,0,0,0,0,0,0,0,0,0,0,0,0,0,0,0,0,0,0,0,0,0,0,0,0,0,0,0,0,0,0,0,0,0,CT30,0)';
      PINUSE='POWER';
      NO_LOAD_CHECK='Both';
      NO_IO_CHECK='Both';
      NO_ASSERT_CHECK='TRUE';
      NO_DIR_CHECK='TRUE';
      ALLOW_CONNECT='TRUE';
    'VSS_CT31':
      PIN_NUMBER='(0,0,0,0,0,0,0,0,0,0,0,0,0,0,0,0,0,0,0,0,0,0,0,0,0,0,0,0,0,0,0,0,0,0,0,0,0,0,CT31,0)';
      PINUSE='POWER';
      NO_LOAD_CHECK='Both';
      NO_IO_CHECK='Both';
      NO_ASSERT_CHECK='TRUE';
      NO_DIR_CHECK='TRUE';
      ALLOW_CONNECT='TRUE';
    'VSS_CT32':
      PIN_NUMBER='(0,0,0,0,0,0,0,0,0,0,0,0,0,0,0,0,0,0,0,0,0,0,0,0,0,0,0,0,0,0,0,0,0,0,0,0,0,0,CT32,0)';
      PINUSE='POWER';
      NO_LOAD_CHECK='Both';
      NO_IO_CHECK='Both';
      NO_ASSERT_CHECK='TRUE';
      NO_DIR_CHECK='TRUE';
      ALLOW_CONNECT='TRUE';
    'VSS_CT33':
      PIN_NUMBER='(0,0,0,0,0,0,0,0,0,0,0,0,0,0,0,0,0,0,0,0,0,0,0,0,0,0,0,0,0,0,0,0,0,0,0,0,0,0,CT33,0)';
      PINUSE='POWER';
      NO_LOAD_CHECK='Both';
      NO_IO_CHECK='Both';
      NO_ASSERT_CHECK='TRUE';
      NO_DIR_CHECK='TRUE';
      ALLOW_CONNECT='TRUE';
    'VSS_CT34':
      PIN_NUMBER='(0,0,0,0,0,0,0,0,0,0,0,0,0,0,0,0,0,0,0,0,0,0,0,0,0,0,0,0,0,0,0,0,0,0,0,0,0,0,CT34,0)';
      PINUSE='POWER';
      NO_LOAD_CHECK='Both';
      NO_IO_CHECK='Both';
      NO_ASSERT_CHECK='TRUE';
      NO_DIR_CHECK='TRUE';
      ALLOW_CONNECT='TRUE';
    'VSS_CT37':
      PIN_NUMBER='(0,0,0,0,0,0,0,0,0,0,0,0,0,0,0,0,0,0,0,0,0,0,0,0,0,0,0,0,0,0,0,0,0,0,0,0,0,0,CT37,0)';
      PINUSE='POWER';
      NO_LOAD_CHECK='Both';
      NO_IO_CHECK='Both';
      NO_ASSERT_CHECK='TRUE';
      NO_DIR_CHECK='TRUE';
      ALLOW_CONNECT='TRUE';
    'VSS_CT39':
      PIN_NUMBER='(0,0,0,0,0,0,0,0,0,0,0,0,0,0,0,0,0,0,0,0,0,0,0,0,0,0,0,0,0,0,0,0,0,0,0,0,0,0,CT39,0)';
      PINUSE='POWER';
      NO_LOAD_CHECK='Both';
      NO_IO_CHECK='Both';
      NO_ASSERT_CHECK='TRUE';
      NO_DIR_CHECK='TRUE';
      ALLOW_CONNECT='TRUE';
    'VSS_CT42':
      PIN_NUMBER='(0,0,0,0,0,0,0,0,0,0,0,0,0,0,0,0,0,0,0,0,0,0,0,0,0,0,0,0,0,0,0,0,0,0,0,0,0,0,CT42,0)';
      PINUSE='POWER';
      NO_LOAD_CHECK='Both';
      NO_IO_CHECK='Both';
      NO_ASSERT_CHECK='TRUE';
      NO_DIR_CHECK='TRUE';
      ALLOW_CONNECT='TRUE';
    'VSS_CT43':
      PIN_NUMBER='(0,0,0,0,0,0,0,0,0,0,0,0,0,0,0,0,0,0,0,0,0,0,0,0,0,0,0,0,0,0,0,0,0,0,0,0,0,0,CT43,0)';
      PINUSE='POWER';
      NO_LOAD_CHECK='Both';
      NO_IO_CHECK='Both';
      NO_ASSERT_CHECK='TRUE';
      NO_DIR_CHECK='TRUE';
      ALLOW_CONNECT='TRUE';
    'VSS_CT44':
      PIN_NUMBER='(0,0,0,0,0,0,0,0,0,0,0,0,0,0,0,0,0,0,0,0,0,0,0,0,0,0,0,0,0,0,0,0,0,0,0,0,0,0,CT44,0)';
      PINUSE='POWER';
      NO_LOAD_CHECK='Both';
      NO_IO_CHECK='Both';
      NO_ASSERT_CHECK='TRUE';
      NO_DIR_CHECK='TRUE';
      ALLOW_CONNECT='TRUE';
    'VSS_CT45':
      PIN_NUMBER='(0,0,0,0,0,0,0,0,0,0,0,0,0,0,0,0,0,0,0,0,0,0,0,0,0,0,0,0,0,0,0,0,0,0,0,0,0,0,CT45,0)';
      PINUSE='POWER';
      NO_LOAD_CHECK='Both';
      NO_IO_CHECK='Both';
      NO_ASSERT_CHECK='TRUE';
      NO_DIR_CHECK='TRUE';
      ALLOW_CONNECT='TRUE';
    'VSS_CT46':
      PIN_NUMBER='(0,0,0,0,0,0,0,0,0,0,0,0,0,0,0,0,0,0,0,0,0,0,0,0,0,0,0,0,0,0,0,0,0,0,0,0,0,0,CT46,0)';
      PINUSE='POWER';
      NO_LOAD_CHECK='Both';
      NO_IO_CHECK='Both';
      NO_ASSERT_CHECK='TRUE';
      NO_DIR_CHECK='TRUE';
      ALLOW_CONNECT='TRUE';
    'VSS_CT47':
      PIN_NUMBER='(0,0,0,0,0,0,0,0,0,0,0,0,0,0,0,0,0,0,0,0,0,0,0,0,0,0,0,0,0,0,0,0,0,0,0,0,0,0,CT47,0)';
      PINUSE='POWER';
      NO_LOAD_CHECK='Both';
      NO_IO_CHECK='Both';
      NO_ASSERT_CHECK='TRUE';
      NO_DIR_CHECK='TRUE';
      ALLOW_CONNECT='TRUE';
    'VSS_CT49':
      PIN_NUMBER='(0,0,0,0,0,0,0,0,0,0,0,0,0,0,0,0,0,0,0,0,0,0,0,0,0,0,0,0,0,0,0,0,0,0,0,0,0,0,CT49,0)';
      PINUSE='POWER';
      NO_LOAD_CHECK='Both';
      NO_IO_CHECK='Both';
      NO_ASSERT_CHECK='TRUE';
      NO_DIR_CHECK='TRUE';
      ALLOW_CONNECT='TRUE';
    'VSS_CT50':
      PIN_NUMBER='(0,0,0,0,0,0,0,0,0,0,0,0,0,0,0,0,0,0,0,0,0,0,0,0,0,0,0,0,0,0,0,0,0,0,0,0,0,0,CT50,0)';
      PINUSE='POWER';
      NO_LOAD_CHECK='Both';
      NO_IO_CHECK='Both';
      NO_ASSERT_CHECK='TRUE';
      NO_DIR_CHECK='TRUE';
      ALLOW_CONNECT='TRUE';
    'VSS_CT51':
      PIN_NUMBER='(0,0,0,0,0,0,0,0,0,0,0,0,0,0,0,0,0,0,0,0,0,0,0,0,0,0,0,0,0,0,0,0,0,0,0,0,0,0,CT51,0)';
      PINUSE='POWER';
      NO_LOAD_CHECK='Both';
      NO_IO_CHECK='Both';
      NO_ASSERT_CHECK='TRUE';
      NO_DIR_CHECK='TRUE';
      ALLOW_CONNECT='TRUE';
    'VSS_CT53':
      PIN_NUMBER='(0,0,0,0,0,0,0,0,0,0,0,0,0,0,0,0,0,0,0,0,0,0,0,0,0,0,0,0,0,0,0,0,0,0,0,0,0,0,CT53,0)';
      PINUSE='POWER';
      NO_LOAD_CHECK='Both';
      NO_IO_CHECK='Both';
      NO_ASSERT_CHECK='TRUE';
      NO_DIR_CHECK='TRUE';
      ALLOW_CONNECT='TRUE';
    'VSS_CT59':
      PIN_NUMBER='(0,0,0,0,0,0,0,0,0,0,0,0,0,0,0,0,0,0,0,0,0,0,0,0,0,0,0,0,0,0,0,0,0,0,0,0,0,0,CT59,0)';
      PINUSE='POWER';
      NO_LOAD_CHECK='Both';
      NO_IO_CHECK='Both';
      NO_ASSERT_CHECK='TRUE';
      NO_DIR_CHECK='TRUE';
      ALLOW_CONNECT='TRUE';
    'VSS_CT61':
      PIN_NUMBER='(0,0,0,0,0,0,0,0,0,0,0,0,0,0,0,0,0,0,0,0,0,0,0,0,0,0,0,0,0,0,0,0,0,0,0,0,0,0,CT61,0)';
      PINUSE='POWER';
      NO_LOAD_CHECK='Both';
      NO_IO_CHECK='Both';
      NO_ASSERT_CHECK='TRUE';
      NO_DIR_CHECK='TRUE';
      ALLOW_CONNECT='TRUE';
    'VSS_CT66':
      PIN_NUMBER='(0,0,0,0,0,0,0,0,0,0,0,0,0,0,0,0,0,0,0,0,0,0,0,0,0,0,0,0,0,0,0,0,0,0,0,0,0,0,CT66,0)';
      PINUSE='POWER';
      NO_LOAD_CHECK='Both';
      NO_IO_CHECK='Both';
      NO_ASSERT_CHECK='TRUE';
      NO_DIR_CHECK='TRUE';
      ALLOW_CONNECT='TRUE';
    'VSS_CT68':
      PIN_NUMBER='(0,0,0,0,0,0,0,0,0,0,0,0,0,0,0,0,0,0,0,0,0,0,0,0,0,0,0,0,0,0,0,0,0,0,0,0,0,0,CT68,0)';
      PINUSE='POWER';
      NO_LOAD_CHECK='Both';
      NO_IO_CHECK='Both';
      NO_ASSERT_CHECK='TRUE';
      NO_DIR_CHECK='TRUE';
      ALLOW_CONNECT='TRUE';
    'VSS_CU4':
      PIN_NUMBER='(0,0,0,0,0,0,0,0,0,0,0,0,0,0,0,0,0,0,0,0,0,0,0,0,0,0,0,0,0,0,0,0,0,0,0,0,0,0,CU4,0)';
      PINUSE='POWER';
      NO_LOAD_CHECK='Both';
      NO_IO_CHECK='Both';
      NO_ASSERT_CHECK='TRUE';
      NO_DIR_CHECK='TRUE';
      ALLOW_CONNECT='TRUE';
    'VSS_CU6':
      PIN_NUMBER='(0,0,0,0,0,0,0,0,0,0,0,0,0,0,0,0,0,0,0,0,0,0,0,0,0,0,0,0,0,0,0,0,0,0,0,0,0,0,CU6,0)';
      PINUSE='POWER';
      NO_LOAD_CHECK='Both';
      NO_IO_CHECK='Both';
      NO_ASSERT_CHECK='TRUE';
      NO_DIR_CHECK='TRUE';
      ALLOW_CONNECT='TRUE';
    'VSS_CU8':
      PIN_NUMBER='(0,0,0,0,0,0,0,0,0,0,0,0,0,0,0,0,0,0,0,0,0,0,0,0,0,0,0,0,0,0,0,0,0,0,0,0,0,0,CU8,0)';
      PINUSE='POWER';
      NO_LOAD_CHECK='Both';
      NO_IO_CHECK='Both';
      NO_ASSERT_CHECK='TRUE';
      NO_DIR_CHECK='TRUE';
      ALLOW_CONNECT='TRUE';
    'VSS_CU11':
      PIN_NUMBER='(0,0,0,0,0,0,0,0,0,0,0,0,0,0,0,0,0,0,0,0,0,0,0,0,0,0,0,0,0,0,0,0,0,0,0,0,0,0,CU11,0)';
      PINUSE='POWER';
      NO_LOAD_CHECK='Both';
      NO_IO_CHECK='Both';
      NO_ASSERT_CHECK='TRUE';
      NO_DIR_CHECK='TRUE';
      ALLOW_CONNECT='TRUE';
    'VSS_CU13':
      PIN_NUMBER='(0,0,0,0,0,0,0,0,0,0,0,0,0,0,0,0,0,0,0,0,0,0,0,0,0,0,0,0,0,0,0,0,0,0,0,0,0,0,CU13,0)';
      PINUSE='POWER';
      NO_LOAD_CHECK='Both';
      NO_IO_CHECK='Both';
      NO_ASSERT_CHECK='TRUE';
      NO_DIR_CHECK='TRUE';
      ALLOW_CONNECT='TRUE';
    'VSS_CU15':
      PIN_NUMBER='(0,0,0,0,0,0,0,0,0,0,0,0,0,0,0,0,0,0,0,0,0,0,0,0,0,0,0,0,0,0,0,0,0,0,0,0,0,0,CU15,0)';
      PINUSE='POWER';
      NO_LOAD_CHECK='Both';
      NO_IO_CHECK='Both';
      NO_ASSERT_CHECK='TRUE';
      NO_DIR_CHECK='TRUE';
      ALLOW_CONNECT='TRUE';
    'VSS_CU18':
      PIN_NUMBER='(0,0,0,0,0,0,0,0,0,0,0,0,0,0,0,0,0,0,0,0,0,0,0,0,0,0,0,0,0,0,0,0,0,0,0,0,0,0,CU18,0)';
      PINUSE='POWER';
      NO_LOAD_CHECK='Both';
      NO_IO_CHECK='Both';
      NO_ASSERT_CHECK='TRUE';
      NO_DIR_CHECK='TRUE';
      ALLOW_CONNECT='TRUE';
    'VSS_CU20':
      PIN_NUMBER='(0,0,0,0,0,0,0,0,0,0,0,0,0,0,0,0,0,0,0,0,0,0,0,0,0,0,0,0,0,0,0,0,0,0,0,0,0,0,CU20,0)';
      PINUSE='POWER';
      NO_LOAD_CHECK='Both';
      NO_IO_CHECK='Both';
      NO_ASSERT_CHECK='TRUE';
      NO_DIR_CHECK='TRUE';
      ALLOW_CONNECT='TRUE';
    'VSS_CU31':
      PIN_NUMBER='(0,0,0,0,0,0,0,0,0,0,0,0,0,0,0,0,0,0,0,0,0,0,0,0,0,0,0,0,0,0,0,0,0,0,0,0,0,0,CU31,0)';
      PINUSE='POWER';
      NO_LOAD_CHECK='Both';
      NO_IO_CHECK='Both';
      NO_ASSERT_CHECK='TRUE';
      NO_DIR_CHECK='TRUE';
      ALLOW_CONNECT='TRUE';
    'VSS_CU34':
      PIN_NUMBER='(0,0,0,0,0,0,0,0,0,0,0,0,0,0,0,0,0,0,0,0,0,0,0,0,0,0,0,0,0,0,0,0,0,0,0,0,0,0,CU34,0)';
      PINUSE='POWER';
      NO_LOAD_CHECK='Both';
      NO_IO_CHECK='Both';
      NO_ASSERT_CHECK='TRUE';
      NO_DIR_CHECK='TRUE';
      ALLOW_CONNECT='TRUE';
    'VSS_CU42':
      PIN_NUMBER='(0,0,0,0,0,0,0,0,0,0,0,0,0,0,0,0,0,0,0,0,0,0,0,0,0,0,0,0,0,0,0,0,0,0,0,0,0,0,CU42,0)';
      PINUSE='POWER';
      NO_LOAD_CHECK='Both';
      NO_IO_CHECK='Both';
      NO_ASSERT_CHECK='TRUE';
      NO_DIR_CHECK='TRUE';
      ALLOW_CONNECT='TRUE';
    'VSS_CU45':
      PIN_NUMBER='(0,0,0,0,0,0,0,0,0,0,0,0,0,0,0,0,0,0,0,0,0,0,0,0,0,0,0,0,0,0,0,0,0,0,0,0,0,0,CU45,0)';
      PINUSE='POWER';
      NO_LOAD_CHECK='Both';
      NO_IO_CHECK='Both';
      NO_ASSERT_CHECK='TRUE';
      NO_DIR_CHECK='TRUE';
      ALLOW_CONNECT='TRUE';
    'VSS_CU48':
      PIN_NUMBER='(0,0,0,0,0,0,0,0,0,0,0,0,0,0,0,0,0,0,0,0,0,0,0,0,0,0,0,0,0,0,0,0,0,0,0,0,0,0,CU48,0)';
      PINUSE='POWER';
      NO_LOAD_CHECK='Both';
      NO_IO_CHECK='Both';
      NO_ASSERT_CHECK='TRUE';
      NO_DIR_CHECK='TRUE';
      ALLOW_CONNECT='TRUE';
    'VSS_CU51':
      PIN_NUMBER='(0,0,0,0,0,0,0,0,0,0,0,0,0,0,0,0,0,0,0,0,0,0,0,0,0,0,0,0,0,0,0,0,0,0,0,0,0,0,CU51,0)';
      PINUSE='POWER';
      NO_LOAD_CHECK='Both';
      NO_IO_CHECK='Both';
      NO_ASSERT_CHECK='TRUE';
      NO_DIR_CHECK='TRUE';
      ALLOW_CONNECT='TRUE';
    'VSS_CU54':
      PIN_NUMBER='(0,0,0,0,0,0,0,0,0,0,0,0,0,0,0,0,0,0,0,0,0,0,0,0,0,0,0,0,0,0,0,0,0,0,0,0,0,0,CU54,0)';
      PINUSE='POWER';
      NO_LOAD_CHECK='Both';
      NO_IO_CHECK='Both';
      NO_ASSERT_CHECK='TRUE';
      NO_DIR_CHECK='TRUE';
      ALLOW_CONNECT='TRUE';
    'VSS_CU65':
      PIN_NUMBER='(0,0,0,0,0,0,0,0,0,0,0,0,0,0,0,0,0,0,0,0,0,0,0,0,0,0,0,0,0,0,0,0,0,0,0,0,0,0,CU65,0)';
      PINUSE='POWER';
      NO_LOAD_CHECK='Both';
      NO_IO_CHECK='Both';
      NO_ASSERT_CHECK='TRUE';
      NO_DIR_CHECK='TRUE';
      ALLOW_CONNECT='TRUE';
    'VSS_CU68':
      PIN_NUMBER='(0,0,0,0,0,0,0,0,0,0,0,0,0,0,0,0,0,0,0,0,0,0,0,0,0,0,0,0,0,0,0,0,0,0,0,0,0,0,CU68,0)';
      PINUSE='POWER';
      NO_LOAD_CHECK='Both';
      NO_IO_CHECK='Both';
      NO_ASSERT_CHECK='TRUE';
      NO_DIR_CHECK='TRUE';
      ALLOW_CONNECT='TRUE';
    'VSS_CU70':
      PIN_NUMBER='(0,0,0,0,0,0,0,0,0,0,0,0,0,0,0,0,0,0,0,0,0,0,0,0,0,0,0,0,0,0,0,0,0,0,0,0,0,0,CU70,0)';
      PINUSE='POWER';
      NO_LOAD_CHECK='Both';
      NO_IO_CHECK='Both';
      NO_ASSERT_CHECK='TRUE';
      NO_DIR_CHECK='TRUE';
      ALLOW_CONNECT='TRUE';
    'VSS_CU72':
      PIN_NUMBER='(0,0,0,0,0,0,0,0,0,0,0,0,0,0,0,0,0,0,0,0,0,0,0,0,0,0,0,0,0,0,0,0,0,0,0,0,0,0,CU72,0)';
      PINUSE='POWER';
      NO_LOAD_CHECK='Both';
      NO_IO_CHECK='Both';
      NO_ASSERT_CHECK='TRUE';
      NO_DIR_CHECK='TRUE';
      ALLOW_CONNECT='TRUE';
    'VSS_CU75':
      PIN_NUMBER='(0,0,0,0,0,0,0,0,0,0,0,0,0,0,0,0,0,0,0,0,0,0,0,0,0,0,0,0,0,0,0,0,0,0,0,0,0,0,CU75,0)';
      PINUSE='POWER';
      NO_LOAD_CHECK='Both';
      NO_IO_CHECK='Both';
      NO_ASSERT_CHECK='TRUE';
      NO_DIR_CHECK='TRUE';
      ALLOW_CONNECT='TRUE';
    'VSS_CV3':
      PIN_NUMBER='(0,0,0,0,0,0,0,0,0,0,0,0,0,0,0,0,0,0,0,0,0,0,0,0,0,0,0,0,0,0,0,0,0,0,0,0,0,0,CV3,0)';
      PINUSE='POWER';
      NO_LOAD_CHECK='Both';
      NO_IO_CHECK='Both';
      NO_ASSERT_CHECK='TRUE';
      NO_DIR_CHECK='TRUE';
      ALLOW_CONNECT='TRUE';
    'VSS_CV17':
      PIN_NUMBER='(0,0,0,0,0,0,0,0,0,0,0,0,0,0,0,0,0,0,0,0,0,0,0,0,0,0,0,0,0,0,0,0,0,0,0,0,0,0,CV17,0)';
      PINUSE='POWER';
      NO_LOAD_CHECK='Both';
      NO_IO_CHECK='Both';
      NO_ASSERT_CHECK='TRUE';
      NO_DIR_CHECK='TRUE';
      ALLOW_CONNECT='TRUE';
    'VSS_CV19':
      PIN_NUMBER='(0,0,0,0,0,0,0,0,0,0,0,0,0,0,0,0,0,0,0,0,0,0,0,0,0,0,0,0,0,0,0,0,0,0,0,0,0,0,CV19,0)';
      PINUSE='POWER';
      NO_LOAD_CHECK='Both';
      NO_IO_CHECK='Both';
      NO_ASSERT_CHECK='TRUE';
      NO_DIR_CHECK='TRUE';
      ALLOW_CONNECT='TRUE';
    'VSS_CV22':
      PIN_NUMBER='(0,0,0,0,0,0,0,0,0,0,0,0,0,0,0,0,0,0,0,0,0,0,0,0,0,0,0,0,0,0,0,0,0,0,0,0,0,0,CV22,0)';
      PINUSE='POWER';
      NO_LOAD_CHECK='Both';
      NO_IO_CHECK='Both';
      NO_ASSERT_CHECK='TRUE';
      NO_DIR_CHECK='TRUE';
      ALLOW_CONNECT='TRUE';
    'VSS_CV25':
      PIN_NUMBER='(0,0,0,0,0,0,0,0,0,0,0,0,0,0,0,0,0,0,0,0,0,0,0,0,0,0,0,0,0,0,0,0,0,0,0,0,0,0,CV25,0)';
      PINUSE='POWER';
      NO_LOAD_CHECK='Both';
      NO_IO_CHECK='Both';
      NO_ASSERT_CHECK='TRUE';
      NO_DIR_CHECK='TRUE';
      ALLOW_CONNECT='TRUE';
    'VSS_CV28':
      PIN_NUMBER='(0,0,0,0,0,0,0,0,0,0,0,0,0,0,0,0,0,0,0,0,0,0,0,0,0,0,0,0,0,0,0,0,0,0,0,0,0,0,CV28,0)';
      PINUSE='POWER';
      NO_LOAD_CHECK='Both';
      NO_IO_CHECK='Both';
      NO_ASSERT_CHECK='TRUE';
      NO_DIR_CHECK='TRUE';
      ALLOW_CONNECT='TRUE';
    'VSS_CV31':
      PIN_NUMBER='(0,0,0,0,0,0,0,0,0,0,0,0,0,0,0,0,0,0,0,0,0,0,0,0,0,0,0,0,0,0,0,0,0,0,0,0,0,0,CV31,0)';
      PINUSE='POWER';
      NO_LOAD_CHECK='Both';
      NO_IO_CHECK='Both';
      NO_ASSERT_CHECK='TRUE';
      NO_DIR_CHECK='TRUE';
      ALLOW_CONNECT='TRUE';
    'VSS_CV48':
      PIN_NUMBER='(0,0,0,0,0,0,0,0,0,0,0,0,0,0,0,0,0,0,0,0,0,0,0,0,0,0,0,0,0,0,0,0,0,0,0,0,0,0,CV48,0)';
      PINUSE='POWER';
      NO_LOAD_CHECK='Both';
      NO_IO_CHECK='Both';
      NO_ASSERT_CHECK='TRUE';
      NO_DIR_CHECK='TRUE';
      ALLOW_CONNECT='TRUE';
    'VSS_CV51':
      PIN_NUMBER='(0,0,0,0,0,0,0,0,0,0,0,0,0,0,0,0,0,0,0,0,0,0,0,0,0,0,0,0,0,0,0,0,0,0,0,0,0,0,CV51,0)';
      PINUSE='POWER';
      NO_LOAD_CHECK='Both';
      NO_IO_CHECK='Both';
      NO_ASSERT_CHECK='TRUE';
      NO_DIR_CHECK='TRUE';
      ALLOW_CONNECT='TRUE';
    'VSS_CV54':
      PIN_NUMBER='(0,0,0,0,0,0,0,0,0,0,0,0,0,0,0,0,0,0,0,0,0,0,0,0,0,0,0,0,0,0,0,0,0,0,0,0,0,0,CV54,0)';
      PINUSE='POWER';
      NO_LOAD_CHECK='Both';
      NO_IO_CHECK='Both';
      NO_ASSERT_CHECK='TRUE';
      NO_DIR_CHECK='TRUE';
      ALLOW_CONNECT='TRUE';
    'VSS_CV57':
      PIN_NUMBER='(0,0,0,0,0,0,0,0,0,0,0,0,0,0,0,0,0,0,0,0,0,0,0,0,0,0,0,0,0,0,0,0,0,0,0,0,0,0,CV57,0)';
      PINUSE='POWER';
      NO_LOAD_CHECK='Both';
      NO_IO_CHECK='Both';
      NO_ASSERT_CHECK='TRUE';
      NO_DIR_CHECK='TRUE';
      ALLOW_CONNECT='TRUE';
    'VSS_CV59':
      PIN_NUMBER='(0,0,0,0,0,0,0,0,0,0,0,0,0,0,0,0,0,0,0,0,0,0,0,0,0,0,0,0,0,0,0,0,0,0,0,0,0,0,CV59,0)';
      PINUSE='POWER';
      NO_LOAD_CHECK='Both';
      NO_IO_CHECK='Both';
      NO_ASSERT_CHECK='TRUE';
      NO_DIR_CHECK='TRUE';
      ALLOW_CONNECT='TRUE';
    'VSS_CV61':
      PIN_NUMBER='(0,0,0,0,0,0,0,0,0,0,0,0,0,0,0,0,0,0,0,0,0,0,0,0,0,0,0,0,0,0,0,0,0,0,0,0,0,0,CV61,0)';
      PINUSE='POWER';
      NO_LOAD_CHECK='Both';
      NO_IO_CHECK='Both';
      NO_ASSERT_CHECK='TRUE';
      NO_DIR_CHECK='TRUE';
      ALLOW_CONNECT='TRUE';
    'VSS_CW1':
      PIN_NUMBER='(0,0,0,0,0,0,0,0,0,0,0,0,0,0,0,0,0,0,0,0,0,0,0,0,0,0,0,0,0,0,0,0,0,0,0,0,0,0,CW1,0)';
      PINUSE='POWER';
      NO_LOAD_CHECK='Both';
      NO_IO_CHECK='Both';
      NO_ASSERT_CHECK='TRUE';
      NO_DIR_CHECK='TRUE';
      ALLOW_CONNECT='TRUE';
    'VSS_CW6':
      PIN_NUMBER='(0,0,0,0,0,0,0,0,0,0,0,0,0,0,0,0,0,0,0,0,0,0,0,0,0,0,0,0,0,0,0,0,0,0,0,0,0,0,CW6,0)';
      PINUSE='POWER';
      NO_LOAD_CHECK='Both';
      NO_IO_CHECK='Both';
      NO_ASSERT_CHECK='TRUE';
      NO_DIR_CHECK='TRUE';
      ALLOW_CONNECT='TRUE';
    'VSS_CW8':
      PIN_NUMBER='(0,0,0,0,0,0,0,0,0,0,0,0,0,0,0,0,0,0,0,0,0,0,0,0,0,0,0,0,0,0,0,0,0,0,0,0,0,0,CW8,0)';
      PINUSE='POWER';
      NO_LOAD_CHECK='Both';
      NO_IO_CHECK='Both';
      NO_ASSERT_CHECK='TRUE';
      NO_DIR_CHECK='TRUE';
      ALLOW_CONNECT='TRUE';
    'VSS_CW13':
      PIN_NUMBER='(0,0,0,0,0,0,0,0,0,0,0,0,0,0,0,0,0,0,0,0,0,0,0,0,0,0,0,0,0,0,0,0,0,0,0,0,0,0,CW13,0)';
      PINUSE='POWER';
      NO_LOAD_CHECK='Both';
      NO_IO_CHECK='Both';
      NO_ASSERT_CHECK='TRUE';
      NO_DIR_CHECK='TRUE';
      ALLOW_CONNECT='TRUE';
    'VSS_CW15':
      PIN_NUMBER='(0,0,0,0,0,0,0,0,0,0,0,0,0,0,0,0,0,0,0,0,0,0,0,0,0,0,0,0,0,0,0,0,0,0,0,0,0,0,CW15,0)';
      PINUSE='POWER';
      NO_LOAD_CHECK='Both';
      NO_IO_CHECK='Both';
      NO_ASSERT_CHECK='TRUE';
      NO_DIR_CHECK='TRUE';
      ALLOW_CONNECT='TRUE';
    'VSS_CW20':
      PIN_NUMBER='(0,0,0,0,0,0,0,0,0,0,0,0,0,0,0,0,0,0,0,0,0,0,0,0,0,0,0,0,0,0,0,0,0,0,0,0,0,0,CW20,0)';
      PINUSE='POWER';
      NO_LOAD_CHECK='Both';
      NO_IO_CHECK='Both';
      NO_ASSERT_CHECK='TRUE';
      NO_DIR_CHECK='TRUE';
      ALLOW_CONNECT='TRUE';
    'VSS_CW35':
      PIN_NUMBER='(0,0,0,0,0,0,0,0,0,0,0,0,0,0,0,0,0,0,0,0,0,0,0,0,0,0,0,0,0,0,0,0,0,0,0,0,0,0,CW35,0)';
      PINUSE='POWER';
      NO_LOAD_CHECK='Both';
      NO_IO_CHECK='Both';
      NO_ASSERT_CHECK='TRUE';
      NO_DIR_CHECK='TRUE';
      ALLOW_CONNECT='TRUE';
    'VSS_CW36':
      PIN_NUMBER='(0,0,0,0,0,0,0,0,0,0,0,0,0,0,0,0,0,0,0,0,0,0,0,0,0,0,0,0,0,0,0,0,0,0,0,0,0,0,CW36,0)';
      PINUSE='POWER';
      NO_LOAD_CHECK='Both';
      NO_IO_CHECK='Both';
      NO_ASSERT_CHECK='TRUE';
      NO_DIR_CHECK='TRUE';
      ALLOW_CONNECT='TRUE';
    'VSS_CW40':
      PIN_NUMBER='(0,0,0,0,0,0,0,0,0,0,0,0,0,0,0,0,0,0,0,0,0,0,0,0,0,0,0,0,0,0,0,0,0,0,0,0,0,0,CW40,0)';
      PINUSE='POWER';
      NO_LOAD_CHECK='Both';
      NO_IO_CHECK='Both';
      NO_ASSERT_CHECK='TRUE';
      NO_DIR_CHECK='TRUE';
      ALLOW_CONNECT='TRUE';
    'VSS_CW41':
      PIN_NUMBER='(0,0,0,0,0,0,0,0,0,0,0,0,0,0,0,0,0,0,0,0,0,0,0,0,0,0,0,0,0,0,0,0,0,0,0,0,0,0,CW41,0)';
      PINUSE='POWER';
      NO_LOAD_CHECK='Both';
      NO_IO_CHECK='Both';
      NO_ASSERT_CHECK='TRUE';
      NO_DIR_CHECK='TRUE';
      ALLOW_CONNECT='TRUE';
    'VSS_CW42':
      PIN_NUMBER='(0,0,0,0,0,0,0,0,0,0,0,0,0,0,0,0,0,0,0,0,0,0,0,0,0,0,0,0,0,0,0,0,0,0,0,0,0,0,CW42,0)';
      PINUSE='POWER';
      NO_LOAD_CHECK='Both';
      NO_IO_CHECK='Both';
      NO_ASSERT_CHECK='TRUE';
      NO_DIR_CHECK='TRUE';
      ALLOW_CONNECT='TRUE';
    'VSS_CW45':
      PIN_NUMBER='(0,0,0,0,0,0,0,0,0,0,0,0,0,0,0,0,0,0,0,0,0,0,0,0,0,0,0,0,0,0,0,0,0,0,0,0,0,0,CW45,0)';
      PINUSE='POWER';
      NO_LOAD_CHECK='Both';
      NO_IO_CHECK='Both';
      NO_ASSERT_CHECK='TRUE';
      NO_DIR_CHECK='TRUE';
      ALLOW_CONNECT='TRUE';
    'VSS_CW48':
      PIN_NUMBER='(0,0,0,0,0,0,0,0,0,0,0,0,0,0,0,0,0,0,0,0,0,0,0,0,0,0,0,0,0,0,0,0,0,0,0,0,0,0,CW48,0)';
      PINUSE='POWER';
      NO_LOAD_CHECK='Both';
      NO_IO_CHECK='Both';
      NO_ASSERT_CHECK='TRUE';
      NO_DIR_CHECK='TRUE';
      ALLOW_CONNECT='TRUE';
    'VSS_CW51':
      PIN_NUMBER='(0,0,0,0,0,0,0,0,0,0,0,0,0,0,0,0,0,0,0,0,0,0,0,0,0,0,0,0,0,0,0,0,0,0,0,0,0,0,CW51,0)';
      PINUSE='POWER';
      NO_LOAD_CHECK='Both';
      NO_IO_CHECK='Both';
      NO_ASSERT_CHECK='TRUE';
      NO_DIR_CHECK='TRUE';
      ALLOW_CONNECT='TRUE';
    'VSS_CW54':
      PIN_NUMBER='(0,0,0,0,0,0,0,0,0,0,0,0,0,0,0,0,0,0,0,0,0,0,0,0,0,0,0,0,0,0,0,0,0,0,0,0,0,0,CW54,0)';
      PINUSE='POWER';
      NO_LOAD_CHECK='Both';
      NO_IO_CHECK='Both';
      NO_ASSERT_CHECK='TRUE';
      NO_DIR_CHECK='TRUE';
      ALLOW_CONNECT='TRUE';
    'VSS_CW56':
      PIN_NUMBER='(0,0,0,0,0,0,0,0,0,0,0,0,0,0,0,0,0,0,0,0,0,0,0,0,0,0,0,0,0,0,0,0,0,0,0,0,0,0,CW56,0)';
      PINUSE='POWER';
      NO_LOAD_CHECK='Both';
      NO_IO_CHECK='Both';
      NO_ASSERT_CHECK='TRUE';
      NO_DIR_CHECK='TRUE';
      ALLOW_CONNECT='TRUE';
    'VSS_CW61':
      PIN_NUMBER='(0,0,0,0,0,0,0,0,0,0,0,0,0,0,0,0,0,0,0,0,0,0,0,0,0,0,0,0,0,0,0,0,0,0,0,0,0,0,CW61,0)';
      PINUSE='POWER';
      NO_LOAD_CHECK='Both';
      NO_IO_CHECK='Both';
      NO_ASSERT_CHECK='TRUE';
      NO_DIR_CHECK='TRUE';
      ALLOW_CONNECT='TRUE';
    'VSS_CW63':
      PIN_NUMBER='(0,0,0,0,0,0,0,0,0,0,0,0,0,0,0,0,0,0,0,0,0,0,0,0,0,0,0,0,0,0,0,0,0,0,0,0,0,0,CW63,0)';
      PINUSE='POWER';
      NO_LOAD_CHECK='Both';
      NO_IO_CHECK='Both';
      NO_ASSERT_CHECK='TRUE';
      NO_DIR_CHECK='TRUE';
      ALLOW_CONNECT='TRUE';
    'VSS_CW68':
      PIN_NUMBER='(0,0,0,0,0,0,0,0,0,0,0,0,0,0,0,0,0,0,0,0,0,0,0,0,0,0,0,0,0,0,0,0,0,0,0,0,0,0,CW68,0)';
      PINUSE='POWER';
      NO_LOAD_CHECK='Both';
      NO_IO_CHECK='Both';
      NO_ASSERT_CHECK='TRUE';
      NO_DIR_CHECK='TRUE';
      ALLOW_CONNECT='TRUE';
    'VSS_CW70':
      PIN_NUMBER='(0,0,0,0,0,0,0,0,0,0,0,0,0,0,0,0,0,0,0,0,0,0,0,0,0,0,0,0,0,0,0,0,0,0,0,0,0,0,CW70,0)';
      PINUSE='POWER';
      NO_LOAD_CHECK='Both';
      NO_IO_CHECK='Both';
      NO_ASSERT_CHECK='TRUE';
      NO_DIR_CHECK='TRUE';
      ALLOW_CONNECT='TRUE';
    'VSS_CW75':
      PIN_NUMBER='(0,0,0,0,0,0,0,0,0,0,0,0,0,0,0,0,0,0,0,0,0,0,0,0,0,0,0,0,0,0,0,0,0,0,0,0,0,0,CW75,0)';
      PINUSE='POWER';
      NO_LOAD_CHECK='Both';
      NO_IO_CHECK='Both';
      NO_ASSERT_CHECK='TRUE';
      NO_DIR_CHECK='TRUE';
      ALLOW_CONNECT='TRUE';
    'VSS_CY3':
      PIN_NUMBER='(0,0,0,0,0,0,0,0,0,0,0,0,0,0,0,0,0,0,0,0,0,0,0,0,0,0,0,0,0,0,0,0,0,0,0,0,0,0,CY3,0)';
      PINUSE='POWER';
      NO_LOAD_CHECK='Both';
      NO_IO_CHECK='Both';
      NO_ASSERT_CHECK='TRUE';
      NO_DIR_CHECK='TRUE';
      ALLOW_CONNECT='TRUE';
    'VSS_CY5':
      PIN_NUMBER='(0,0,0,0,0,0,0,0,0,0,0,0,0,0,0,0,0,0,0,0,0,0,0,0,0,0,0,0,0,0,0,0,0,0,0,0,0,0,CY5,0)';
      PINUSE='POWER';
      NO_LOAD_CHECK='Both';
      NO_IO_CHECK='Both';
      NO_ASSERT_CHECK='TRUE';
      NO_DIR_CHECK='TRUE';
      ALLOW_CONNECT='TRUE';
    'VSS_CY8':
      PIN_NUMBER='(0,0,0,0,0,0,0,0,0,0,0,0,0,0,0,0,0,0,0,0,0,0,0,0,0,0,0,0,0,0,0,0,0,0,0,0,0,0,CY8,0)';
      PINUSE='POWER';
      NO_LOAD_CHECK='Both';
      NO_IO_CHECK='Both';
      NO_ASSERT_CHECK='TRUE';
      NO_DIR_CHECK='TRUE';
      ALLOW_CONNECT='TRUE';
    'VSS_CY10':
      PIN_NUMBER='(0,0,0,0,0,0,0,0,0,0,0,0,0,0,0,0,0,0,0,0,0,0,0,0,0,0,0,0,0,0,0,0,0,0,0,0,0,0,CY10,0)';
      PINUSE='POWER';
      NO_LOAD_CHECK='Both';
      NO_IO_CHECK='Both';
      NO_ASSERT_CHECK='TRUE';
      NO_DIR_CHECK='TRUE';
      ALLOW_CONNECT='TRUE';
    'VSS_CY12':
      PIN_NUMBER='(0,0,0,0,0,0,0,0,0,0,0,0,0,0,0,0,0,0,0,0,0,0,0,0,0,0,0,0,0,0,0,0,0,0,0,0,0,0,CY12,0)';
      PINUSE='POWER';
      NO_LOAD_CHECK='Both';
      NO_IO_CHECK='Both';
      NO_ASSERT_CHECK='TRUE';
      NO_DIR_CHECK='TRUE';
      ALLOW_CONNECT='TRUE';
    'VSS_CY15':
      PIN_NUMBER='(0,0,0,0,0,0,0,0,0,0,0,0,0,0,0,0,0,0,0,0,0,0,0,0,0,0,0,0,0,0,0,0,0,0,0,0,0,0,CY15,0)';
      PINUSE='POWER';
      NO_LOAD_CHECK='Both';
      NO_IO_CHECK='Both';
      NO_ASSERT_CHECK='TRUE';
      NO_DIR_CHECK='TRUE';
      ALLOW_CONNECT='TRUE';
    'VSS_CY17':
      PIN_NUMBER='(0,0,0,0,0,0,0,0,0,0,0,0,0,0,0,0,0,0,0,0,0,0,0,0,0,0,0,0,0,0,0,0,0,0,0,0,0,0,CY17,0)';
      PINUSE='POWER';
      NO_LOAD_CHECK='Both';
      NO_IO_CHECK='Both';
      NO_ASSERT_CHECK='TRUE';
      NO_DIR_CHECK='TRUE';
      ALLOW_CONNECT='TRUE';
    'VSS_CY19':
      PIN_NUMBER='(0,0,0,0,0,0,0,0,0,0,0,0,0,0,0,0,0,0,0,0,0,0,0,0,0,0,0,0,0,0,0,0,0,0,0,0,0,0,CY19,0)';
      PINUSE='POWER';
      NO_LOAD_CHECK='Both';
      NO_IO_CHECK='Both';
      NO_ASSERT_CHECK='TRUE';
      NO_DIR_CHECK='TRUE';
      ALLOW_CONNECT='TRUE';
    'VSS_CY23':
      PIN_NUMBER='(0,0,0,0,0,0,0,0,0,0,0,0,0,0,0,0,0,0,0,0,0,0,0,0,0,0,0,0,0,0,0,0,0,0,0,0,0,0,CY23,0)';
      PINUSE='POWER';
      NO_LOAD_CHECK='Both';
      NO_IO_CHECK='Both';
      NO_ASSERT_CHECK='TRUE';
      NO_DIR_CHECK='TRUE';
      ALLOW_CONNECT='TRUE';
    'VSS_CY24':
      PIN_NUMBER='(0,0,0,0,0,0,0,0,0,0,0,0,0,0,0,0,0,0,0,0,0,0,0,0,0,0,0,0,0,0,0,0,0,0,0,0,0,0,CY24,0)';
      PINUSE='POWER';
      NO_LOAD_CHECK='Both';
      NO_IO_CHECK='Both';
      NO_ASSERT_CHECK='TRUE';
      NO_DIR_CHECK='TRUE';
      ALLOW_CONNECT='TRUE';
    'VSS_CY25':
      PIN_NUMBER='(0,0,0,0,0,0,0,0,0,0,0,0,0,0,0,0,0,0,0,0,0,0,0,0,0,0,0,0,0,0,0,0,0,0,0,0,0,0,CY25,0)';
      PINUSE='POWER';
      NO_LOAD_CHECK='Both';
      NO_IO_CHECK='Both';
      NO_ASSERT_CHECK='TRUE';
      NO_DIR_CHECK='TRUE';
      ALLOW_CONNECT='TRUE';
    'VSS_CY26':
      PIN_NUMBER='(0,0,0,0,0,0,0,0,0,0,0,0,0,0,0,0,0,0,0,0,0,0,0,0,0,0,0,0,0,0,0,0,0,0,0,0,0,0,CY26,0)';
      PINUSE='POWER';
      NO_LOAD_CHECK='Both';
      NO_IO_CHECK='Both';
      NO_ASSERT_CHECK='TRUE';
      NO_DIR_CHECK='TRUE';
      ALLOW_CONNECT='TRUE';
    'VSS_CY27':
      PIN_NUMBER='(0,0,0,0,0,0,0,0,0,0,0,0,0,0,0,0,0,0,0,0,0,0,0,0,0,0,0,0,0,0,0,0,0,0,0,0,0,0,CY27,0)';
      PINUSE='POWER';
      NO_LOAD_CHECK='Both';
      NO_IO_CHECK='Both';
      NO_ASSERT_CHECK='TRUE';
      NO_DIR_CHECK='TRUE';
      ALLOW_CONNECT='TRUE';
    'VSS_CY28':
      PIN_NUMBER='(0,0,0,0,0,0,0,0,0,0,0,0,0,0,0,0,0,0,0,0,0,0,0,0,0,0,0,0,0,0,0,0,0,0,0,0,0,0,CY28,0)';
      PINUSE='POWER';
      NO_LOAD_CHECK='Both';
      NO_IO_CHECK='Both';
      NO_ASSERT_CHECK='TRUE';
      NO_DIR_CHECK='TRUE';
      ALLOW_CONNECT='TRUE';
    'VSS_CY29':
      PIN_NUMBER='(0,0,0,0,0,0,0,0,0,0,0,0,0,0,0,0,0,0,0,0,0,0,0,0,0,0,0,0,0,0,0,0,0,0,0,0,0,0,CY29,0)';
      PINUSE='POWER';
      NO_LOAD_CHECK='Both';
      NO_IO_CHECK='Both';
      NO_ASSERT_CHECK='TRUE';
      NO_DIR_CHECK='TRUE';
      ALLOW_CONNECT='TRUE';
    'VSS_CY30':
      PIN_NUMBER='(0,0,0,0,0,0,0,0,0,0,0,0,0,0,0,0,0,0,0,0,0,0,0,0,0,0,0,0,0,0,0,0,0,0,0,0,0,0,CY30,0)';
      PINUSE='POWER';
      NO_LOAD_CHECK='Both';
      NO_IO_CHECK='Both';
      NO_ASSERT_CHECK='TRUE';
      NO_DIR_CHECK='TRUE';
      ALLOW_CONNECT='TRUE';
    'VSS_CY31':
      PIN_NUMBER='(0,0,0,0,0,0,0,0,0,0,0,0,0,0,0,0,0,0,0,0,0,0,0,0,0,0,0,0,0,0,0,0,0,0,0,0,0,0,CY31,0)';
      PINUSE='POWER';
      NO_LOAD_CHECK='Both';
      NO_IO_CHECK='Both';
      NO_ASSERT_CHECK='TRUE';
      NO_DIR_CHECK='TRUE';
      ALLOW_CONNECT='TRUE';
    'VSS_CY33':
      PIN_NUMBER='(0,0,0,0,0,0,0,0,0,0,0,0,0,0,0,0,0,0,0,0,0,0,0,0,0,0,0,0,0,0,0,0,0,0,0,0,0,0,CY33,0)';
      PINUSE='POWER';
      NO_LOAD_CHECK='Both';
      NO_IO_CHECK='Both';
      NO_ASSERT_CHECK='TRUE';
      NO_DIR_CHECK='TRUE';
      ALLOW_CONNECT='TRUE';
    'VSS_CY34':
      PIN_NUMBER='(0,0,0,0,0,0,0,0,0,0,0,0,0,0,0,0,0,0,0,0,0,0,0,0,0,0,0,0,0,0,0,0,0,0,0,0,0,0,CY34,0)';
      PINUSE='POWER';
      NO_LOAD_CHECK='Both';
      NO_IO_CHECK='Both';
      NO_ASSERT_CHECK='TRUE';
      NO_DIR_CHECK='TRUE';
      ALLOW_CONNECT='TRUE';
    'VSS_CY37':
      PIN_NUMBER='(0,0,0,0,0,0,0,0,0,0,0,0,0,0,0,0,0,0,0,0,0,0,0,0,0,0,0,0,0,0,0,0,0,0,0,0,0,0,CY37,0)';
      PINUSE='POWER';
      NO_LOAD_CHECK='Both';
      NO_IO_CHECK='Both';
      NO_ASSERT_CHECK='TRUE';
      NO_DIR_CHECK='TRUE';
      ALLOW_CONNECT='TRUE';
    'VSS_CY39':
      PIN_NUMBER='(0,0,0,0,0,0,0,0,0,0,0,0,0,0,0,0,0,0,0,0,0,0,0,0,0,0,0,0,0,0,0,0,0,0,0,0,0,0,CY39,0)';
      PINUSE='POWER';
      NO_LOAD_CHECK='Both';
      NO_IO_CHECK='Both';
      NO_ASSERT_CHECK='TRUE';
      NO_DIR_CHECK='TRUE';
      ALLOW_CONNECT='TRUE';
    'VSS_CY42':
      PIN_NUMBER='(0,0,0,0,0,0,0,0,0,0,0,0,0,0,0,0,0,0,0,0,0,0,0,0,0,0,0,0,0,0,0,0,0,0,0,0,0,0,CY42,0)';
      PINUSE='POWER';
      NO_LOAD_CHECK='Both';
      NO_IO_CHECK='Both';
      NO_ASSERT_CHECK='TRUE';
      NO_DIR_CHECK='TRUE';
      ALLOW_CONNECT='TRUE';
    'VSS_CY43':
      PIN_NUMBER='(0,0,0,0,0,0,0,0,0,0,0,0,0,0,0,0,0,0,0,0,0,0,0,0,0,0,0,0,0,0,0,0,0,0,0,0,0,0,CY43,0)';
      PINUSE='POWER';
      NO_LOAD_CHECK='Both';
      NO_IO_CHECK='Both';
      NO_ASSERT_CHECK='TRUE';
      NO_DIR_CHECK='TRUE';
      ALLOW_CONNECT='TRUE';
    'VSS_CY44':
      PIN_NUMBER='(0,0,0,0,0,0,0,0,0,0,0,0,0,0,0,0,0,0,0,0,0,0,0,0,0,0,0,0,0,0,0,0,0,0,0,0,0,0,CY44,0)';
      PINUSE='POWER';
      NO_LOAD_CHECK='Both';
      NO_IO_CHECK='Both';
      NO_ASSERT_CHECK='TRUE';
      NO_DIR_CHECK='TRUE';
      ALLOW_CONNECT='TRUE';
    'VSS_CY45':
      PIN_NUMBER='(0,0,0,0,0,0,0,0,0,0,0,0,0,0,0,0,0,0,0,0,0,0,0,0,0,0,0,0,0,0,0,0,0,0,0,0,0,0,CY45,0)';
      PINUSE='POWER';
      NO_LOAD_CHECK='Both';
      NO_IO_CHECK='Both';
      NO_ASSERT_CHECK='TRUE';
      NO_DIR_CHECK='TRUE';
      ALLOW_CONNECT='TRUE';
    'VSS_CY46':
      PIN_NUMBER='(0,0,0,0,0,0,0,0,0,0,0,0,0,0,0,0,0,0,0,0,0,0,0,0,0,0,0,0,0,0,0,0,0,0,0,0,0,0,CY46,0)';
      PINUSE='POWER';
      NO_LOAD_CHECK='Both';
      NO_IO_CHECK='Both';
      NO_ASSERT_CHECK='TRUE';
      NO_DIR_CHECK='TRUE';
      ALLOW_CONNECT='TRUE';
    'VSS_CY49':
      PIN_NUMBER='(0,0,0,0,0,0,0,0,0,0,0,0,0,0,0,0,0,0,0,0,0,0,0,0,0,0,0,0,0,0,0,0,0,0,0,0,0,0,CY49,0)';
      PINUSE='POWER';
      NO_LOAD_CHECK='Both';
      NO_IO_CHECK='Both';
      NO_ASSERT_CHECK='TRUE';
      NO_DIR_CHECK='TRUE';
      ALLOW_CONNECT='TRUE';
    'VSS_CY50':
      PIN_NUMBER='(0,0,0,0,0,0,0,0,0,0,0,0,0,0,0,0,0,0,0,0,0,0,0,0,0,0,0,0,0,0,0,0,0,0,0,0,0,0,CY50,0)';
      PINUSE='POWER';
      NO_LOAD_CHECK='Both';
      NO_IO_CHECK='Both';
      NO_ASSERT_CHECK='TRUE';
      NO_DIR_CHECK='TRUE';
      ALLOW_CONNECT='TRUE';
    'VSS_CY51':
      PIN_NUMBER='(0,0,0,0,0,0,0,0,0,0,0,0,0,0,0,0,0,0,0,0,0,0,0,0,0,0,0,0,0,0,0,0,0,0,0,0,0,0,CY51,0)';
      PINUSE='POWER';
      NO_LOAD_CHECK='Both';
      NO_IO_CHECK='Both';
      NO_ASSERT_CHECK='TRUE';
      NO_DIR_CHECK='TRUE';
      ALLOW_CONNECT='TRUE';
    'VSS_CY52':
      PIN_NUMBER='(0,0,0,0,0,0,0,0,0,0,0,0,0,0,0,0,0,0,0,0,0,0,0,0,0,0,0,0,0,0,0,0,0,0,0,0,0,0,CY52,0)';
      PINUSE='POWER';
      NO_LOAD_CHECK='Both';
      NO_IO_CHECK='Both';
      NO_ASSERT_CHECK='TRUE';
      NO_DIR_CHECK='TRUE';
      ALLOW_CONNECT='TRUE';
    'VSS_CY53':
      PIN_NUMBER='(0,0,0,0,0,0,0,0,0,0,0,0,0,0,0,0,0,0,0,0,0,0,0,0,0,0,0,0,0,0,0,0,0,0,0,0,0,0,CY53,0)';
      PINUSE='POWER';
      NO_LOAD_CHECK='Both';
      NO_IO_CHECK='Both';
      NO_ASSERT_CHECK='TRUE';
      NO_DIR_CHECK='TRUE';
      ALLOW_CONNECT='TRUE';
    'VSS_CY59':
      PIN_NUMBER='(0,0,0,0,0,0,0,0,0,0,0,0,0,0,0,0,0,0,0,0,0,0,0,0,0,0,0,0,0,0,0,0,0,0,0,0,0,0,CY59,0)';
      PINUSE='POWER';
      NO_LOAD_CHECK='Both';
      NO_IO_CHECK='Both';
      NO_ASSERT_CHECK='TRUE';
      NO_DIR_CHECK='TRUE';
      ALLOW_CONNECT='TRUE';
    'VSS_CY61':
      PIN_NUMBER='(0,0,0,0,0,0,0,0,0,0,0,0,0,0,0,0,0,0,0,0,0,0,0,0,0,0,0,0,0,0,0,0,0,0,0,0,0,0,CY61,0)';
      PINUSE='POWER';
      NO_LOAD_CHECK='Both';
      NO_IO_CHECK='Both';
      NO_ASSERT_CHECK='TRUE';
      NO_DIR_CHECK='TRUE';
      ALLOW_CONNECT='TRUE';
    'VSS_CY71':
      PIN_NUMBER='(0,0,0,0,0,0,0,0,0,0,0,0,0,0,0,0,0,0,0,0,0,0,0,0,0,0,0,0,0,0,0,0,0,0,0,0,0,0,CY71,0)';
      PINUSE='POWER';
      NO_LOAD_CHECK='Both';
      NO_IO_CHECK='Both';
      NO_ASSERT_CHECK='TRUE';
      NO_DIR_CHECK='TRUE';
      ALLOW_CONNECT='TRUE';
    'VSS_CY73':
      PIN_NUMBER='(0,0,0,0,0,0,0,0,0,0,0,0,0,0,0,0,0,0,0,0,0,0,0,0,0,0,0,0,0,0,0,0,0,0,0,0,0,0,CY73,0)';
      PINUSE='POWER';
      NO_LOAD_CHECK='Both';
      NO_IO_CHECK='Both';
      NO_ASSERT_CHECK='TRUE';
      NO_DIR_CHECK='TRUE';
      ALLOW_CONNECT='TRUE';
    'VSS_DA1':
      PIN_NUMBER='(0,0,0,0,0,0,0,0,0,0,0,0,0,0,0,0,0,0,0,0,0,0,0,0,0,0,0,0,0,0,0,0,0,0,0,0,0,0,DA1,0)';
      PINUSE='POWER';
      NO_LOAD_CHECK='Both';
      NO_IO_CHECK='Both';
      NO_ASSERT_CHECK='TRUE';
      NO_DIR_CHECK='TRUE';
      ALLOW_CONNECT='TRUE';
    'VSS_DA4':
      PIN_NUMBER='(0,0,0,0,0,0,0,0,0,0,0,0,0,0,0,0,0,0,0,0,0,0,0,0,0,0,0,0,0,0,0,0,0,0,0,0,0,0,DA4,0)';
      PINUSE='POWER';
      NO_LOAD_CHECK='Both';
      NO_IO_CHECK='Both';
      NO_ASSERT_CHECK='TRUE';
      NO_DIR_CHECK='TRUE';
      ALLOW_CONNECT='TRUE';
    'VSS_DA6':
      PIN_NUMBER='(0,0,0,0,0,0,0,0,0,0,0,0,0,0,0,0,0,0,0,0,0,0,0,0,0,0,0,0,0,0,0,0,0,0,0,0,0,0,DA6,0)';
      PINUSE='POWER';
      NO_LOAD_CHECK='Both';
      NO_IO_CHECK='Both';
      NO_ASSERT_CHECK='TRUE';
      NO_DIR_CHECK='TRUE';
      ALLOW_CONNECT='TRUE';
    'VSS_DA8':
      PIN_NUMBER='(0,0,0,0,0,0,0,0,0,0,0,0,0,0,0,0,0,0,0,0,0,0,0,0,0,0,0,0,0,0,0,0,0,0,0,0,0,0,DA8,0)';
      PINUSE='POWER';
      NO_LOAD_CHECK='Both';
      NO_IO_CHECK='Both';
      NO_ASSERT_CHECK='TRUE';
      NO_DIR_CHECK='TRUE';
      ALLOW_CONNECT='TRUE';
    'VSS_DA11':
      PIN_NUMBER='(0,0,0,0,0,0,0,0,0,0,0,0,0,0,0,0,0,0,0,0,0,0,0,0,0,0,0,0,0,0,0,0,0,0,0,0,0,0,DA11,0)';
      PINUSE='POWER';
      NO_LOAD_CHECK='Both';
      NO_IO_CHECK='Both';
      NO_ASSERT_CHECK='TRUE';
      NO_DIR_CHECK='TRUE';
      ALLOW_CONNECT='TRUE';
    'VSS_DA22':
      PIN_NUMBER='(0,0,0,0,0,0,0,0,0,0,0,0,0,0,0,0,0,0,0,0,0,0,0,0,0,0,0,0,0,0,0,0,0,0,0,0,0,0,DA22,0)';
      PINUSE='POWER';
      NO_LOAD_CHECK='Both';
      NO_IO_CHECK='Both';
      NO_ASSERT_CHECK='TRUE';
      NO_DIR_CHECK='TRUE';
      ALLOW_CONNECT='TRUE';
    'VSS_DA25':
      PIN_NUMBER='(0,0,0,0,0,0,0,0,0,0,0,0,0,0,0,0,0,0,0,0,0,0,0,0,0,0,0,0,0,0,0,0,0,0,0,0,0,0,DA25,0)';
      PINUSE='POWER';
      NO_LOAD_CHECK='Both';
      NO_IO_CHECK='Both';
      NO_ASSERT_CHECK='TRUE';
      NO_DIR_CHECK='TRUE';
      ALLOW_CONNECT='TRUE';
    'VSS_DA28':
      PIN_NUMBER='(0,0,0,0,0,0,0,0,0,0,0,0,0,0,0,0,0,0,0,0,0,0,0,0,0,0,0,0,0,0,0,0,0,0,0,0,0,0,DA28,0)';
      PINUSE='POWER';
      NO_LOAD_CHECK='Both';
      NO_IO_CHECK='Both';
      NO_ASSERT_CHECK='TRUE';
      NO_DIR_CHECK='TRUE';
      ALLOW_CONNECT='TRUE';
    'VSS_DA31':
      PIN_NUMBER='(0,0,0,0,0,0,0,0,0,0,0,0,0,0,0,0,0,0,0,0,0,0,0,0,0,0,0,0,0,0,0,0,0,0,0,0,0,0,DA31,0)';
      PINUSE='POWER';
      NO_LOAD_CHECK='Both';
      NO_IO_CHECK='Both';
      NO_ASSERT_CHECK='TRUE';
      NO_DIR_CHECK='TRUE';
      ALLOW_CONNECT='TRUE';
    'VSS_DA34':
      PIN_NUMBER='(0,0,0,0,0,0,0,0,0,0,0,0,0,0,0,0,0,0,0,0,0,0,0,0,0,0,0,0,0,0,0,0,0,0,0,0,0,0,DA34,0)';
      PINUSE='POWER';
      NO_LOAD_CHECK='Both';
      NO_IO_CHECK='Both';
      NO_ASSERT_CHECK='TRUE';
      NO_DIR_CHECK='TRUE';
      ALLOW_CONNECT='TRUE';
    'VSS_DA42':
      PIN_NUMBER='(0,0,0,0,0,0,0,0,0,0,0,0,0,0,0,0,0,0,0,0,0,0,0,0,0,0,0,0,0,0,0,0,0,0,0,0,0,0,DA42,0)';
      PINUSE='POWER';
      NO_LOAD_CHECK='Both';
      NO_IO_CHECK='Both';
      NO_ASSERT_CHECK='TRUE';
      NO_DIR_CHECK='TRUE';
      ALLOW_CONNECT='TRUE';
    'VSS_DA58':
      PIN_NUMBER='(0,0,0,0,0,0,0,0,0,0,0,0,0,0,0,0,0,0,0,0,0,0,0,0,0,0,0,0,0,0,0,0,0,0,0,0,0,0,DA58,0)';
      PINUSE='POWER';
      NO_LOAD_CHECK='Both';
      NO_IO_CHECK='Both';
      NO_ASSERT_CHECK='TRUE';
      NO_DIR_CHECK='TRUE';
      ALLOW_CONNECT='TRUE';
    'VSS_DA61':
      PIN_NUMBER='(0,0,0,0,0,0,0,0,0,0,0,0,0,0,0,0,0,0,0,0,0,0,0,0,0,0,0,0,0,0,0,0,0,0,0,0,0,0,DA61,0)';
      PINUSE='POWER';
      NO_LOAD_CHECK='Both';
      NO_IO_CHECK='Both';
      NO_ASSERT_CHECK='TRUE';
      NO_DIR_CHECK='TRUE';
      ALLOW_CONNECT='TRUE';
    'VSS_DA63':
      PIN_NUMBER='(0,0,0,0,0,0,0,0,0,0,0,0,0,0,0,0,0,0,0,0,0,0,0,0,0,0,0,0,0,0,0,0,0,0,0,0,0,0,DA63,0)';
      PINUSE='POWER';
      NO_LOAD_CHECK='Both';
      NO_IO_CHECK='Both';
      NO_ASSERT_CHECK='TRUE';
      NO_DIR_CHECK='TRUE';
      ALLOW_CONNECT='TRUE';
    'VSS_DA65':
      PIN_NUMBER='(0,0,0,0,0,0,0,0,0,0,0,0,0,0,0,0,0,0,0,0,0,0,0,0,0,0,0,0,0,0,0,0,0,0,0,0,0,0,DA65,0)';
      PINUSE='POWER';
      NO_LOAD_CHECK='Both';
      NO_IO_CHECK='Both';
      NO_ASSERT_CHECK='TRUE';
      NO_DIR_CHECK='TRUE';
      ALLOW_CONNECT='TRUE';
    'VSS_DA68':
      PIN_NUMBER='(0,0,0,0,0,0,0,0,0,0,0,0,0,0,0,0,0,0,0,0,0,0,0,0,0,0,0,0,0,0,0,0,0,0,0,0,0,0,DA68,0)';
      PINUSE='POWER';
      NO_LOAD_CHECK='Both';
      NO_IO_CHECK='Both';
      NO_ASSERT_CHECK='TRUE';
      NO_DIR_CHECK='TRUE';
      ALLOW_CONNECT='TRUE';
    'VSS_DA70':
      PIN_NUMBER='(0,0,0,0,0,0,0,0,0,0,0,0,0,0,0,0,0,0,0,0,0,0,0,0,0,0,0,0,0,0,0,0,0,0,0,0,0,0,DA70,0)';
      PINUSE='POWER';
      NO_LOAD_CHECK='Both';
      NO_IO_CHECK='Both';
      NO_ASSERT_CHECK='TRUE';
      NO_DIR_CHECK='TRUE';
      ALLOW_CONNECT='TRUE';
    'VSS_DB15':
      PIN_NUMBER='(0,0,0,0,0,0,0,0,0,0,0,0,0,0,0,0,0,0,0,0,0,0,0,0,0,0,0,0,0,0,0,0,0,0,0,0,0,0,0,DB15)';
      PINUSE='POWER';
      NO_LOAD_CHECK='Both';
      NO_IO_CHECK='Both';
      NO_ASSERT_CHECK='TRUE';
      NO_DIR_CHECK='TRUE';
      ALLOW_CONNECT='TRUE';
    'VSS_DB17':
      PIN_NUMBER='(0,0,0,0,0,0,0,0,0,0,0,0,0,0,0,0,0,0,0,0,0,0,0,0,0,0,0,0,0,0,0,0,0,0,0,0,0,0,0,DB17)';
      PINUSE='POWER';
      NO_LOAD_CHECK='Both';
      NO_IO_CHECK='Both';
      NO_ASSERT_CHECK='TRUE';
      NO_DIR_CHECK='TRUE';
      ALLOW_CONNECT='TRUE';
    'VSS_DB22':
      PIN_NUMBER='(0,0,0,0,0,0,0,0,0,0,0,0,0,0,0,0,0,0,0,0,0,0,0,0,0,0,0,0,0,0,0,0,0,0,0,0,0,0,0,DB22)';
      PINUSE='POWER';
      NO_LOAD_CHECK='Both';
      NO_IO_CHECK='Both';
      NO_ASSERT_CHECK='TRUE';
      NO_DIR_CHECK='TRUE';
      ALLOW_CONNECT='TRUE';
    'VSS_DB25':
      PIN_NUMBER='(0,0,0,0,0,0,0,0,0,0,0,0,0,0,0,0,0,0,0,0,0,0,0,0,0,0,0,0,0,0,0,0,0,0,0,0,0,0,0,DB25)';
      PINUSE='POWER';
      NO_LOAD_CHECK='Both';
      NO_IO_CHECK='Both';
      NO_ASSERT_CHECK='TRUE';
      NO_DIR_CHECK='TRUE';
      ALLOW_CONNECT='TRUE';
    'VSS_DB48':
      PIN_NUMBER='(0,0,0,0,0,0,0,0,0,0,0,0,0,0,0,0,0,0,0,0,0,0,0,0,0,0,0,0,0,0,0,0,0,0,0,0,0,0,0,DB48)';
      PINUSE='POWER';
      NO_LOAD_CHECK='Both';
      NO_IO_CHECK='Both';
      NO_ASSERT_CHECK='TRUE';
      NO_DIR_CHECK='TRUE';
      ALLOW_CONNECT='TRUE';
    'VSS_DB51':
      PIN_NUMBER='(0,0,0,0,0,0,0,0,0,0,0,0,0,0,0,0,0,0,0,0,0,0,0,0,0,0,0,0,0,0,0,0,0,0,0,0,0,0,0,DB51)';
      PINUSE='POWER';
      NO_LOAD_CHECK='Both';
      NO_IO_CHECK='Both';
      NO_ASSERT_CHECK='TRUE';
      NO_DIR_CHECK='TRUE';
      ALLOW_CONNECT='TRUE';
    'VSS_DB54':
      PIN_NUMBER='(0,0,0,0,0,0,0,0,0,0,0,0,0,0,0,0,0,0,0,0,0,0,0,0,0,0,0,0,0,0,0,0,0,0,0,0,0,0,0,DB54)';
      PINUSE='POWER';
      NO_LOAD_CHECK='Both';
      NO_IO_CHECK='Both';
      NO_ASSERT_CHECK='TRUE';
      NO_DIR_CHECK='TRUE';
      ALLOW_CONNECT='TRUE';
    'VSS_DB59':
      PIN_NUMBER='(0,0,0,0,0,0,0,0,0,0,0,0,0,0,0,0,0,0,0,0,0,0,0,0,0,0,0,0,0,0,0,0,0,0,0,0,0,0,0,DB59)';
      PINUSE='POWER';
      NO_LOAD_CHECK='Both';
      NO_IO_CHECK='Both';
      NO_ASSERT_CHECK='TRUE';
      NO_DIR_CHECK='TRUE';
      ALLOW_CONNECT='TRUE';
    'VSS_DC13':
      PIN_NUMBER='(0,0,0,0,0,0,0,0,0,0,0,0,0,0,0,0,0,0,0,0,0,0,0,0,0,0,0,0,0,0,0,0,0,0,0,0,0,0,0,DC13)';
      PINUSE='POWER';
      NO_LOAD_CHECK='Both';
      NO_IO_CHECK='Both';
      NO_ASSERT_CHECK='TRUE';
      NO_DIR_CHECK='TRUE';
      ALLOW_CONNECT='TRUE';
    'VSS_DC15':
      PIN_NUMBER='(0,0,0,0,0,0,0,0,0,0,0,0,0,0,0,0,0,0,0,0,0,0,0,0,0,0,0,0,0,0,0,0,0,0,0,0,0,0,0,DC15)';
      PINUSE='POWER';
      NO_LOAD_CHECK='Both';
      NO_IO_CHECK='Both';
      NO_ASSERT_CHECK='TRUE';
      NO_DIR_CHECK='TRUE';
      ALLOW_CONNECT='TRUE';
    'VSS_DC45':
      PIN_NUMBER='(0,0,0,0,0,0,0,0,0,0,0,0,0,0,0,0,0,0,0,0,0,0,0,0,0,0,0,0,0,0,0,0,0,0,0,0,0,0,0,DC45)';
      PINUSE='POWER';
      NO_LOAD_CHECK='Both';
      NO_IO_CHECK='Both';
      NO_ASSERT_CHECK='TRUE';
      NO_DIR_CHECK='TRUE';
      ALLOW_CONNECT='TRUE';
    'VSS_DC48':
      PIN_NUMBER='(0,0,0,0,0,0,0,0,0,0,0,0,0,0,0,0,0,0,0,0,0,0,0,0,0,0,0,0,0,0,0,0,0,0,0,0,0,0,0,DC48)';
      PINUSE='POWER';
      NO_LOAD_CHECK='Both';
      NO_IO_CHECK='Both';
      NO_ASSERT_CHECK='TRUE';
      NO_DIR_CHECK='TRUE';
      ALLOW_CONNECT='TRUE';
    'VSS_DC51':
      PIN_NUMBER='(0,0,0,0,0,0,0,0,0,0,0,0,0,0,0,0,0,0,0,0,0,0,0,0,0,0,0,0,0,0,0,0,0,0,0,0,0,0,0,DC51)';
      PINUSE='POWER';
      NO_LOAD_CHECK='Both';
      NO_IO_CHECK='Both';
      NO_ASSERT_CHECK='TRUE';
      NO_DIR_CHECK='TRUE';
      ALLOW_CONNECT='TRUE';
    'VSS_DC70':
      PIN_NUMBER='(0,0,0,0,0,0,0,0,0,0,0,0,0,0,0,0,0,0,0,0,0,0,0,0,0,0,0,0,0,0,0,0,0,0,0,0,0,0,0,DC70)';
      PINUSE='POWER';
      NO_LOAD_CHECK='Both';
      NO_IO_CHECK='Both';
      NO_ASSERT_CHECK='TRUE';
      NO_DIR_CHECK='TRUE';
      ALLOW_CONNECT='TRUE';
    'VSS_DC72':
      PIN_NUMBER='(0,0,0,0,0,0,0,0,0,0,0,0,0,0,0,0,0,0,0,0,0,0,0,0,0,0,0,0,0,0,0,0,0,0,0,0,0,0,0,DC72)';
      PINUSE='POWER';
      NO_LOAD_CHECK='Both';
      NO_IO_CHECK='Both';
      NO_ASSERT_CHECK='TRUE';
      NO_DIR_CHECK='TRUE';
      ALLOW_CONNECT='TRUE';
    'VSS_DC75':
      PIN_NUMBER='(0,0,0,0,0,0,0,0,0,0,0,0,0,0,0,0,0,0,0,0,0,0,0,0,0,0,0,0,0,0,0,0,0,0,0,0,0,0,0,DC75)';
      PINUSE='POWER';
      NO_LOAD_CHECK='Both';
      NO_IO_CHECK='Both';
      NO_ASSERT_CHECK='TRUE';
      NO_DIR_CHECK='TRUE';
      ALLOW_CONNECT='TRUE';
    'VSS_DD3':
      PIN_NUMBER='(0,0,0,0,0,0,0,0,0,0,0,0,0,0,0,0,0,0,0,0,0,0,0,0,0,0,0,0,0,0,0,0,0,0,0,0,0,0,0,DD3)';
      PINUSE='POWER';
      NO_LOAD_CHECK='Both';
      NO_IO_CHECK='Both';
      NO_ASSERT_CHECK='TRUE';
      NO_DIR_CHECK='TRUE';
      ALLOW_CONNECT='TRUE';
    'VSS_DD23':
      PIN_NUMBER='(0,0,0,0,0,0,0,0,0,0,0,0,0,0,0,0,0,0,0,0,0,0,0,0,0,0,0,0,0,0,0,0,0,0,0,0,0,0,0,DD23)';
      PINUSE='POWER';
      NO_LOAD_CHECK='Both';
      NO_IO_CHECK='Both';
      NO_ASSERT_CHECK='TRUE';
      NO_DIR_CHECK='TRUE';
      ALLOW_CONNECT='TRUE';
    'VSS_DD24':
      PIN_NUMBER='(0,0,0,0,0,0,0,0,0,0,0,0,0,0,0,0,0,0,0,0,0,0,0,0,0,0,0,0,0,0,0,0,0,0,0,0,0,0,0,DD24)';
      PINUSE='POWER';
      NO_LOAD_CHECK='Both';
      NO_IO_CHECK='Both';
      NO_ASSERT_CHECK='TRUE';
      NO_DIR_CHECK='TRUE';
      ALLOW_CONNECT='TRUE';
    'VSS_DD26':
      PIN_NUMBER='(0,0,0,0,0,0,0,0,0,0,0,0,0,0,0,0,0,0,0,0,0,0,0,0,0,0,0,0,0,0,0,0,0,0,0,0,0,0,0,DD26)';
      PINUSE='POWER';
      NO_LOAD_CHECK='Both';
      NO_IO_CHECK='Both';
      NO_ASSERT_CHECK='TRUE';
      NO_DIR_CHECK='TRUE';
      ALLOW_CONNECT='TRUE';
    'VSS_DD27':
      PIN_NUMBER='(0,0,0,0,0,0,0,0,0,0,0,0,0,0,0,0,0,0,0,0,0,0,0,0,0,0,0,0,0,0,0,0,0,0,0,0,0,0,0,DD27)';
      PINUSE='POWER';
      NO_LOAD_CHECK='Both';
      NO_IO_CHECK='Both';
      NO_ASSERT_CHECK='TRUE';
      NO_DIR_CHECK='TRUE';
      ALLOW_CONNECT='TRUE';
    'VSS_DD39':
      PIN_NUMBER='(0,0,0,0,0,0,0,0,0,0,0,0,0,0,0,0,0,0,0,0,0,0,0,0,0,0,0,0,0,0,0,0,0,0,0,0,0,0,0,DD39)';
      PINUSE='POWER';
      NO_LOAD_CHECK='Both';
      NO_IO_CHECK='Both';
      NO_ASSERT_CHECK='TRUE';
      NO_DIR_CHECK='TRUE';
      ALLOW_CONNECT='TRUE';
    'VSS_DD40':
      PIN_NUMBER='(0,0,0,0,0,0,0,0,0,0,0,0,0,0,0,0,0,0,0,0,0,0,0,0,0,0,0,0,0,0,0,0,0,0,0,0,0,0,0,DD40)';
      PINUSE='POWER';
      NO_LOAD_CHECK='Both';
      NO_IO_CHECK='Both';
      NO_ASSERT_CHECK='TRUE';
      NO_DIR_CHECK='TRUE';
      ALLOW_CONNECT='TRUE';
    'VSS_DD41':
      PIN_NUMBER='(0,0,0,0,0,0,0,0,0,0,0,0,0,0,0,0,0,0,0,0,0,0,0,0,0,0,0,0,0,0,0,0,0,0,0,0,0,0,0,DD41)';
      PINUSE='POWER';
      NO_LOAD_CHECK='Both';
      NO_IO_CHECK='Both';
      NO_ASSERT_CHECK='TRUE';
      NO_DIR_CHECK='TRUE';
      ALLOW_CONNECT='TRUE';
    'VSS_DD43':
      PIN_NUMBER='(0,0,0,0,0,0,0,0,0,0,0,0,0,0,0,0,0,0,0,0,0,0,0,0,0,0,0,0,0,0,0,0,0,0,0,0,0,0,0,DD43)';
      PINUSE='POWER';
      NO_LOAD_CHECK='Both';
      NO_IO_CHECK='Both';
      NO_ASSERT_CHECK='TRUE';
      NO_DIR_CHECK='TRUE';
      ALLOW_CONNECT='TRUE';
    'VSS_DD57':
      PIN_NUMBER='(0,0,0,0,0,0,0,0,0,0,0,0,0,0,0,0,0,0,0,0,0,0,0,0,0,0,0,0,0,0,0,0,0,0,0,0,0,0,0,DD57)';
      PINUSE='POWER';
      NO_LOAD_CHECK='Both';
      NO_IO_CHECK='Both';
      NO_ASSERT_CHECK='TRUE';
      NO_DIR_CHECK='TRUE';
      ALLOW_CONNECT='TRUE';
    'VSS_DD59':
      PIN_NUMBER='(0,0,0,0,0,0,0,0,0,0,0,0,0,0,0,0,0,0,0,0,0,0,0,0,0,0,0,0,0,0,0,0,0,0,0,0,0,0,0,DD59)';
      PINUSE='POWER';
      NO_LOAD_CHECK='Both';
      NO_IO_CHECK='Both';
      NO_ASSERT_CHECK='TRUE';
      NO_DIR_CHECK='TRUE';
      ALLOW_CONNECT='TRUE';
    'VSS_DD61':
      PIN_NUMBER='(0,0,0,0,0,0,0,0,0,0,0,0,0,0,0,0,0,0,0,0,0,0,0,0,0,0,0,0,0,0,0,0,0,0,0,0,0,0,0,DD61)';
      PINUSE='POWER';
      NO_LOAD_CHECK='Both';
      NO_IO_CHECK='Both';
      NO_ASSERT_CHECK='TRUE';
      NO_DIR_CHECK='TRUE';
      ALLOW_CONNECT='TRUE';
    'VSS_DD64':
      PIN_NUMBER='(0,0,0,0,0,0,0,0,0,0,0,0,0,0,0,0,0,0,0,0,0,0,0,0,0,0,0,0,0,0,0,0,0,0,0,0,0,0,0,DD64)';
      PINUSE='POWER';
      NO_LOAD_CHECK='Both';
      NO_IO_CHECK='Both';
      NO_ASSERT_CHECK='TRUE';
      NO_DIR_CHECK='TRUE';
      ALLOW_CONNECT='TRUE';
    'VSS_DE13':
      PIN_NUMBER='(0,0,0,0,0,0,0,0,0,0,0,0,0,0,0,0,0,0,0,0,0,0,0,0,0,0,0,0,0,0,0,0,0,0,0,0,0,0,0,DE13)';
      PINUSE='POWER';
      NO_LOAD_CHECK='Both';
      NO_IO_CHECK='Both';
      NO_ASSERT_CHECK='TRUE';
      NO_DIR_CHECK='TRUE';
      ALLOW_CONNECT='TRUE';
    'VSS_DE15':
      PIN_NUMBER='(0,0,0,0,0,0,0,0,0,0,0,0,0,0,0,0,0,0,0,0,0,0,0,0,0,0,0,0,0,0,0,0,0,0,0,0,0,0,0,DE15)';
      PINUSE='POWER';
      NO_LOAD_CHECK='Both';
      NO_IO_CHECK='Both';
      NO_ASSERT_CHECK='TRUE';
      NO_DIR_CHECK='TRUE';
      ALLOW_CONNECT='TRUE';
    'VSS_DE20':
      PIN_NUMBER='(0,0,0,0,0,0,0,0,0,0,0,0,0,0,0,0,0,0,0,0,0,0,0,0,0,0,0,0,0,0,0,0,0,0,0,0,0,0,0,DE20)';
      PINUSE='POWER';
      NO_LOAD_CHECK='Both';
      NO_IO_CHECK='Both';
      NO_ASSERT_CHECK='TRUE';
      NO_DIR_CHECK='TRUE';
      ALLOW_CONNECT='TRUE';
    'VSS_DE23':
      PIN_NUMBER='(0,0,0,0,0,0,0,0,0,0,0,0,0,0,0,0,0,0,0,0,0,0,0,0,0,0,0,0,0,0,0,0,0,0,0,0,0,0,0,DE23)';
      PINUSE='POWER';
      NO_LOAD_CHECK='Both';
      NO_IO_CHECK='Both';
      NO_ASSERT_CHECK='TRUE';
      NO_DIR_CHECK='TRUE';
      ALLOW_CONNECT='TRUE';
    'VSS_DE70':
      PIN_NUMBER='(0,0,0,0,0,0,0,0,0,0,0,0,0,0,0,0,0,0,0,0,0,0,0,0,0,0,0,0,0,0,0,0,0,0,0,0,0,0,0,DE70)';
      PINUSE='POWER';
      NO_LOAD_CHECK='Both';
      NO_IO_CHECK='Both';
      NO_ASSERT_CHECK='TRUE';
      NO_DIR_CHECK='TRUE';
      ALLOW_CONNECT='TRUE';
    'VSS_DE75':
      PIN_NUMBER='(0,0,0,0,0,0,0,0,0,0,0,0,0,0,0,0,0,0,0,0,0,0,0,0,0,0,0,0,0,0,0,0,0,0,0,0,0,0,0,DE75)';
      PINUSE='POWER';
      NO_LOAD_CHECK='Both';
      NO_IO_CHECK='Both';
      NO_ASSERT_CHECK='TRUE';
      NO_DIR_CHECK='TRUE';
      ALLOW_CONNECT='TRUE';
    'VSS_DF3':
      PIN_NUMBER='(0,0,0,0,0,0,0,0,0,0,0,0,0,0,0,0,0,0,0,0,0,0,0,0,0,0,0,0,0,0,0,0,0,0,0,0,0,0,0,DF3)';
      PINUSE='POWER';
      NO_LOAD_CHECK='Both';
      NO_IO_CHECK='Both';
      NO_ASSERT_CHECK='TRUE';
      NO_DIR_CHECK='TRUE';
      ALLOW_CONNECT='TRUE';
    'VSS_DF4':
      PIN_NUMBER='(0,0,0,0,0,0,0,0,0,0,0,0,0,0,0,0,0,0,0,0,0,0,0,0,0,0,0,0,0,0,0,0,0,0,0,0,0,0,0,DF4)';
      PINUSE='POWER';
      NO_LOAD_CHECK='Both';
      NO_IO_CHECK='Both';
      NO_ASSERT_CHECK='TRUE';
      NO_DIR_CHECK='TRUE';
      ALLOW_CONNECT='TRUE';
    'VSS_DF15':
      PIN_NUMBER='(0,0,0,0,0,0,0,0,0,0,0,0,0,0,0,0,0,0,0,0,0,0,0,0,0,0,0,0,0,0,0,0,0,0,0,0,0,0,0,DF15)';
      PINUSE='POWER';
      NO_LOAD_CHECK='Both';
      NO_IO_CHECK='Both';
      NO_ASSERT_CHECK='TRUE';
      NO_DIR_CHECK='TRUE';
      ALLOW_CONNECT='TRUE';
    'VSS_DF17':
      PIN_NUMBER='(0,0,0,0,0,0,0,0,0,0,0,0,0,0,0,0,0,0,0,0,0,0,0,0,0,0,0,0,0,0,0,0,0,0,0,0,0,0,0,DF17)';
      PINUSE='POWER';
      NO_LOAD_CHECK='Both';
      NO_IO_CHECK='Both';
      NO_ASSERT_CHECK='TRUE';
      NO_DIR_CHECK='TRUE';
      ALLOW_CONNECT='TRUE';
    'VSS_DF18':
      PIN_NUMBER='(0,0,0,0,0,0,0,0,0,0,0,0,0,0,0,0,0,0,0,0,0,0,0,0,0,0,0,0,0,0,0,0,0,0,0,0,0,0,0,DF18)';
      PINUSE='POWER';
      NO_LOAD_CHECK='Both';
      NO_IO_CHECK='Both';
      NO_ASSERT_CHECK='TRUE';
      NO_DIR_CHECK='TRUE';
      ALLOW_CONNECT='TRUE';
    'VSS_DF19':
      PIN_NUMBER='(0,0,0,0,0,0,0,0,0,0,0,0,0,0,0,0,0,0,0,0,0,0,0,0,0,0,0,0,0,0,0,0,0,0,0,0,0,0,0,DF19)';
      PINUSE='POWER';
      NO_LOAD_CHECK='Both';
      NO_IO_CHECK='Both';
      NO_ASSERT_CHECK='TRUE';
      NO_DIR_CHECK='TRUE';
      ALLOW_CONNECT='TRUE';
    'VSS_DF43':
      PIN_NUMBER='(0,0,0,0,0,0,0,0,0,0,0,0,0,0,0,0,0,0,0,0,0,0,0,0,0,0,0,0,0,0,0,0,0,0,0,0,0,0,0,DF43)';
      PINUSE='POWER';
      NO_LOAD_CHECK='Both';
      NO_IO_CHECK='Both';
      NO_ASSERT_CHECK='TRUE';
      NO_DIR_CHECK='TRUE';
      ALLOW_CONNECT='TRUE';
    'VSS_DF53':
      PIN_NUMBER='(0,0,0,0,0,0,0,0,0,0,0,0,0,0,0,0,0,0,0,0,0,0,0,0,0,0,0,0,0,0,0,0,0,0,0,0,0,0,0,DF53)';
      PINUSE='POWER';
      NO_LOAD_CHECK='Both';
      NO_IO_CHECK='Both';
      NO_ASSERT_CHECK='TRUE';
      NO_DIR_CHECK='TRUE';
      ALLOW_CONNECT='TRUE';
    'VSS_DF54':
      PIN_NUMBER='(0,0,0,0,0,0,0,0,0,0,0,0,0,0,0,0,0,0,0,0,0,0,0,0,0,0,0,0,0,0,0,0,0,0,0,0,0,0,0,DF54)';
      PINUSE='POWER';
      NO_LOAD_CHECK='Both';
      NO_IO_CHECK='Both';
      NO_ASSERT_CHECK='TRUE';
      NO_DIR_CHECK='TRUE';
      ALLOW_CONNECT='TRUE';
    'VSS_DF66':
      PIN_NUMBER='(0,0,0,0,0,0,0,0,0,0,0,0,0,0,0,0,0,0,0,0,0,0,0,0,0,0,0,0,0,0,0,0,0,0,0,0,0,0,0,DF66)';
      PINUSE='POWER';
      NO_LOAD_CHECK='Both';
      NO_IO_CHECK='Both';
      NO_ASSERT_CHECK='TRUE';
      NO_DIR_CHECK='TRUE';
      ALLOW_CONNECT='TRUE';
    'VSS_DF68':
      PIN_NUMBER='(0,0,0,0,0,0,0,0,0,0,0,0,0,0,0,0,0,0,0,0,0,0,0,0,0,0,0,0,0,0,0,0,0,0,0,0,0,0,0,DF68)';
      PINUSE='POWER';
      NO_LOAD_CHECK='Both';
      NO_IO_CHECK='Both';
      NO_ASSERT_CHECK='TRUE';
      NO_DIR_CHECK='TRUE';
      ALLOW_CONNECT='TRUE';
    'VSS_DF70':
      PIN_NUMBER='(0,0,0,0,0,0,0,0,0,0,0,0,0,0,0,0,0,0,0,0,0,0,0,0,0,0,0,0,0,0,0,0,0,0,0,0,0,0,0,DF70)';
      PINUSE='POWER';
      NO_LOAD_CHECK='Both';
      NO_IO_CHECK='Both';
      NO_ASSERT_CHECK='TRUE';
      NO_DIR_CHECK='TRUE';
      ALLOW_CONNECT='TRUE';
    'VSS_DG8':
      PIN_NUMBER='(0,0,0,0,0,0,0,0,0,0,0,0,0,0,0,0,0,0,0,0,0,0,0,0,0,0,0,0,0,0,0,0,0,0,0,0,0,0,0,DG8)';
      PINUSE='POWER';
      NO_LOAD_CHECK='Both';
      NO_IO_CHECK='Both';
      NO_ASSERT_CHECK='TRUE';
      NO_DIR_CHECK='TRUE';
      ALLOW_CONNECT='TRUE';
    'VSS_DG9':
      PIN_NUMBER='(0,0,0,0,0,0,0,0,0,0,0,0,0,0,0,0,0,0,0,0,0,0,0,0,0,0,0,0,0,0,0,0,0,0,0,0,0,0,0,DG9)';
      PINUSE='POWER';
      NO_LOAD_CHECK='Both';
      NO_IO_CHECK='Both';
      NO_ASSERT_CHECK='TRUE';
      NO_DIR_CHECK='TRUE';
      ALLOW_CONNECT='TRUE';
    'VSS_DG13':
      PIN_NUMBER='(0,0,0,0,0,0,0,0,0,0,0,0,0,0,0,0,0,0,0,0,0,0,0,0,0,0,0,0,0,0,0,0,0,0,0,0,0,0,0,DG13)';
      PINUSE='POWER';
      NO_LOAD_CHECK='Both';
      NO_IO_CHECK='Both';
      NO_ASSERT_CHECK='TRUE';
      NO_DIR_CHECK='TRUE';
      ALLOW_CONNECT='TRUE';
    'VSS_DG14':
      PIN_NUMBER='(0,0,0,0,0,0,0,0,0,0,0,0,0,0,0,0,0,0,0,0,0,0,0,0,0,0,0,0,0,0,0,0,0,0,0,0,0,0,0,DG14)';
      PINUSE='POWER';
      NO_LOAD_CHECK='Both';
      NO_IO_CHECK='Both';
      NO_ASSERT_CHECK='TRUE';
      NO_DIR_CHECK='TRUE';
      ALLOW_CONNECT='TRUE';
    'VSS_DG30':
      PIN_NUMBER='(0,0,0,0,0,0,0,0,0,0,0,0,0,0,0,0,0,0,0,0,0,0,0,0,0,0,0,0,0,0,0,0,0,0,0,0,0,0,0,DG30)';
      PINUSE='POWER';
      NO_LOAD_CHECK='Both';
      NO_IO_CHECK='Both';
      NO_ASSERT_CHECK='TRUE';
      NO_DIR_CHECK='TRUE';
      ALLOW_CONNECT='TRUE';
    'VSS_DG33':
      PIN_NUMBER='(0,0,0,0,0,0,0,0,0,0,0,0,0,0,0,0,0,0,0,0,0,0,0,0,0,0,0,0,0,0,0,0,0,0,0,0,0,0,0,DG33)';
      PINUSE='POWER';
      NO_LOAD_CHECK='Both';
      NO_IO_CHECK='Both';
      NO_ASSERT_CHECK='TRUE';
      NO_DIR_CHECK='TRUE';
      ALLOW_CONNECT='TRUE';
    'VSS_DG41':
      PIN_NUMBER='(0,0,0,0,0,0,0,0,0,0,0,0,0,0,0,0,0,0,0,0,0,0,0,0,0,0,0,0,0,0,0,0,0,0,0,0,0,0,0,DG41)';
      PINUSE='POWER';
      NO_LOAD_CHECK='Both';
      NO_IO_CHECK='Both';
      NO_ASSERT_CHECK='TRUE';
      NO_DIR_CHECK='TRUE';
      ALLOW_CONNECT='TRUE';
    'VSS_DG43':
      PIN_NUMBER='(0,0,0,0,0,0,0,0,0,0,0,0,0,0,0,0,0,0,0,0,0,0,0,0,0,0,0,0,0,0,0,0,0,0,0,0,0,0,0,DG43)';
      PINUSE='POWER';
      NO_LOAD_CHECK='Both';
      NO_IO_CHECK='Both';
      NO_ASSERT_CHECK='TRUE';
      NO_DIR_CHECK='TRUE';
      ALLOW_CONNECT='TRUE';
    'VSS_DG61':
      PIN_NUMBER='(0,0,0,0,0,0,0,0,0,0,0,0,0,0,0,0,0,0,0,0,0,0,0,0,0,0,0,0,0,0,0,0,0,0,0,0,0,0,0,DG61)';
      PINUSE='POWER';
      NO_LOAD_CHECK='Both';
      NO_IO_CHECK='Both';
      NO_ASSERT_CHECK='TRUE';
      NO_DIR_CHECK='TRUE';
      ALLOW_CONNECT='TRUE';
    'VSS_DG62':
      PIN_NUMBER='(0,0,0,0,0,0,0,0,0,0,0,0,0,0,0,0,0,0,0,0,0,0,0,0,0,0,0,0,0,0,0,0,0,0,0,0,0,0,0,DG62)';
      PINUSE='POWER';
      NO_LOAD_CHECK='Both';
      NO_IO_CHECK='Both';
      NO_ASSERT_CHECK='TRUE';
      NO_DIR_CHECK='TRUE';
      ALLOW_CONNECT='TRUE';
    'VSS_DG63':
      PIN_NUMBER='(0,0,0,0,0,0,0,0,0,0,0,0,0,0,0,0,0,0,0,0,0,0,0,0,0,0,0,0,0,0,0,0,0,0,0,0,0,0,0,DG63)';
      PINUSE='POWER';
      NO_LOAD_CHECK='Both';
      NO_IO_CHECK='Both';
      NO_ASSERT_CHECK='TRUE';
      NO_DIR_CHECK='TRUE';
      ALLOW_CONNECT='TRUE';
    'VSS_DG65':
      PIN_NUMBER='(0,0,0,0,0,0,0,0,0,0,0,0,0,0,0,0,0,0,0,0,0,0,0,0,0,0,0,0,0,0,0,0,0,0,0,0,0,0,0,DG65)';
      PINUSE='POWER';
      NO_LOAD_CHECK='Both';
      NO_IO_CHECK='Both';
      NO_ASSERT_CHECK='TRUE';
      NO_DIR_CHECK='TRUE';
      ALLOW_CONNECT='TRUE';
    'VSS_DH5':
      PIN_NUMBER='(0,0,0,0,0,0,0,0,0,0,0,0,0,0,0,0,0,0,0,0,0,0,0,0,0,0,0,0,0,0,0,0,0,0,0,0,0,0,0,DH5)';
      PINUSE='POWER';
      NO_LOAD_CHECK='Both';
      NO_IO_CHECK='Both';
      NO_ASSERT_CHECK='TRUE';
      NO_DIR_CHECK='TRUE';
      ALLOW_CONNECT='TRUE';
    'VSS_DH11':
      PIN_NUMBER='(0,0,0,0,0,0,0,0,0,0,0,0,0,0,0,0,0,0,0,0,0,0,0,0,0,0,0,0,0,0,0,0,0,0,0,0,0,0,0,DH11)';
      PINUSE='POWER';
      NO_LOAD_CHECK='Both';
      NO_IO_CHECK='Both';
      NO_ASSERT_CHECK='TRUE';
      NO_DIR_CHECK='TRUE';
      ALLOW_CONNECT='TRUE';
    'VSS_DH18':
      PIN_NUMBER='(0,0,0,0,0,0,0,0,0,0,0,0,0,0,0,0,0,0,0,0,0,0,0,0,0,0,0,0,0,0,0,0,0,0,0,0,0,0,0,DH18)';
      PINUSE='POWER';
      NO_LOAD_CHECK='Both';
      NO_IO_CHECK='Both';
      NO_ASSERT_CHECK='TRUE';
      NO_DIR_CHECK='TRUE';
      ALLOW_CONNECT='TRUE';
    'VSS_DH37':
      PIN_NUMBER='(0,0,0,0,0,0,0,0,0,0,0,0,0,0,0,0,0,0,0,0,0,0,0,0,0,0,0,0,0,0,0,0,0,0,0,0,0,0,0,DH37)';
      PINUSE='POWER';
      NO_LOAD_CHECK='Both';
      NO_IO_CHECK='Both';
      NO_ASSERT_CHECK='TRUE';
      NO_DIR_CHECK='TRUE';
      ALLOW_CONNECT='TRUE';
    'VSS_DH61':
      PIN_NUMBER='(0,0,0,0,0,0,0,0,0,0,0,0,0,0,0,0,0,0,0,0,0,0,0,0,0,0,0,0,0,0,0,0,0,0,0,0,0,0,0,DH61)';
      PINUSE='POWER';
      NO_LOAD_CHECK='Both';
      NO_IO_CHECK='Both';
      NO_ASSERT_CHECK='TRUE';
      NO_DIR_CHECK='TRUE';
      ALLOW_CONNECT='TRUE';
    'VSS_DH63':
      PIN_NUMBER='(0,0,0,0,0,0,0,0,0,0,0,0,0,0,0,0,0,0,0,0,0,0,0,0,0,0,0,0,0,0,0,0,0,0,0,0,0,0,0,DH63)';
      PINUSE='POWER';
      NO_LOAD_CHECK='Both';
      NO_IO_CHECK='Both';
      NO_ASSERT_CHECK='TRUE';
      NO_DIR_CHECK='TRUE';
      ALLOW_CONNECT='TRUE';
    'VSS_DH64':
      PIN_NUMBER='(0,0,0,0,0,0,0,0,0,0,0,0,0,0,0,0,0,0,0,0,0,0,0,0,0,0,0,0,0,0,0,0,0,0,0,0,0,0,0,DH64)';
      PINUSE='POWER';
      NO_LOAD_CHECK='Both';
      NO_IO_CHECK='Both';
      NO_ASSERT_CHECK='TRUE';
      NO_DIR_CHECK='TRUE';
      ALLOW_CONNECT='TRUE';
    'VSS_DH66':
      PIN_NUMBER='(0,0,0,0,0,0,0,0,0,0,0,0,0,0,0,0,0,0,0,0,0,0,0,0,0,0,0,0,0,0,0,0,0,0,0,0,0,0,0,DH66)';
      PINUSE='POWER';
      NO_LOAD_CHECK='Both';
      NO_IO_CHECK='Both';
      NO_ASSERT_CHECK='TRUE';
      NO_DIR_CHECK='TRUE';
      ALLOW_CONNECT='TRUE';
    'VSS_DA72':
      PIN_NUMBER='(0,0,0,0,0,0,0,0,0,0,0,0,0,0,0,0,0,0,0,0,0,0,0,0,0,0,0,0,0,0,0,0,0,0,0,0,0,0,0,DA72)';
      PINUSE='POWER';
      NO_LOAD_CHECK='Both';
      NO_IO_CHECK='Both';
      NO_ASSERT_CHECK='TRUE';
      NO_DIR_CHECK='TRUE';
      ALLOW_CONNECT='TRUE';
    'VSS_DA75':
      PIN_NUMBER='(0,0,0,0,0,0,0,0,0,0,0,0,0,0,0,0,0,0,0,0,0,0,0,0,0,0,0,0,0,0,0,0,0,0,0,0,0,0,0,DA75)';
      PINUSE='POWER';
      NO_LOAD_CHECK='Both';
      NO_IO_CHECK='Both';
      NO_ASSERT_CHECK='TRUE';
      NO_DIR_CHECK='TRUE';
      ALLOW_CONNECT='TRUE';
    'VSS_DB3':
      PIN_NUMBER='(0,0,0,0,0,0,0,0,0,0,0,0,0,0,0,0,0,0,0,0,0,0,0,0,0,0,0,0,0,0,0,0,0,0,0,0,0,0,0,DB3)';
      PINUSE='POWER';
      NO_LOAD_CHECK='Both';
      NO_IO_CHECK='Both';
      NO_ASSERT_CHECK='TRUE';
      NO_DIR_CHECK='TRUE';
      ALLOW_CONNECT='TRUE';
    'VSS_DB8':
      PIN_NUMBER='(0,0,0,0,0,0,0,0,0,0,0,0,0,0,0,0,0,0,0,0,0,0,0,0,0,0,0,0,0,0,0,0,0,0,0,0,0,0,0,DB8)';
      PINUSE='POWER';
      NO_LOAD_CHECK='Both';
      NO_IO_CHECK='Both';
      NO_ASSERT_CHECK='TRUE';
      NO_DIR_CHECK='TRUE';
      ALLOW_CONNECT='TRUE';
    'VSS_DB10':
      PIN_NUMBER='(0,0,0,0,0,0,0,0,0,0,0,0,0,0,0,0,0,0,0,0,0,0,0,0,0,0,0,0,0,0,0,0,0,0,0,0,0,0,0,DB10)';
      PINUSE='POWER';
      NO_LOAD_CHECK='Both';
      NO_IO_CHECK='Both';
      NO_ASSERT_CHECK='TRUE';
      NO_DIR_CHECK='TRUE';
      ALLOW_CONNECT='TRUE';
    'VSS_DB28':
      PIN_NUMBER='(0,0,0,0,0,0,0,0,0,0,0,0,0,0,0,0,0,0,0,0,0,0,0,0,0,0,0,0,0,0,0,0,0,0,0,0,0,0,0,DB28)';
      PINUSE='POWER';
      NO_LOAD_CHECK='Both';
      NO_IO_CHECK='Both';
      NO_ASSERT_CHECK='TRUE';
      NO_DIR_CHECK='TRUE';
      ALLOW_CONNECT='TRUE';
    'VSS_DB31':
      PIN_NUMBER='(0,0,0,0,0,0,0,0,0,0,0,0,0,0,0,0,0,0,0,0,0,0,0,0,0,0,0,0,0,0,0,0,0,0,0,0,0,0,0,DB31)';
      PINUSE='POWER';
      NO_LOAD_CHECK='Both';
      NO_IO_CHECK='Both';
      NO_ASSERT_CHECK='TRUE';
      NO_DIR_CHECK='TRUE';
      ALLOW_CONNECT='TRUE';
    'VSS_DB34':
      PIN_NUMBER='(0,0,0,0,0,0,0,0,0,0,0,0,0,0,0,0,0,0,0,0,0,0,0,0,0,0,0,0,0,0,0,0,0,0,0,0,0,0,0,DB34)';
      PINUSE='POWER';
      NO_LOAD_CHECK='Both';
      NO_IO_CHECK='Both';
      NO_ASSERT_CHECK='TRUE';
      NO_DIR_CHECK='TRUE';
      ALLOW_CONNECT='TRUE';
    'VSS_DB37':
      PIN_NUMBER='(0,0,0,0,0,0,0,0,0,0,0,0,0,0,0,0,0,0,0,0,0,0,0,0,0,0,0,0,0,0,0,0,0,0,0,0,0,0,0,DB37)';
      PINUSE='POWER';
      NO_LOAD_CHECK='Both';
      NO_IO_CHECK='Both';
      NO_ASSERT_CHECK='TRUE';
      NO_DIR_CHECK='TRUE';
      ALLOW_CONNECT='TRUE';
    'VSS_DB39':
      PIN_NUMBER='(0,0,0,0,0,0,0,0,0,0,0,0,0,0,0,0,0,0,0,0,0,0,0,0,0,0,0,0,0,0,0,0,0,0,0,0,0,0,0,DB39)';
      PINUSE='POWER';
      NO_LOAD_CHECK='Both';
      NO_IO_CHECK='Both';
      NO_ASSERT_CHECK='TRUE';
      NO_DIR_CHECK='TRUE';
      ALLOW_CONNECT='TRUE';
    'VSS_DB42':
      PIN_NUMBER='(0,0,0,0,0,0,0,0,0,0,0,0,0,0,0,0,0,0,0,0,0,0,0,0,0,0,0,0,0,0,0,0,0,0,0,0,0,0,0,DB42)';
      PINUSE='POWER';
      NO_LOAD_CHECK='Both';
      NO_IO_CHECK='Both';
      NO_ASSERT_CHECK='TRUE';
      NO_DIR_CHECK='TRUE';
      ALLOW_CONNECT='TRUE';
    'VSS_DB45':
      PIN_NUMBER='(0,0,0,0,0,0,0,0,0,0,0,0,0,0,0,0,0,0,0,0,0,0,0,0,0,0,0,0,0,0,0,0,0,0,0,0,0,0,0,DB45)';
      PINUSE='POWER';
      NO_LOAD_CHECK='Both';
      NO_IO_CHECK='Both';
      NO_ASSERT_CHECK='TRUE';
      NO_DIR_CHECK='TRUE';
      ALLOW_CONNECT='TRUE';
    'VSS_DB61':
      PIN_NUMBER='(0,0,0,0,0,0,0,0,0,0,0,0,0,0,0,0,0,0,0,0,0,0,0,0,0,0,0,0,0,0,0,0,0,0,0,0,0,0,0,DB61)';
      PINUSE='POWER';
      NO_LOAD_CHECK='Both';
      NO_IO_CHECK='Both';
      NO_ASSERT_CHECK='TRUE';
      NO_DIR_CHECK='TRUE';
      ALLOW_CONNECT='TRUE';
    'VSS_DB66':
      PIN_NUMBER='(0,0,0,0,0,0,0,0,0,0,0,0,0,0,0,0,0,0,0,0,0,0,0,0,0,0,0,0,0,0,0,0,0,0,0,0,0,0,0,DB66)';
      PINUSE='POWER';
      NO_LOAD_CHECK='Both';
      NO_IO_CHECK='Both';
      NO_ASSERT_CHECK='TRUE';
      NO_DIR_CHECK='TRUE';
      ALLOW_CONNECT='TRUE';
    'VSS_DB68':
      PIN_NUMBER='(0,0,0,0,0,0,0,0,0,0,0,0,0,0,0,0,0,0,0,0,0,0,0,0,0,0,0,0,0,0,0,0,0,0,0,0,0,0,0,DB68)';
      PINUSE='POWER';
      NO_LOAD_CHECK='Both';
      NO_IO_CHECK='Both';
      NO_ASSERT_CHECK='TRUE';
      NO_DIR_CHECK='TRUE';
      ALLOW_CONNECT='TRUE';
    'VSS_DB73':
      PIN_NUMBER='(0,0,0,0,0,0,0,0,0,0,0,0,0,0,0,0,0,0,0,0,0,0,0,0,0,0,0,0,0,0,0,0,0,0,0,0,0,0,0,DB73)';
      PINUSE='POWER';
      NO_LOAD_CHECK='Both';
      NO_IO_CHECK='Both';
      NO_ASSERT_CHECK='TRUE';
      NO_DIR_CHECK='TRUE';
      ALLOW_CONNECT='TRUE';
    'VSS_DC1':
      PIN_NUMBER='(0,0,0,0,0,0,0,0,0,0,0,0,0,0,0,0,0,0,0,0,0,0,0,0,0,0,0,0,0,0,0,0,0,0,0,0,0,0,0,DC1)';
      PINUSE='POWER';
      NO_LOAD_CHECK='Both';
      NO_IO_CHECK='Both';
      NO_ASSERT_CHECK='TRUE';
      NO_DIR_CHECK='TRUE';
      ALLOW_CONNECT='TRUE';
    'VSS_DC4':
      PIN_NUMBER='(0,0,0,0,0,0,0,0,0,0,0,0,0,0,0,0,0,0,0,0,0,0,0,0,0,0,0,0,0,0,0,0,0,0,0,0,0,0,0,DC4)';
      PINUSE='POWER';
      NO_LOAD_CHECK='Both';
      NO_IO_CHECK='Both';
      NO_ASSERT_CHECK='TRUE';
      NO_DIR_CHECK='TRUE';
      ALLOW_CONNECT='TRUE';
    'VSS_DC6':
      PIN_NUMBER='(0,0,0,0,0,0,0,0,0,0,0,0,0,0,0,0,0,0,0,0,0,0,0,0,0,0,0,0,0,0,0,0,0,0,0,0,0,0,0,DC6)';
      PINUSE='POWER';
      NO_LOAD_CHECK='Both';
      NO_IO_CHECK='Both';
      NO_ASSERT_CHECK='TRUE';
      NO_DIR_CHECK='TRUE';
      ALLOW_CONNECT='TRUE';
    'VSS_DC8':
      PIN_NUMBER='(0,0,0,0,0,0,0,0,0,0,0,0,0,0,0,0,0,0,0,0,0,0,0,0,0,0,0,0,0,0,0,0,0,0,0,0,0,0,0,DC8)';
      PINUSE='POWER';
      NO_LOAD_CHECK='Both';
      NO_IO_CHECK='Both';
      NO_ASSERT_CHECK='TRUE';
      NO_DIR_CHECK='TRUE';
      ALLOW_CONNECT='TRUE';
    'VSS_DC11':
      PIN_NUMBER='(0,0,0,0,0,0,0,0,0,0,0,0,0,0,0,0,0,0,0,0,0,0,0,0,0,0,0,0,0,0,0,0,0,0,0,0,0,0,0,DC11)';
      PINUSE='POWER';
      NO_LOAD_CHECK='Both';
      NO_IO_CHECK='Both';
      NO_ASSERT_CHECK='TRUE';
      NO_DIR_CHECK='TRUE';
      ALLOW_CONNECT='TRUE';
    'VSS_DC18':
      PIN_NUMBER='(0,0,0,0,0,0,0,0,0,0,0,0,0,0,0,0,0,0,0,0,0,0,0,0,0,0,0,0,0,0,0,0,0,0,0,0,0,0,0,DC18)';
      PINUSE='POWER';
      NO_LOAD_CHECK='Both';
      NO_IO_CHECK='Both';
      NO_ASSERT_CHECK='TRUE';
      NO_DIR_CHECK='TRUE';
      ALLOW_CONNECT='TRUE';
    'VSS_DC20':
      PIN_NUMBER='(0,0,0,0,0,0,0,0,0,0,0,0,0,0,0,0,0,0,0,0,0,0,0,0,0,0,0,0,0,0,0,0,0,0,0,0,0,0,0,DC20)';
      PINUSE='POWER';
      NO_LOAD_CHECK='Both';
      NO_IO_CHECK='Both';
      NO_ASSERT_CHECK='TRUE';
      NO_DIR_CHECK='TRUE';
      ALLOW_CONNECT='TRUE';
    'VSS_DC22':
      PIN_NUMBER='(0,0,0,0,0,0,0,0,0,0,0,0,0,0,0,0,0,0,0,0,0,0,0,0,0,0,0,0,0,0,0,0,0,0,0,0,0,0,0,DC22)';
      PINUSE='POWER';
      NO_LOAD_CHECK='Both';
      NO_IO_CHECK='Both';
      NO_ASSERT_CHECK='TRUE';
      NO_DIR_CHECK='TRUE';
      ALLOW_CONNECT='TRUE';
    'VSS_DC25':
      PIN_NUMBER='(0,0,0,0,0,0,0,0,0,0,0,0,0,0,0,0,0,0,0,0,0,0,0,0,0,0,0,0,0,0,0,0,0,0,0,0,0,0,0,DC25)';
      PINUSE='POWER';
      NO_LOAD_CHECK='Both';
      NO_IO_CHECK='Both';
      NO_ASSERT_CHECK='TRUE';
      NO_DIR_CHECK='TRUE';
      ALLOW_CONNECT='TRUE';
    'VSS_DC28':
      PIN_NUMBER='(0,0,0,0,0,0,0,0,0,0,0,0,0,0,0,0,0,0,0,0,0,0,0,0,0,0,0,0,0,0,0,0,0,0,0,0,0,0,0,DC28)';
      PINUSE='POWER';
      NO_LOAD_CHECK='Both';
      NO_IO_CHECK='Both';
      NO_ASSERT_CHECK='TRUE';
      NO_DIR_CHECK='TRUE';
      ALLOW_CONNECT='TRUE';
    'VSS_DC31':
      PIN_NUMBER='(0,0,0,0,0,0,0,0,0,0,0,0,0,0,0,0,0,0,0,0,0,0,0,0,0,0,0,0,0,0,0,0,0,0,0,0,0,0,0,DC31)';
      PINUSE='POWER';
      NO_LOAD_CHECK='Both';
      NO_IO_CHECK='Both';
      NO_ASSERT_CHECK='TRUE';
      NO_DIR_CHECK='TRUE';
      ALLOW_CONNECT='TRUE';
    'VSS_DC34':
      PIN_NUMBER='(0,0,0,0,0,0,0,0,0,0,0,0,0,0,0,0,0,0,0,0,0,0,0,0,0,0,0,0,0,0,0,0,0,0,0,0,0,0,0,DC34)';
      PINUSE='POWER';
      NO_LOAD_CHECK='Both';
      NO_IO_CHECK='Both';
      NO_ASSERT_CHECK='TRUE';
      NO_DIR_CHECK='TRUE';
      ALLOW_CONNECT='TRUE';
    'VSS_DC42':
      PIN_NUMBER='(0,0,0,0,0,0,0,0,0,0,0,0,0,0,0,0,0,0,0,0,0,0,0,0,0,0,0,0,0,0,0,0,0,0,0,0,0,0,0,DC42)';
      PINUSE='POWER';
      NO_LOAD_CHECK='Both';
      NO_IO_CHECK='Both';
      NO_ASSERT_CHECK='TRUE';
      NO_DIR_CHECK='TRUE';
      ALLOW_CONNECT='TRUE';
    'VSS_DC54':
      PIN_NUMBER='(0,0,0,0,0,0,0,0,0,0,0,0,0,0,0,0,0,0,0,0,0,0,0,0,0,0,0,0,0,0,0,0,0,0,0,0,0,0,0,DC54)';
      PINUSE='POWER';
      NO_LOAD_CHECK='Both';
      NO_IO_CHECK='Both';
      NO_ASSERT_CHECK='TRUE';
      NO_DIR_CHECK='TRUE';
      ALLOW_CONNECT='TRUE';
    'VSS_DC56':
      PIN_NUMBER='(0,0,0,0,0,0,0,0,0,0,0,0,0,0,0,0,0,0,0,0,0,0,0,0,0,0,0,0,0,0,0,0,0,0,0,0,0,0,0,DC56)';
      PINUSE='POWER';
      NO_LOAD_CHECK='Both';
      NO_IO_CHECK='Both';
      NO_ASSERT_CHECK='TRUE';
      NO_DIR_CHECK='TRUE';
      ALLOW_CONNECT='TRUE';
    'VSS_DC58':
      PIN_NUMBER='(0,0,0,0,0,0,0,0,0,0,0,0,0,0,0,0,0,0,0,0,0,0,0,0,0,0,0,0,0,0,0,0,0,0,0,0,0,0,0,DC58)';
      PINUSE='POWER';
      NO_LOAD_CHECK='Both';
      NO_IO_CHECK='Both';
      NO_ASSERT_CHECK='TRUE';
      NO_DIR_CHECK='TRUE';
      ALLOW_CONNECT='TRUE';
    'VSS_DC61':
      PIN_NUMBER='(0,0,0,0,0,0,0,0,0,0,0,0,0,0,0,0,0,0,0,0,0,0,0,0,0,0,0,0,0,0,0,0,0,0,0,0,0,0,0,DC61)';
      PINUSE='POWER';
      NO_LOAD_CHECK='Both';
      NO_IO_CHECK='Both';
      NO_ASSERT_CHECK='TRUE';
      NO_DIR_CHECK='TRUE';
      ALLOW_CONNECT='TRUE';
    'VSS_DC63':
      PIN_NUMBER='(0,0,0,0,0,0,0,0,0,0,0,0,0,0,0,0,0,0,0,0,0,0,0,0,0,0,0,0,0,0,0,0,0,0,0,0,0,0,0,DC63)';
      PINUSE='POWER';
      NO_LOAD_CHECK='Both';
      NO_IO_CHECK='Both';
      NO_ASSERT_CHECK='TRUE';
      NO_DIR_CHECK='TRUE';
      ALLOW_CONNECT='TRUE';
    'VSS_DC65':
      PIN_NUMBER='(0,0,0,0,0,0,0,0,0,0,0,0,0,0,0,0,0,0,0,0,0,0,0,0,0,0,0,0,0,0,0,0,0,0,0,0,0,0,0,DC65)';
      PINUSE='POWER';
      NO_LOAD_CHECK='Both';
      NO_IO_CHECK='Both';
      NO_ASSERT_CHECK='TRUE';
      NO_DIR_CHECK='TRUE';
      ALLOW_CONNECT='TRUE';
    'VSS_DC68':
      PIN_NUMBER='(0,0,0,0,0,0,0,0,0,0,0,0,0,0,0,0,0,0,0,0,0,0,0,0,0,0,0,0,0,0,0,0,0,0,0,0,0,0,0,DC68)';
      PINUSE='POWER';
      NO_LOAD_CHECK='Both';
      NO_IO_CHECK='Both';
      NO_ASSERT_CHECK='TRUE';
      NO_DIR_CHECK='TRUE';
      ALLOW_CONNECT='TRUE';
    'VSS_DD5':
      PIN_NUMBER='(0,0,0,0,0,0,0,0,0,0,0,0,0,0,0,0,0,0,0,0,0,0,0,0,0,0,0,0,0,0,0,0,0,0,0,0,0,0,0,DD5)';
      PINUSE='POWER';
      NO_LOAD_CHECK='Both';
      NO_IO_CHECK='Both';
      NO_ASSERT_CHECK='TRUE';
      NO_DIR_CHECK='TRUE';
      ALLOW_CONNECT='TRUE';
    'VSS_DD8':
      PIN_NUMBER='(0,0,0,0,0,0,0,0,0,0,0,0,0,0,0,0,0,0,0,0,0,0,0,0,0,0,0,0,0,0,0,0,0,0,0,0,0,0,0,DD8)';
      PINUSE='POWER';
      NO_LOAD_CHECK='Both';
      NO_IO_CHECK='Both';
      NO_ASSERT_CHECK='TRUE';
      NO_DIR_CHECK='TRUE';
      ALLOW_CONNECT='TRUE';
    'VSS_DD10':
      PIN_NUMBER='(0,0,0,0,0,0,0,0,0,0,0,0,0,0,0,0,0,0,0,0,0,0,0,0,0,0,0,0,0,0,0,0,0,0,0,0,0,0,0,DD10)';
      PINUSE='POWER';
      NO_LOAD_CHECK='Both';
      NO_IO_CHECK='Both';
      NO_ASSERT_CHECK='TRUE';
      NO_DIR_CHECK='TRUE';
      ALLOW_CONNECT='TRUE';
    'VSS_DD12':
      PIN_NUMBER='(0,0,0,0,0,0,0,0,0,0,0,0,0,0,0,0,0,0,0,0,0,0,0,0,0,0,0,0,0,0,0,0,0,0,0,0,0,0,0,DD12)';
      PINUSE='POWER';
      NO_LOAD_CHECK='Both';
      NO_IO_CHECK='Both';
      NO_ASSERT_CHECK='TRUE';
      NO_DIR_CHECK='TRUE';
      ALLOW_CONNECT='TRUE';
    'VSS_DD15':
      PIN_NUMBER='(0,0,0,0,0,0,0,0,0,0,0,0,0,0,0,0,0,0,0,0,0,0,0,0,0,0,0,0,0,0,0,0,0,0,0,0,0,0,0,DD15)';
      PINUSE='POWER';
      NO_LOAD_CHECK='Both';
      NO_IO_CHECK='Both';
      NO_ASSERT_CHECK='TRUE';
      NO_DIR_CHECK='TRUE';
      ALLOW_CONNECT='TRUE';
    'VSS_DD17':
      PIN_NUMBER='(0,0,0,0,0,0,0,0,0,0,0,0,0,0,0,0,0,0,0,0,0,0,0,0,0,0,0,0,0,0,0,0,0,0,0,0,0,0,0,DD17)';
      PINUSE='POWER';
      NO_LOAD_CHECK='Both';
      NO_IO_CHECK='Both';
      NO_ASSERT_CHECK='TRUE';
      NO_DIR_CHECK='TRUE';
      ALLOW_CONNECT='TRUE';
    'VSS_DD19':
      PIN_NUMBER='(0,0,0,0,0,0,0,0,0,0,0,0,0,0,0,0,0,0,0,0,0,0,0,0,0,0,0,0,0,0,0,0,0,0,0,0,0,0,0,DD19)';
      PINUSE='POWER';
      NO_LOAD_CHECK='Both';
      NO_IO_CHECK='Both';
      NO_ASSERT_CHECK='TRUE';
      NO_DIR_CHECK='TRUE';
      ALLOW_CONNECT='TRUE';
    'VSS_DD29':
      PIN_NUMBER='(0,0,0,0,0,0,0,0,0,0,0,0,0,0,0,0,0,0,0,0,0,0,0,0,0,0,0,0,0,0,0,0,0,0,0,0,0,0,0,DD29)';
      PINUSE='POWER';
      NO_LOAD_CHECK='Both';
      NO_IO_CHECK='Both';
      NO_ASSERT_CHECK='TRUE';
      NO_DIR_CHECK='TRUE';
      ALLOW_CONNECT='TRUE';
    'VSS_DD30':
      PIN_NUMBER='(0,0,0,0,0,0,0,0,0,0,0,0,0,0,0,0,0,0,0,0,0,0,0,0,0,0,0,0,0,0,0,0,0,0,0,0,0,0,0,DD30)';
      PINUSE='POWER';
      NO_LOAD_CHECK='Both';
      NO_IO_CHECK='Both';
      NO_ASSERT_CHECK='TRUE';
      NO_DIR_CHECK='TRUE';
      ALLOW_CONNECT='TRUE';
    'VSS_DD32':
      PIN_NUMBER='(0,0,0,0,0,0,0,0,0,0,0,0,0,0,0,0,0,0,0,0,0,0,0,0,0,0,0,0,0,0,0,0,0,0,0,0,0,0,0,DD32)';
      PINUSE='POWER';
      NO_LOAD_CHECK='Both';
      NO_IO_CHECK='Both';
      NO_ASSERT_CHECK='TRUE';
      NO_DIR_CHECK='TRUE';
      ALLOW_CONNECT='TRUE';
    'VSS_DD33':
      PIN_NUMBER='(0,0,0,0,0,0,0,0,0,0,0,0,0,0,0,0,0,0,0,0,0,0,0,0,0,0,0,0,0,0,0,0,0,0,0,0,0,0,0,DD33)';
      PINUSE='POWER';
      NO_LOAD_CHECK='Both';
      NO_IO_CHECK='Both';
      NO_ASSERT_CHECK='TRUE';
      NO_DIR_CHECK='TRUE';
      ALLOW_CONNECT='TRUE';
    'VSS_DD35':
      PIN_NUMBER='(0,0,0,0,0,0,0,0,0,0,0,0,0,0,0,0,0,0,0,0,0,0,0,0,0,0,0,0,0,0,0,0,0,0,0,0,0,0,0,DD35)';
      PINUSE='POWER';
      NO_LOAD_CHECK='Both';
      NO_IO_CHECK='Both';
      NO_ASSERT_CHECK='TRUE';
      NO_DIR_CHECK='TRUE';
      ALLOW_CONNECT='TRUE';
    'VSS_DD36':
      PIN_NUMBER='(0,0,0,0,0,0,0,0,0,0,0,0,0,0,0,0,0,0,0,0,0,0,0,0,0,0,0,0,0,0,0,0,0,0,0,0,0,0,0,DD36)';
      PINUSE='POWER';
      NO_LOAD_CHECK='Both';
      NO_IO_CHECK='Both';
      NO_ASSERT_CHECK='TRUE';
      NO_DIR_CHECK='TRUE';
      ALLOW_CONNECT='TRUE';
    'VSS_DD37':
      PIN_NUMBER='(0,0,0,0,0,0,0,0,0,0,0,0,0,0,0,0,0,0,0,0,0,0,0,0,0,0,0,0,0,0,0,0,0,0,0,0,0,0,0,DD37)';
      PINUSE='POWER';
      NO_LOAD_CHECK='Both';
      NO_IO_CHECK='Both';
      NO_ASSERT_CHECK='TRUE';
      NO_DIR_CHECK='TRUE';
      ALLOW_CONNECT='TRUE';
    'VSS_DD44':
      PIN_NUMBER='(0,0,0,0,0,0,0,0,0,0,0,0,0,0,0,0,0,0,0,0,0,0,0,0,0,0,0,0,0,0,0,0,0,0,0,0,0,0,0,DD44)';
      PINUSE='POWER';
      NO_LOAD_CHECK='Both';
      NO_IO_CHECK='Both';
      NO_ASSERT_CHECK='TRUE';
      NO_DIR_CHECK='TRUE';
      ALLOW_CONNECT='TRUE';
    'VSS_DD46':
      PIN_NUMBER='(0,0,0,0,0,0,0,0,0,0,0,0,0,0,0,0,0,0,0,0,0,0,0,0,0,0,0,0,0,0,0,0,0,0,0,0,0,0,0,DD46)';
      PINUSE='POWER';
      NO_LOAD_CHECK='Both';
      NO_IO_CHECK='Both';
      NO_ASSERT_CHECK='TRUE';
      NO_DIR_CHECK='TRUE';
      ALLOW_CONNECT='TRUE';
    'VSS_DD47':
      PIN_NUMBER='(0,0,0,0,0,0,0,0,0,0,0,0,0,0,0,0,0,0,0,0,0,0,0,0,0,0,0,0,0,0,0,0,0,0,0,0,0,0,0,DD47)';
      PINUSE='POWER';
      NO_LOAD_CHECK='Both';
      NO_IO_CHECK='Both';
      NO_ASSERT_CHECK='TRUE';
      NO_DIR_CHECK='TRUE';
      ALLOW_CONNECT='TRUE';
    'VSS_DD49':
      PIN_NUMBER='(0,0,0,0,0,0,0,0,0,0,0,0,0,0,0,0,0,0,0,0,0,0,0,0,0,0,0,0,0,0,0,0,0,0,0,0,0,0,0,DD49)';
      PINUSE='POWER';
      NO_LOAD_CHECK='Both';
      NO_IO_CHECK='Both';
      NO_ASSERT_CHECK='TRUE';
      NO_DIR_CHECK='TRUE';
      ALLOW_CONNECT='TRUE';
    'VSS_DD50':
      PIN_NUMBER='(0,0,0,0,0,0,0,0,0,0,0,0,0,0,0,0,0,0,0,0,0,0,0,0,0,0,0,0,0,0,0,0,0,0,0,0,0,0,0,DD50)';
      PINUSE='POWER';
      NO_LOAD_CHECK='Both';
      NO_IO_CHECK='Both';
      NO_ASSERT_CHECK='TRUE';
      NO_DIR_CHECK='TRUE';
      ALLOW_CONNECT='TRUE';
    'VSS_DD52':
      PIN_NUMBER='(0,0,0,0,0,0,0,0,0,0,0,0,0,0,0,0,0,0,0,0,0,0,0,0,0,0,0,0,0,0,0,0,0,0,0,0,0,0,0,DD52)';
      PINUSE='POWER';
      NO_LOAD_CHECK='Both';
      NO_IO_CHECK='Both';
      NO_ASSERT_CHECK='TRUE';
      NO_DIR_CHECK='TRUE';
      ALLOW_CONNECT='TRUE';
    'VSS_DD53':
      PIN_NUMBER='(0,0,0,0,0,0,0,0,0,0,0,0,0,0,0,0,0,0,0,0,0,0,0,0,0,0,0,0,0,0,0,0,0,0,0,0,0,0,0,DD53)';
      PINUSE='POWER';
      NO_LOAD_CHECK='Both';
      NO_IO_CHECK='Both';
      NO_ASSERT_CHECK='TRUE';
      NO_DIR_CHECK='TRUE';
      ALLOW_CONNECT='TRUE';
    'VSS_DD66':
      PIN_NUMBER='(0,0,0,0,0,0,0,0,0,0,0,0,0,0,0,0,0,0,0,0,0,0,0,0,0,0,0,0,0,0,0,0,0,0,0,0,0,0,0,DD66)';
      PINUSE='POWER';
      NO_LOAD_CHECK='Both';
      NO_IO_CHECK='Both';
      NO_ASSERT_CHECK='TRUE';
      NO_DIR_CHECK='TRUE';
      ALLOW_CONNECT='TRUE';
    'VSS_DD68':
      PIN_NUMBER='(0,0,0,0,0,0,0,0,0,0,0,0,0,0,0,0,0,0,0,0,0,0,0,0,0,0,0,0,0,0,0,0,0,0,0,0,0,0,0,DD68)';
      PINUSE='POWER';
      NO_LOAD_CHECK='Both';
      NO_IO_CHECK='Both';
      NO_ASSERT_CHECK='TRUE';
      NO_DIR_CHECK='TRUE';
      ALLOW_CONNECT='TRUE';
    'VSS_DD71':
      PIN_NUMBER='(0,0,0,0,0,0,0,0,0,0,0,0,0,0,0,0,0,0,0,0,0,0,0,0,0,0,0,0,0,0,0,0,0,0,0,0,0,0,0,DD71)';
      PINUSE='POWER';
      NO_LOAD_CHECK='Both';
      NO_IO_CHECK='Both';
      NO_ASSERT_CHECK='TRUE';
      NO_DIR_CHECK='TRUE';
      ALLOW_CONNECT='TRUE';
    'VSS_DD73':
      PIN_NUMBER='(0,0,0,0,0,0,0,0,0,0,0,0,0,0,0,0,0,0,0,0,0,0,0,0,0,0,0,0,0,0,0,0,0,0,0,0,0,0,0,DD73)';
      PINUSE='POWER';
      NO_LOAD_CHECK='Both';
      NO_IO_CHECK='Both';
      NO_ASSERT_CHECK='TRUE';
      NO_DIR_CHECK='TRUE';
      ALLOW_CONNECT='TRUE';
    'VSS_DE1':
      PIN_NUMBER='(0,0,0,0,0,0,0,0,0,0,0,0,0,0,0,0,0,0,0,0,0,0,0,0,0,0,0,0,0,0,0,0,0,0,0,0,0,0,0,DE1)';
      PINUSE='POWER';
      NO_LOAD_CHECK='Both';
      NO_IO_CHECK='Both';
      NO_ASSERT_CHECK='TRUE';
      NO_DIR_CHECK='TRUE';
      ALLOW_CONNECT='TRUE';
    'VSS_DE6':
      PIN_NUMBER='(0,0,0,0,0,0,0,0,0,0,0,0,0,0,0,0,0,0,0,0,0,0,0,0,0,0,0,0,0,0,0,0,0,0,0,0,0,0,0,DE6)';
      PINUSE='POWER';
      NO_LOAD_CHECK='Both';
      NO_IO_CHECK='Both';
      NO_ASSERT_CHECK='TRUE';
      NO_DIR_CHECK='TRUE';
      ALLOW_CONNECT='TRUE';
    'VSS_DE8':
      PIN_NUMBER='(0,0,0,0,0,0,0,0,0,0,0,0,0,0,0,0,0,0,0,0,0,0,0,0,0,0,0,0,0,0,0,0,0,0,0,0,0,0,0,DE8)';
      PINUSE='POWER';
      NO_LOAD_CHECK='Both';
      NO_IO_CHECK='Both';
      NO_ASSERT_CHECK='TRUE';
      NO_DIR_CHECK='TRUE';
      ALLOW_CONNECT='TRUE';
    'VSS_DE26':
      PIN_NUMBER='(0,0,0,0,0,0,0,0,0,0,0,0,0,0,0,0,0,0,0,0,0,0,0,0,0,0,0,0,0,0,0,0,0,0,0,0,0,0,0,DE26)';
      PINUSE='POWER';
      NO_LOAD_CHECK='Both';
      NO_IO_CHECK='Both';
      NO_ASSERT_CHECK='TRUE';
      NO_DIR_CHECK='TRUE';
      ALLOW_CONNECT='TRUE';
    'VSS_DE29':
      PIN_NUMBER='(0,0,0,0,0,0,0,0,0,0,0,0,0,0,0,0,0,0,0,0,0,0,0,0,0,0,0,0,0,0,0,0,0,0,0,0,0,0,0,DE29)';
      PINUSE='POWER';
      NO_LOAD_CHECK='Both';
      NO_IO_CHECK='Both';
      NO_ASSERT_CHECK='TRUE';
      NO_DIR_CHECK='TRUE';
      ALLOW_CONNECT='TRUE';
    'VSS_DE33':
      PIN_NUMBER='(0,0,0,0,0,0,0,0,0,0,0,0,0,0,0,0,0,0,0,0,0,0,0,0,0,0,0,0,0,0,0,0,0,0,0,0,0,0,0,DE33)';
      PINUSE='POWER';
      NO_LOAD_CHECK='Both';
      NO_IO_CHECK='Both';
      NO_ASSERT_CHECK='TRUE';
      NO_DIR_CHECK='TRUE';
      ALLOW_CONNECT='TRUE';
    'VSS_DE56':
      PIN_NUMBER='(0,0,0,0,0,0,0,0,0,0,0,0,0,0,0,0,0,0,0,0,0,0,0,0,0,0,0,0,0,0,0,0,0,0,0,0,0,0,0,DE56)';
      PINUSE='POWER';
      NO_LOAD_CHECK='Both';
      NO_IO_CHECK='Both';
      NO_ASSERT_CHECK='TRUE';
      NO_DIR_CHECK='TRUE';
      ALLOW_CONNECT='TRUE';
    'VSS_DE61':
      PIN_NUMBER='(0,0,0,0,0,0,0,0,0,0,0,0,0,0,0,0,0,0,0,0,0,0,0,0,0,0,0,0,0,0,0,0,0,0,0,0,0,0,0,DE61)';
      PINUSE='POWER';
      NO_LOAD_CHECK='Both';
      NO_IO_CHECK='Both';
      NO_ASSERT_CHECK='TRUE';
      NO_DIR_CHECK='TRUE';
      ALLOW_CONNECT='TRUE';
    'VSS_DE63':
      PIN_NUMBER='(0,0,0,0,0,0,0,0,0,0,0,0,0,0,0,0,0,0,0,0,0,0,0,0,0,0,0,0,0,0,0,0,0,0,0,0,0,0,0,DE63)';
      PINUSE='POWER';
      NO_LOAD_CHECK='Both';
      NO_IO_CHECK='Both';
      NO_ASSERT_CHECK='TRUE';
      NO_DIR_CHECK='TRUE';
      ALLOW_CONNECT='TRUE';
    'VSS_DE68':
      PIN_NUMBER='(0,0,0,0,0,0,0,0,0,0,0,0,0,0,0,0,0,0,0,0,0,0,0,0,0,0,0,0,0,0,0,0,0,0,0,0,0,0,0,DE68)';
      PINUSE='POWER';
      NO_LOAD_CHECK='Both';
      NO_IO_CHECK='Both';
      NO_ASSERT_CHECK='TRUE';
      NO_DIR_CHECK='TRUE';
      ALLOW_CONNECT='TRUE';
    'VSS_DF5':
      PIN_NUMBER='(0,0,0,0,0,0,0,0,0,0,0,0,0,0,0,0,0,0,0,0,0,0,0,0,0,0,0,0,0,0,0,0,0,0,0,0,0,0,0,DF5)';
      PINUSE='POWER';
      NO_LOAD_CHECK='Both';
      NO_IO_CHECK='Both';
      NO_ASSERT_CHECK='TRUE';
      NO_DIR_CHECK='TRUE';
      ALLOW_CONNECT='TRUE';
    'VSS_DF6':
      PIN_NUMBER='(0,0,0,0,0,0,0,0,0,0,0,0,0,0,0,0,0,0,0,0,0,0,0,0,0,0,0,0,0,0,0,0,0,0,0,0,0,0,0,DF6)';
      PINUSE='POWER';
      NO_LOAD_CHECK='Both';
      NO_IO_CHECK='Both';
      NO_ASSERT_CHECK='TRUE';
      NO_DIR_CHECK='TRUE';
      ALLOW_CONNECT='TRUE';
    'VSS_DF8':
      PIN_NUMBER='(0,0,0,0,0,0,0,0,0,0,0,0,0,0,0,0,0,0,0,0,0,0,0,0,0,0,0,0,0,0,0,0,0,0,0,0,0,0,0,DF8)';
      PINUSE='POWER';
      NO_LOAD_CHECK='Both';
      NO_IO_CHECK='Both';
      NO_ASSERT_CHECK='TRUE';
      NO_DIR_CHECK='TRUE';
      ALLOW_CONNECT='TRUE';
    'VSS_DF10':
      PIN_NUMBER='(0,0,0,0,0,0,0,0,0,0,0,0,0,0,0,0,0,0,0,0,0,0,0,0,0,0,0,0,0,0,0,0,0,0,0,0,0,0,0,DF10)';
      PINUSE='POWER';
      NO_LOAD_CHECK='Both';
      NO_IO_CHECK='Both';
      NO_ASSERT_CHECK='TRUE';
      NO_DIR_CHECK='TRUE';
      ALLOW_CONNECT='TRUE';
    'VSS_DF11':
      PIN_NUMBER='(0,0,0,0,0,0,0,0,0,0,0,0,0,0,0,0,0,0,0,0,0,0,0,0,0,0,0,0,0,0,0,0,0,0,0,0,0,0,0,DF11)';
      PINUSE='POWER';
      NO_LOAD_CHECK='Both';
      NO_IO_CHECK='Both';
      NO_ASSERT_CHECK='TRUE';
      NO_DIR_CHECK='TRUE';
      ALLOW_CONNECT='TRUE';
    'VSS_DF12':
      PIN_NUMBER='(0,0,0,0,0,0,0,0,0,0,0,0,0,0,0,0,0,0,0,0,0,0,0,0,0,0,0,0,0,0,0,0,0,0,0,0,0,0,0,DF12)';
      PINUSE='POWER';
      NO_LOAD_CHECK='Both';
      NO_IO_CHECK='Both';
      NO_ASSERT_CHECK='TRUE';
      NO_DIR_CHECK='TRUE';
      ALLOW_CONNECT='TRUE';
    'VSS_DF13':
      PIN_NUMBER='(0,0,0,0,0,0,0,0,0,0,0,0,0,0,0,0,0,0,0,0,0,0,0,0,0,0,0,0,0,0,0,0,0,0,0,0,0,0,0,DF13)';
      PINUSE='POWER';
      NO_LOAD_CHECK='Both';
      NO_IO_CHECK='Both';
      NO_ASSERT_CHECK='TRUE';
      NO_DIR_CHECK='TRUE';
      ALLOW_CONNECT='TRUE';
    'VSS_DF20':
      PIN_NUMBER='(0,0,0,0,0,0,0,0,0,0,0,0,0,0,0,0,0,0,0,0,0,0,0,0,0,0,0,0,0,0,0,0,0,0,0,0,0,0,0,DF20)';
      PINUSE='POWER';
      NO_LOAD_CHECK='Both';
      NO_IO_CHECK='Both';
      NO_ASSERT_CHECK='TRUE';
      NO_DIR_CHECK='TRUE';
      ALLOW_CONNECT='TRUE';
    'VSS_DF22':
      PIN_NUMBER='(0,0,0,0,0,0,0,0,0,0,0,0,0,0,0,0,0,0,0,0,0,0,0,0,0,0,0,0,0,0,0,0,0,0,0,0,0,0,0,DF22)';
      PINUSE='POWER';
      NO_LOAD_CHECK='Both';
      NO_IO_CHECK='Both';
      NO_ASSERT_CHECK='TRUE';
      NO_DIR_CHECK='TRUE';
      ALLOW_CONNECT='TRUE';
    'VSS_DF23':
      PIN_NUMBER='(0,0,0,0,0,0,0,0,0,0,0,0,0,0,0,0,0,0,0,0,0,0,0,0,0,0,0,0,0,0,0,0,0,0,0,0,0,0,0,DF23)';
      PINUSE='POWER';
      NO_LOAD_CHECK='Both';
      NO_IO_CHECK='Both';
      NO_ASSERT_CHECK='TRUE';
      NO_DIR_CHECK='TRUE';
      ALLOW_CONNECT='TRUE';
    'VSS_DF26':
      PIN_NUMBER='(0,0,0,0,0,0,0,0,0,0,0,0,0,0,0,0,0,0,0,0,0,0,0,0,0,0,0,0,0,0,0,0,0,0,0,0,0,0,0,DF26)';
      PINUSE='POWER';
      NO_LOAD_CHECK='Both';
      NO_IO_CHECK='Both';
      NO_ASSERT_CHECK='TRUE';
      NO_DIR_CHECK='TRUE';
      ALLOW_CONNECT='TRUE';
    'VSS_DF29':
      PIN_NUMBER='(0,0,0,0,0,0,0,0,0,0,0,0,0,0,0,0,0,0,0,0,0,0,0,0,0,0,0,0,0,0,0,0,0,0,0,0,0,0,0,DF29)';
      PINUSE='POWER';
      NO_LOAD_CHECK='Both';
      NO_IO_CHECK='Both';
      NO_ASSERT_CHECK='TRUE';
      NO_DIR_CHECK='TRUE';
      ALLOW_CONNECT='TRUE';
    'VSS_DF32':
      PIN_NUMBER='(0,0,0,0,0,0,0,0,0,0,0,0,0,0,0,0,0,0,0,0,0,0,0,0,0,0,0,0,0,0,0,0,0,0,0,0,0,0,0,DF32)';
      PINUSE='POWER';
      NO_LOAD_CHECK='Both';
      NO_IO_CHECK='Both';
      NO_ASSERT_CHECK='TRUE';
      NO_DIR_CHECK='TRUE';
      ALLOW_CONNECT='TRUE';
    'VSS_DF35':
      PIN_NUMBER='(0,0,0,0,0,0,0,0,0,0,0,0,0,0,0,0,0,0,0,0,0,0,0,0,0,0,0,0,0,0,0,0,0,0,0,0,0,0,0,DF35)';
      PINUSE='POWER';
      NO_LOAD_CHECK='Both';
      NO_IO_CHECK='Both';
      NO_ASSERT_CHECK='TRUE';
      NO_DIR_CHECK='TRUE';
      ALLOW_CONNECT='TRUE';
    'VSS_DF37':
      PIN_NUMBER='(0,0,0,0,0,0,0,0,0,0,0,0,0,0,0,0,0,0,0,0,0,0,0,0,0,0,0,0,0,0,0,0,0,0,0,0,0,0,0,DF37)';
      PINUSE='POWER';
      NO_LOAD_CHECK='Both';
      NO_IO_CHECK='Both';
      NO_ASSERT_CHECK='TRUE';
      NO_DIR_CHECK='TRUE';
      ALLOW_CONNECT='TRUE';
    'VSS_DF39':
      PIN_NUMBER='(0,0,0,0,0,0,0,0,0,0,0,0,0,0,0,0,0,0,0,0,0,0,0,0,0,0,0,0,0,0,0,0,0,0,0,0,0,0,0,DF39)';
      PINUSE='POWER';
      NO_LOAD_CHECK='Both';
      NO_IO_CHECK='Both';
      NO_ASSERT_CHECK='TRUE';
      NO_DIR_CHECK='TRUE';
      ALLOW_CONNECT='TRUE';
    'VSS_DF42':
      PIN_NUMBER='(0,0,0,0,0,0,0,0,0,0,0,0,0,0,0,0,0,0,0,0,0,0,0,0,0,0,0,0,0,0,0,0,0,0,0,0,0,0,0,DF42)';
      PINUSE='POWER';
      NO_LOAD_CHECK='Both';
      NO_IO_CHECK='Both';
      NO_ASSERT_CHECK='TRUE';
      NO_DIR_CHECK='TRUE';
      ALLOW_CONNECT='TRUE';
    'VSS_DF44':
      PIN_NUMBER='(0,0,0,0,0,0,0,0,0,0,0,0,0,0,0,0,0,0,0,0,0,0,0,0,0,0,0,0,0,0,0,0,0,0,0,0,0,0,0,DF44)';
      PINUSE='POWER';
      NO_LOAD_CHECK='Both';
      NO_IO_CHECK='Both';
      NO_ASSERT_CHECK='TRUE';
      NO_DIR_CHECK='TRUE';
      ALLOW_CONNECT='TRUE';
    'VSS_DF45':
      PIN_NUMBER='(0,0,0,0,0,0,0,0,0,0,0,0,0,0,0,0,0,0,0,0,0,0,0,0,0,0,0,0,0,0,0,0,0,0,0,0,0,0,0,DF45)';
      PINUSE='POWER';
      NO_LOAD_CHECK='Both';
      NO_IO_CHECK='Both';
      NO_ASSERT_CHECK='TRUE';
      NO_DIR_CHECK='TRUE';
      ALLOW_CONNECT='TRUE';
    'VSS_DF46':
      PIN_NUMBER='(0,0,0,0,0,0,0,0,0,0,0,0,0,0,0,0,0,0,0,0,0,0,0,0,0,0,0,0,0,0,0,0,0,0,0,0,0,0,0,DF46)';
      PINUSE='POWER';
      NO_LOAD_CHECK='Both';
      NO_IO_CHECK='Both';
      NO_ASSERT_CHECK='TRUE';
      NO_DIR_CHECK='TRUE';
      ALLOW_CONNECT='TRUE';
    'VSS_DF47':
      PIN_NUMBER='(0,0,0,0,0,0,0,0,0,0,0,0,0,0,0,0,0,0,0,0,0,0,0,0,0,0,0,0,0,0,0,0,0,0,0,0,0,0,0,DF47)';
      PINUSE='POWER';
      NO_LOAD_CHECK='Both';
      NO_IO_CHECK='Both';
      NO_ASSERT_CHECK='TRUE';
      NO_DIR_CHECK='TRUE';
      ALLOW_CONNECT='TRUE';
    'VSS_DF48':
      PIN_NUMBER='(0,0,0,0,0,0,0,0,0,0,0,0,0,0,0,0,0,0,0,0,0,0,0,0,0,0,0,0,0,0,0,0,0,0,0,0,0,0,0,DF48)';
      PINUSE='POWER';
      NO_LOAD_CHECK='Both';
      NO_IO_CHECK='Both';
      NO_ASSERT_CHECK='TRUE';
      NO_DIR_CHECK='TRUE';
      ALLOW_CONNECT='TRUE';
    'VSS_DF49':
      PIN_NUMBER='(0,0,0,0,0,0,0,0,0,0,0,0,0,0,0,0,0,0,0,0,0,0,0,0,0,0,0,0,0,0,0,0,0,0,0,0,0,0,0,DF49)';
      PINUSE='POWER';
      NO_LOAD_CHECK='Both';
      NO_IO_CHECK='Both';
      NO_ASSERT_CHECK='TRUE';
      NO_DIR_CHECK='TRUE';
      ALLOW_CONNECT='TRUE';
    'VSS_DF50':
      PIN_NUMBER='(0,0,0,0,0,0,0,0,0,0,0,0,0,0,0,0,0,0,0,0,0,0,0,0,0,0,0,0,0,0,0,0,0,0,0,0,0,0,0,DF50)';
      PINUSE='POWER';
      NO_LOAD_CHECK='Both';
      NO_IO_CHECK='Both';
      NO_ASSERT_CHECK='TRUE';
      NO_DIR_CHECK='TRUE';
      ALLOW_CONNECT='TRUE';
    'VSS_DF51':
      PIN_NUMBER='(0,0,0,0,0,0,0,0,0,0,0,0,0,0,0,0,0,0,0,0,0,0,0,0,0,0,0,0,0,0,0,0,0,0,0,0,0,0,0,DF51)';
      PINUSE='POWER';
      NO_LOAD_CHECK='Both';
      NO_IO_CHECK='Both';
      NO_ASSERT_CHECK='TRUE';
      NO_DIR_CHECK='TRUE';
      ALLOW_CONNECT='TRUE';
    'VSS_DF52':
      PIN_NUMBER='(0,0,0,0,0,0,0,0,0,0,0,0,0,0,0,0,0,0,0,0,0,0,0,0,0,0,0,0,0,0,0,0,0,0,0,0,0,0,0,DF52)';
      PINUSE='POWER';
      NO_LOAD_CHECK='Both';
      NO_IO_CHECK='Both';
      NO_ASSERT_CHECK='TRUE';
      NO_DIR_CHECK='TRUE';
      ALLOW_CONNECT='TRUE';
    'VSS_DF56':
      PIN_NUMBER='(0,0,0,0,0,0,0,0,0,0,0,0,0,0,0,0,0,0,0,0,0,0,0,0,0,0,0,0,0,0,0,0,0,0,0,0,0,0,0,DF56)';
      PINUSE='POWER';
      NO_LOAD_CHECK='Both';
      NO_IO_CHECK='Both';
      NO_ASSERT_CHECK='TRUE';
      NO_DIR_CHECK='TRUE';
      ALLOW_CONNECT='TRUE';
    'VSS_DF57':
      PIN_NUMBER='(0,0,0,0,0,0,0,0,0,0,0,0,0,0,0,0,0,0,0,0,0,0,0,0,0,0,0,0,0,0,0,0,0,0,0,0,0,0,0,DF57)';
      PINUSE='POWER';
      NO_LOAD_CHECK='Both';
      NO_IO_CHECK='Both';
      NO_ASSERT_CHECK='TRUE';
      NO_DIR_CHECK='TRUE';
      ALLOW_CONNECT='TRUE';
    'VSS_DF58':
      PIN_NUMBER='(0,0,0,0,0,0,0,0,0,0,0,0,0,0,0,0,0,0,0,0,0,0,0,0,0,0,0,0,0,0,0,0,0,0,0,0,0,0,0,DF58)';
      PINUSE='POWER';
      NO_LOAD_CHECK='Both';
      NO_IO_CHECK='Both';
      NO_ASSERT_CHECK='TRUE';
      NO_DIR_CHECK='TRUE';
      ALLOW_CONNECT='TRUE';
    'VSS_DF59':
      PIN_NUMBER='(0,0,0,0,0,0,0,0,0,0,0,0,0,0,0,0,0,0,0,0,0,0,0,0,0,0,0,0,0,0,0,0,0,0,0,0,0,0,0,DF59)';
      PINUSE='POWER';
      NO_LOAD_CHECK='Both';
      NO_IO_CHECK='Both';
      NO_ASSERT_CHECK='TRUE';
      NO_DIR_CHECK='TRUE';
      ALLOW_CONNECT='TRUE';
    'VSS_DF61':
      PIN_NUMBER='(0,0,0,0,0,0,0,0,0,0,0,0,0,0,0,0,0,0,0,0,0,0,0,0,0,0,0,0,0,0,0,0,0,0,0,0,0,0,0,DF61)';
      PINUSE='POWER';
      NO_LOAD_CHECK='Both';
      NO_IO_CHECK='Both';
      NO_ASSERT_CHECK='TRUE';
      NO_DIR_CHECK='TRUE';
      ALLOW_CONNECT='TRUE';
    'VSS_DF63':
      PIN_NUMBER='(0,0,0,0,0,0,0,0,0,0,0,0,0,0,0,0,0,0,0,0,0,0,0,0,0,0,0,0,0,0,0,0,0,0,0,0,0,0,0,DF63)';
      PINUSE='POWER';
      NO_LOAD_CHECK='Both';
      NO_IO_CHECK='Both';
      NO_ASSERT_CHECK='TRUE';
      NO_DIR_CHECK='TRUE';
      ALLOW_CONNECT='TRUE';
    'VSS_DF64':
      PIN_NUMBER='(0,0,0,0,0,0,0,0,0,0,0,0,0,0,0,0,0,0,0,0,0,0,0,0,0,0,0,0,0,0,0,0,0,0,0,0,0,0,0,DF64)';
      PINUSE='POWER';
      NO_LOAD_CHECK='Both';
      NO_IO_CHECK='Both';
      NO_ASSERT_CHECK='TRUE';
      NO_DIR_CHECK='TRUE';
      ALLOW_CONNECT='TRUE';
    'VSS_DF65':
      PIN_NUMBER='(0,0,0,0,0,0,0,0,0,0,0,0,0,0,0,0,0,0,0,0,0,0,0,0,0,0,0,0,0,0,0,0,0,0,0,0,0,0,0,DF65)';
      PINUSE='POWER';
      NO_LOAD_CHECK='Both';
      NO_IO_CHECK='Both';
      NO_ASSERT_CHECK='TRUE';
      NO_DIR_CHECK='TRUE';
      ALLOW_CONNECT='TRUE';
    'VSS_DF71':
      PIN_NUMBER='(0,0,0,0,0,0,0,0,0,0,0,0,0,0,0,0,0,0,0,0,0,0,0,0,0,0,0,0,0,0,0,0,0,0,0,0,0,0,0,DF71)';
      PINUSE='POWER';
      NO_LOAD_CHECK='Both';
      NO_IO_CHECK='Both';
      NO_ASSERT_CHECK='TRUE';
      NO_DIR_CHECK='TRUE';
      ALLOW_CONNECT='TRUE';
    'VSS_DF72':
      PIN_NUMBER='(0,0,0,0,0,0,0,0,0,0,0,0,0,0,0,0,0,0,0,0,0,0,0,0,0,0,0,0,0,0,0,0,0,0,0,0,0,0,0,DF72)';
      PINUSE='POWER';
      NO_LOAD_CHECK='Both';
      NO_IO_CHECK='Both';
      NO_ASSERT_CHECK='TRUE';
      NO_DIR_CHECK='TRUE';
      ALLOW_CONNECT='TRUE';
    'VSS_DF73':
      PIN_NUMBER='(0,0,0,0,0,0,0,0,0,0,0,0,0,0,0,0,0,0,0,0,0,0,0,0,0,0,0,0,0,0,0,0,0,0,0,0,0,0,0,DF73)';
      PINUSE='POWER';
      NO_LOAD_CHECK='Both';
      NO_IO_CHECK='Both';
      NO_ASSERT_CHECK='TRUE';
      NO_DIR_CHECK='TRUE';
      ALLOW_CONNECT='TRUE';
    'VSS_DG1':
      PIN_NUMBER='(0,0,0,0,0,0,0,0,0,0,0,0,0,0,0,0,0,0,0,0,0,0,0,0,0,0,0,0,0,0,0,0,0,0,0,0,0,0,0,DG1)';
      PINUSE='POWER';
      NO_LOAD_CHECK='Both';
      NO_IO_CHECK='Both';
      NO_ASSERT_CHECK='TRUE';
      NO_DIR_CHECK='TRUE';
      ALLOW_CONNECT='TRUE';
    'VSS_DG2':
      PIN_NUMBER='(0,0,0,0,0,0,0,0,0,0,0,0,0,0,0,0,0,0,0,0,0,0,0,0,0,0,0,0,0,0,0,0,0,0,0,0,0,0,0,DG2)';
      PINUSE='POWER';
      NO_LOAD_CHECK='Both';
      NO_IO_CHECK='Both';
      NO_ASSERT_CHECK='TRUE';
      NO_DIR_CHECK='TRUE';
      ALLOW_CONNECT='TRUE';
    'VSS_DG6':
      PIN_NUMBER='(0,0,0,0,0,0,0,0,0,0,0,0,0,0,0,0,0,0,0,0,0,0,0,0,0,0,0,0,0,0,0,0,0,0,0,0,0,0,0,DG6)';
      PINUSE='POWER';
      NO_LOAD_CHECK='Both';
      NO_IO_CHECK='Both';
      NO_ASSERT_CHECK='TRUE';
      NO_DIR_CHECK='TRUE';
      ALLOW_CONNECT='TRUE';
    'VSS_DG7':
      PIN_NUMBER='(0,0,0,0,0,0,0,0,0,0,0,0,0,0,0,0,0,0,0,0,0,0,0,0,0,0,0,0,0,0,0,0,0,0,0,0,0,0,0,DG7)';
      PINUSE='POWER';
      NO_LOAD_CHECK='Both';
      NO_IO_CHECK='Both';
      NO_ASSERT_CHECK='TRUE';
      NO_DIR_CHECK='TRUE';
      ALLOW_CONNECT='TRUE';
    'VSS_DG15':
      PIN_NUMBER='(0,0,0,0,0,0,0,0,0,0,0,0,0,0,0,0,0,0,0,0,0,0,0,0,0,0,0,0,0,0,0,0,0,0,0,0,0,0,0,DG15)';
      PINUSE='POWER';
      NO_LOAD_CHECK='Both';
      NO_IO_CHECK='Both';
      NO_ASSERT_CHECK='TRUE';
      NO_DIR_CHECK='TRUE';
      ALLOW_CONNECT='TRUE';
    'VSS_DG16':
      PIN_NUMBER='(0,0,0,0,0,0,0,0,0,0,0,0,0,0,0,0,0,0,0,0,0,0,0,0,0,0,0,0,0,0,0,0,0,0,0,0,0,0,0,DG16)';
      PINUSE='POWER';
      NO_LOAD_CHECK='Both';
      NO_IO_CHECK='Both';
      NO_ASSERT_CHECK='TRUE';
      NO_DIR_CHECK='TRUE';
      ALLOW_CONNECT='TRUE';
    'VSS_DG18':
      PIN_NUMBER='(0,0,0,0,0,0,0,0,0,0,0,0,0,0,0,0,0,0,0,0,0,0,0,0,0,0,0,0,0,0,0,0,0,0,0,0,0,0,0,DG18)';
      PINUSE='POWER';
      NO_LOAD_CHECK='Both';
      NO_IO_CHECK='Both';
      NO_ASSERT_CHECK='TRUE';
      NO_DIR_CHECK='TRUE';
      ALLOW_CONNECT='TRUE';
    'VSS_DG20':
      PIN_NUMBER='(0,0,0,0,0,0,0,0,0,0,0,0,0,0,0,0,0,0,0,0,0,0,0,0,0,0,0,0,0,0,0,0,0,0,0,0,0,0,0,DG20)';
      PINUSE='POWER';
      NO_LOAD_CHECK='Both';
      NO_IO_CHECK='Both';
      NO_ASSERT_CHECK='TRUE';
      NO_DIR_CHECK='TRUE';
      ALLOW_CONNECT='TRUE';
    'VSS_DG21':
      PIN_NUMBER='(0,0,0,0,0,0,0,0,0,0,0,0,0,0,0,0,0,0,0,0,0,0,0,0,0,0,0,0,0,0,0,0,0,0,0,0,0,0,0,DG21)';
      PINUSE='POWER';
      NO_LOAD_CHECK='Both';
      NO_IO_CHECK='Both';
      NO_ASSERT_CHECK='TRUE';
      NO_DIR_CHECK='TRUE';
      ALLOW_CONNECT='TRUE';
    'VSS_DG24':
      PIN_NUMBER='(0,0,0,0,0,0,0,0,0,0,0,0,0,0,0,0,0,0,0,0,0,0,0,0,0,0,0,0,0,0,0,0,0,0,0,0,0,0,0,DG24)';
      PINUSE='POWER';
      NO_LOAD_CHECK='Both';
      NO_IO_CHECK='Both';
      NO_ASSERT_CHECK='TRUE';
      NO_DIR_CHECK='TRUE';
      ALLOW_CONNECT='TRUE';
    'VSS_DG27':
      PIN_NUMBER='(0,0,0,0,0,0,0,0,0,0,0,0,0,0,0,0,0,0,0,0,0,0,0,0,0,0,0,0,0,0,0,0,0,0,0,0,0,0,0,DG27)';
      PINUSE='POWER';
      NO_LOAD_CHECK='Both';
      NO_IO_CHECK='Both';
      NO_ASSERT_CHECK='TRUE';
      NO_DIR_CHECK='TRUE';
      ALLOW_CONNECT='TRUE';
    'VSS_DG46':
      PIN_NUMBER='(0,0,0,0,0,0,0,0,0,0,0,0,0,0,0,0,0,0,0,0,0,0,0,0,0,0,0,0,0,0,0,0,0,0,0,0,0,0,0,DG46)';
      PINUSE='POWER';
      NO_LOAD_CHECK='Both';
      NO_IO_CHECK='Both';
      NO_ASSERT_CHECK='TRUE';
      NO_DIR_CHECK='TRUE';
      ALLOW_CONNECT='TRUE';
    'VSS_DG49':
      PIN_NUMBER='(0,0,0,0,0,0,0,0,0,0,0,0,0,0,0,0,0,0,0,0,0,0,0,0,0,0,0,0,0,0,0,0,0,0,0,0,0,0,0,DG49)';
      PINUSE='POWER';
      NO_LOAD_CHECK='Both';
      NO_IO_CHECK='Both';
      NO_ASSERT_CHECK='TRUE';
      NO_DIR_CHECK='TRUE';
      ALLOW_CONNECT='TRUE';
    'VSS_DG52':
      PIN_NUMBER='(0,0,0,0,0,0,0,0,0,0,0,0,0,0,0,0,0,0,0,0,0,0,0,0,0,0,0,0,0,0,0,0,0,0,0,0,0,0,0,DG52)';
      PINUSE='POWER';
      NO_LOAD_CHECK='Both';
      NO_IO_CHECK='Both';
      NO_ASSERT_CHECK='TRUE';
      NO_DIR_CHECK='TRUE';
      ALLOW_CONNECT='TRUE';
    'VSS_DG55':
      PIN_NUMBER='(0,0,0,0,0,0,0,0,0,0,0,0,0,0,0,0,0,0,0,0,0,0,0,0,0,0,0,0,0,0,0,0,0,0,0,0,0,0,0,DG55)';
      PINUSE='POWER';
      NO_LOAD_CHECK='Both';
      NO_IO_CHECK='Both';
      NO_ASSERT_CHECK='TRUE';
      NO_DIR_CHECK='TRUE';
      ALLOW_CONNECT='TRUE';
    'VSS_DG56':
      PIN_NUMBER='(0,0,0,0,0,0,0,0,0,0,0,0,0,0,0,0,0,0,0,0,0,0,0,0,0,0,0,0,0,0,0,0,0,0,0,0,0,0,0,DG56)';
      PINUSE='POWER';
      NO_LOAD_CHECK='Both';
      NO_IO_CHECK='Both';
      NO_ASSERT_CHECK='TRUE';
      NO_DIR_CHECK='TRUE';
      ALLOW_CONNECT='TRUE';
    'VSS_DG59':
      PIN_NUMBER='(0,0,0,0,0,0,0,0,0,0,0,0,0,0,0,0,0,0,0,0,0,0,0,0,0,0,0,0,0,0,0,0,0,0,0,0,0,0,0,DG59)';
      PINUSE='POWER';
      NO_LOAD_CHECK='Both';
      NO_IO_CHECK='Both';
      NO_ASSERT_CHECK='TRUE';
      NO_DIR_CHECK='TRUE';
      ALLOW_CONNECT='TRUE';
    'VSS_DG60':
      PIN_NUMBER='(0,0,0,0,0,0,0,0,0,0,0,0,0,0,0,0,0,0,0,0,0,0,0,0,0,0,0,0,0,0,0,0,0,0,0,0,0,0,0,DG60)';
      PINUSE='POWER';
      NO_LOAD_CHECK='Both';
      NO_IO_CHECK='Both';
      NO_ASSERT_CHECK='TRUE';
      NO_DIR_CHECK='TRUE';
      ALLOW_CONNECT='TRUE';
    'VSS_DG66':
      PIN_NUMBER='(0,0,0,0,0,0,0,0,0,0,0,0,0,0,0,0,0,0,0,0,0,0,0,0,0,0,0,0,0,0,0,0,0,0,0,0,0,0,0,DG66)';
      PINUSE='POWER';
      NO_LOAD_CHECK='Both';
      NO_IO_CHECK='Both';
      NO_ASSERT_CHECK='TRUE';
      NO_DIR_CHECK='TRUE';
      ALLOW_CONNECT='TRUE';
    'VSS_DG67':
      PIN_NUMBER='(0,0,0,0,0,0,0,0,0,0,0,0,0,0,0,0,0,0,0,0,0,0,0,0,0,0,0,0,0,0,0,0,0,0,0,0,0,0,0,DG67)';
      PINUSE='POWER';
      NO_LOAD_CHECK='Both';
      NO_IO_CHECK='Both';
      NO_ASSERT_CHECK='TRUE';
      NO_DIR_CHECK='TRUE';
      ALLOW_CONNECT='TRUE';
    'VSS_DG68':
      PIN_NUMBER='(0,0,0,0,0,0,0,0,0,0,0,0,0,0,0,0,0,0,0,0,0,0,0,0,0,0,0,0,0,0,0,0,0,0,0,0,0,0,0,DG68)';
      PINUSE='POWER';
      NO_LOAD_CHECK='Both';
      NO_IO_CHECK='Both';
      NO_ASSERT_CHECK='TRUE';
      NO_DIR_CHECK='TRUE';
      ALLOW_CONNECT='TRUE';
    'VSS_DG69':
      PIN_NUMBER='(0,0,0,0,0,0,0,0,0,0,0,0,0,0,0,0,0,0,0,0,0,0,0,0,0,0,0,0,0,0,0,0,0,0,0,0,0,0,0,DG69)';
      PINUSE='POWER';
      NO_LOAD_CHECK='Both';
      NO_IO_CHECK='Both';
      NO_ASSERT_CHECK='TRUE';
      NO_DIR_CHECK='TRUE';
      ALLOW_CONNECT='TRUE';
    'VSS_DG70':
      PIN_NUMBER='(0,0,0,0,0,0,0,0,0,0,0,0,0,0,0,0,0,0,0,0,0,0,0,0,0,0,0,0,0,0,0,0,0,0,0,0,0,0,0,DG70)';
      PINUSE='POWER';
      NO_LOAD_CHECK='Both';
      NO_IO_CHECK='Both';
      NO_ASSERT_CHECK='TRUE';
      NO_DIR_CHECK='TRUE';
      ALLOW_CONNECT='TRUE';
    'VSS_DG74':
      PIN_NUMBER='(0,0,0,0,0,0,0,0,0,0,0,0,0,0,0,0,0,0,0,0,0,0,0,0,0,0,0,0,0,0,0,0,0,0,0,0,0,0,0,DG74)';
      PINUSE='POWER';
      NO_LOAD_CHECK='Both';
      NO_IO_CHECK='Both';
      NO_ASSERT_CHECK='TRUE';
      NO_DIR_CHECK='TRUE';
      ALLOW_CONNECT='TRUE';
    'VSS_DG75':
      PIN_NUMBER='(0,0,0,0,0,0,0,0,0,0,0,0,0,0,0,0,0,0,0,0,0,0,0,0,0,0,0,0,0,0,0,0,0,0,0,0,0,0,0,DG75)';
      PINUSE='POWER';
      NO_LOAD_CHECK='Both';
      NO_IO_CHECK='Both';
      NO_ASSERT_CHECK='TRUE';
      NO_DIR_CHECK='TRUE';
      ALLOW_CONNECT='TRUE';
    'VSS_DH39':
      PIN_NUMBER='(0,0,0,0,0,0,0,0,0,0,0,0,0,0,0,0,0,0,0,0,0,0,0,0,0,0,0,0,0,0,0,0,0,0,0,0,0,0,0,DH39)';
      PINUSE='POWER';
      NO_LOAD_CHECK='Both';
      NO_IO_CHECK='Both';
      NO_ASSERT_CHECK='TRUE';
      NO_DIR_CHECK='TRUE';
      ALLOW_CONNECT='TRUE';
    'VSS_DH43':
      PIN_NUMBER='(0,0,0,0,0,0,0,0,0,0,0,0,0,0,0,0,0,0,0,0,0,0,0,0,0,0,0,0,0,0,0,0,0,0,0,0,0,0,0,DH43)';
      PINUSE='POWER';
      NO_LOAD_CHECK='Both';
      NO_IO_CHECK='Both';
      NO_ASSERT_CHECK='TRUE';
      NO_DIR_CHECK='TRUE';
      ALLOW_CONNECT='TRUE';
    'VSS_DH46':
      PIN_NUMBER='(0,0,0,0,0,0,0,0,0,0,0,0,0,0,0,0,0,0,0,0,0,0,0,0,0,0,0,0,0,0,0,0,0,0,0,0,0,0,0,DH46)';
      PINUSE='POWER';
      NO_LOAD_CHECK='Both';
      NO_IO_CHECK='Both';
      NO_ASSERT_CHECK='TRUE';
      NO_DIR_CHECK='TRUE';
      ALLOW_CONNECT='TRUE';
    'VSS_DH49':
      PIN_NUMBER='(0,0,0,0,0,0,0,0,0,0,0,0,0,0,0,0,0,0,0,0,0,0,0,0,0,0,0,0,0,0,0,0,0,0,0,0,0,0,0,DH49)';
      PINUSE='POWER';
      NO_LOAD_CHECK='Both';
      NO_IO_CHECK='Both';
      NO_ASSERT_CHECK='TRUE';
      NO_DIR_CHECK='TRUE';
      ALLOW_CONNECT='TRUE';
    'VSS_DH52':
      PIN_NUMBER='(0,0,0,0,0,0,0,0,0,0,0,0,0,0,0,0,0,0,0,0,0,0,0,0,0,0,0,0,0,0,0,0,0,0,0,0,0,0,0,DH52)';
      PINUSE='POWER';
      NO_LOAD_CHECK='Both';
      NO_IO_CHECK='Both';
      NO_ASSERT_CHECK='TRUE';
      NO_DIR_CHECK='TRUE';
      ALLOW_CONNECT='TRUE';
    'VSS_DH55':
      PIN_NUMBER='(0,0,0,0,0,0,0,0,0,0,0,0,0,0,0,0,0,0,0,0,0,0,0,0,0,0,0,0,0,0,0,0,0,0,0,0,0,0,0,DH55)';
      PINUSE='POWER';
      NO_LOAD_CHECK='Both';
      NO_IO_CHECK='Both';
      NO_ASSERT_CHECK='TRUE';
      NO_DIR_CHECK='TRUE';
      ALLOW_CONNECT='TRUE';
    'VSS_DH59':
      PIN_NUMBER='(0,0,0,0,0,0,0,0,0,0,0,0,0,0,0,0,0,0,0,0,0,0,0,0,0,0,0,0,0,0,0,0,0,0,0,0,0,0,0,DH59)';
      PINUSE='POWER';
      NO_LOAD_CHECK='Both';
      NO_IO_CHECK='Both';
      NO_ASSERT_CHECK='TRUE';
      NO_DIR_CHECK='TRUE';
      ALLOW_CONNECT='TRUE';
    'VSS_DH68':
      PIN_NUMBER='(0,0,0,0,0,0,0,0,0,0,0,0,0,0,0,0,0,0,0,0,0,0,0,0,0,0,0,0,0,0,0,0,0,0,0,0,0,0,0,DH68)';
      PINUSE='POWER';
      NO_LOAD_CHECK='Both';
      NO_IO_CHECK='Both';
      NO_ASSERT_CHECK='TRUE';
      NO_DIR_CHECK='TRUE';
      ALLOW_CONNECT='TRUE';
    'VSS_DH70':
      PIN_NUMBER='(0,0,0,0,0,0,0,0,0,0,0,0,0,0,0,0,0,0,0,0,0,0,0,0,0,0,0,0,0,0,0,0,0,0,0,0,0,0,0,DH70)';
      PINUSE='POWER';
      NO_LOAD_CHECK='Both';
      NO_IO_CHECK='Both';
      NO_ASSERT_CHECK='TRUE';
      NO_DIR_CHECK='TRUE';
      ALLOW_CONNECT='TRUE';
    'VSS_DJ7':
      PIN_NUMBER='(0,0,0,0,0,0,0,0,0,0,0,0,0,0,0,0,0,0,0,0,0,0,0,0,0,0,0,0,0,0,0,0,0,0,0,0,0,0,0,DJ7)';
      PINUSE='POWER';
      NO_LOAD_CHECK='Both';
      NO_IO_CHECK='Both';
      NO_ASSERT_CHECK='TRUE';
      NO_DIR_CHECK='TRUE';
      ALLOW_CONNECT='TRUE';
    'VSS_DJ15':
      PIN_NUMBER='(0,0,0,0,0,0,0,0,0,0,0,0,0,0,0,0,0,0,0,0,0,0,0,0,0,0,0,0,0,0,0,0,0,0,0,0,0,0,0,DJ15)';
      PINUSE='POWER';
      NO_LOAD_CHECK='Both';
      NO_IO_CHECK='Both';
      NO_ASSERT_CHECK='TRUE';
      NO_DIR_CHECK='TRUE';
      ALLOW_CONNECT='TRUE';
    'VSS_DJ19':
      PIN_NUMBER='(0,0,0,0,0,0,0,0,0,0,0,0,0,0,0,0,0,0,0,0,0,0,0,0,0,0,0,0,0,0,0,0,0,0,0,0,0,0,0,DJ19)';
      PINUSE='POWER';
      NO_LOAD_CHECK='Both';
      NO_IO_CHECK='Both';
      NO_ASSERT_CHECK='TRUE';
      NO_DIR_CHECK='TRUE';
      ALLOW_CONNECT='TRUE';
    'VSS_DJ43':
      PIN_NUMBER='(0,0,0,0,0,0,0,0,0,0,0,0,0,0,0,0,0,0,0,0,0,0,0,0,0,0,0,0,0,0,0,0,0,0,0,0,0,0,0,DJ43)';
      PINUSE='POWER';
      NO_LOAD_CHECK='Both';
      NO_IO_CHECK='Both';
      NO_ASSERT_CHECK='TRUE';
      NO_DIR_CHECK='TRUE';
      ALLOW_CONNECT='TRUE';
    'VSS_DJ49':
      PIN_NUMBER='(0,0,0,0,0,0,0,0,0,0,0,0,0,0,0,0,0,0,0,0,0,0,0,0,0,0,0,0,0,0,0,0,0,0,0,0,0,0,0,DJ49)';
      PINUSE='POWER';
      NO_LOAD_CHECK='Both';
      NO_IO_CHECK='Both';
      NO_ASSERT_CHECK='TRUE';
      NO_DIR_CHECK='TRUE';
      ALLOW_CONNECT='TRUE';
    'VSS_DJ59':
      PIN_NUMBER='(0,0,0,0,0,0,0,0,0,0,0,0,0,0,0,0,0,0,0,0,0,0,0,0,0,0,0,0,0,0,0,0,0,0,0,0,0,0,0,DJ59)';
      PINUSE='POWER';
      NO_LOAD_CHECK='Both';
      NO_IO_CHECK='Both';
      NO_ASSERT_CHECK='TRUE';
      NO_DIR_CHECK='TRUE';
      ALLOW_CONNECT='TRUE';
    'VSS_DJ61':
      PIN_NUMBER='(0,0,0,0,0,0,0,0,0,0,0,0,0,0,0,0,0,0,0,0,0,0,0,0,0,0,0,0,0,0,0,0,0,0,0,0,0,0,0,DJ61)';
      PINUSE='POWER';
      NO_LOAD_CHECK='Both';
      NO_IO_CHECK='Both';
      NO_ASSERT_CHECK='TRUE';
      NO_DIR_CHECK='TRUE';
      ALLOW_CONNECT='TRUE';
    'VSS_DJ63':
      PIN_NUMBER='(0,0,0,0,0,0,0,0,0,0,0,0,0,0,0,0,0,0,0,0,0,0,0,0,0,0,0,0,0,0,0,0,0,0,0,0,0,0,0,DJ63)';
      PINUSE='POWER';
      NO_LOAD_CHECK='Both';
      NO_IO_CHECK='Both';
      NO_ASSERT_CHECK='TRUE';
      NO_DIR_CHECK='TRUE';
      ALLOW_CONNECT='TRUE';
    'VSS_DJ66':
      PIN_NUMBER='(0,0,0,0,0,0,0,0,0,0,0,0,0,0,0,0,0,0,0,0,0,0,0,0,0,0,0,0,0,0,0,0,0,0,0,0,0,0,0,DJ66)';
      PINUSE='POWER';
      NO_LOAD_CHECK='Both';
      NO_IO_CHECK='Both';
      NO_ASSERT_CHECK='TRUE';
      NO_DIR_CHECK='TRUE';
      ALLOW_CONNECT='TRUE';
    'VSS_DJ68':
      PIN_NUMBER='(0,0,0,0,0,0,0,0,0,0,0,0,0,0,0,0,0,0,0,0,0,0,0,0,0,0,0,0,0,0,0,0,0,0,0,0,0,0,0,DJ68)';
      PINUSE='POWER';
      NO_LOAD_CHECK='Both';
      NO_IO_CHECK='Both';
      NO_ASSERT_CHECK='TRUE';
      NO_DIR_CHECK='TRUE';
      ALLOW_CONNECT='TRUE';
    'VSS_DJ73':
      PIN_NUMBER='(0,0,0,0,0,0,0,0,0,0,0,0,0,0,0,0,0,0,0,0,0,0,0,0,0,0,0,0,0,0,0,0,0,0,0,0,0,0,0,DJ73)';
      PINUSE='POWER';
      NO_LOAD_CHECK='Both';
      NO_IO_CHECK='Both';
      NO_ASSERT_CHECK='TRUE';
      NO_DIR_CHECK='TRUE';
      ALLOW_CONNECT='TRUE';
    'VSS_CY57':
      PIN_NUMBER='(0,0,0,0,0,0,0,0,0,0,0,0,0,0,0,0,0,0,0,0,0,0,0,0,0,0,0,0,0,0,0,0,0,0,0,0,0,0,0,CY57)';
      PINUSE='POWER';
      NO_LOAD_CHECK='Both';
      NO_IO_CHECK='Both';
      NO_ASSERT_CHECK='TRUE';
      NO_DIR_CHECK='TRUE';
      ALLOW_CONNECT='TRUE';
    'VSS_CK31':
      PIN_NUMBER='(0,0,0,0,0,0,0,0,0,0,0,0,0,0,0,0,0,0,0,0,0,0,0,0,0,0,0,0,0,0,0,0,0,0,0,0,0,0,0,CK31)';
      PINUSE='POWER';
      NO_LOAD_CHECK='Both';
      NO_IO_CHECK='Both';
      NO_ASSERT_CHECK='TRUE';
      NO_DIR_CHECK='TRUE';
      ALLOW_CONNECT='TRUE';
    'VSS_CB44':
      PIN_NUMBER='(0,0,0,0,0,0,0,0,0,0,0,0,0,0,0,0,0,0,0,0,0,0,0,0,0,0,0,0,0,0,0,0,0,0,0,0,0,0,0,CB44)';
      PINUSE='POWER';
      NO_LOAD_CHECK='Both';
      NO_IO_CHECK='Both';
      NO_ASSERT_CHECK='TRUE';
      NO_DIR_CHECK='TRUE';
      ALLOW_CONNECT='TRUE';
    'VSS_AM37':
      PIN_NUMBER='(0,0,0,0,0,0,0,0,0,0,0,0,0,0,0,0,0,0,0,0,0,0,0,0,0,0,0,0,0,0,0,0,0,0,0,0,0,0,0,AM37)';
      PINUSE='POWER';
      NO_LOAD_CHECK='Both';
      NO_IO_CHECK='Both';
      NO_ASSERT_CHECK='TRUE';
      NO_DIR_CHECK='TRUE';
      ALLOW_CONNECT='TRUE';
    'VSS_K23':
      PIN_NUMBER='(0,0,0,0,0,0,0,0,0,0,0,0,0,0,0,0,0,0,0,0,0,0,0,0,0,0,0,0,0,0,0,0,0,0,0,0,0,0,0,K23)';
      PINUSE='POWER';
      NO_LOAD_CHECK='Both';
      NO_IO_CHECK='Both';
      NO_ASSERT_CHECK='TRUE';
      NO_DIR_CHECK='TRUE';
      ALLOW_CONNECT='TRUE';
    'VSS_CN54':
      PIN_NUMBER='(0,0,0,0,0,0,0,0,0,0,0,0,0,0,0,0,0,0,0,0,0,0,0,0,0,0,0,0,0,0,0,0,0,0,0,0,0,0,0,CN54)';
      PINUSE='POWER';
      NO_LOAD_CHECK='Both';
      NO_IO_CHECK='Both';
      NO_ASSERT_CHECK='TRUE';
      NO_DIR_CHECK='TRUE';
      ALLOW_CONNECT='TRUE';
    'VSS_CK10':
      PIN_NUMBER='(0,0,0,0,0,0,0,0,0,0,0,0,0,0,0,0,0,0,0,0,0,0,0,0,0,0,0,0,0,0,0,0,0,0,0,0,0,0,0,CK10)';
      PINUSE='POWER';
      NO_LOAD_CHECK='Both';
      NO_IO_CHECK='Both';
      NO_ASSERT_CHECK='TRUE';
      NO_DIR_CHECK='TRUE';
      ALLOW_CONNECT='TRUE';
    'VSS_AA72':
      PIN_NUMBER='(0,0,0,0,0,0,0,0,0,0,0,0,0,0,0,0,0,0,0,0,0,0,0,0,0,0,0,0,0,0,0,0,0,0,0,0,0,0,0,AA72)';
      PINUSE='POWER';
      NO_LOAD_CHECK='Both';
      NO_IO_CHECK='Both';
      NO_ASSERT_CHECK='TRUE';
      NO_DIR_CHECK='TRUE';
      ALLOW_CONNECT='TRUE';
    'VSS_AJ13':
      PIN_NUMBER='(0,0,0,0,0,0,0,0,0,0,0,0,0,0,0,0,0,0,0,0,0,0,0,0,0,0,0,0,0,0,0,0,0,0,0,0,0,0,0,AJ13)';
      PINUSE='POWER';
      NO_LOAD_CHECK='Both';
      NO_IO_CHECK='Both';
      NO_ASSERT_CHECK='TRUE';
      NO_DIR_CHECK='TRUE';
      ALLOW_CONNECT='TRUE';
    'VSS_AD31':
      PIN_NUMBER='(0,0,0,0,0,0,0,0,0,0,0,0,0,0,0,0,0,0,0,0,0,0,0,0,0,0,0,0,0,0,0,0,0,0,0,0,0,0,0,AD31)';
      PINUSE='POWER';
      NO_LOAD_CHECK='Both';
      NO_IO_CHECK='Both';
      NO_ASSERT_CHECK='TRUE';
      NO_DIR_CHECK='TRUE';
      ALLOW_CONNECT='TRUE';
    'VSS_AA42':
      PIN_NUMBER='(0,0,0,0,0,0,0,0,0,0,0,0,0,0,0,0,0,0,0,0,0,0,0,0,0,0,0,0,0,0,0,0,0,0,0,0,0,0,0,AA42)';
      PINUSE='POWER';
      NO_LOAD_CHECK='Both';
      NO_IO_CHECK='Both';
      NO_ASSERT_CHECK='TRUE';
      NO_DIR_CHECK='TRUE';
      ALLOW_CONNECT='TRUE';
    'VSS_V27':
      PIN_NUMBER='(0,0,0,0,0,0,0,0,0,0,0,0,0,0,0,0,0,0,0,0,0,0,0,0,0,0,0,0,0,0,0,0,0,0,0,0,0,0,0,V27)';
      PINUSE='POWER';
      NO_LOAD_CHECK='Both';
      NO_IO_CHECK='Both';
      NO_ASSERT_CHECK='TRUE';
      NO_DIR_CHECK='TRUE';
      ALLOW_CONNECT='TRUE';
    'VSS_CF46':
      PIN_NUMBER='(0,0,0,0,0,0,0,0,0,0,0,0,0,0,0,0,0,0,0,0,0,0,0,0,0,0,0,0,0,0,0,0,0,0,0,0,0,0,0,CF46)';
      PINUSE='POWER';
      NO_LOAD_CHECK='Both';
      NO_IO_CHECK='Both';
      NO_ASSERT_CHECK='TRUE';
      NO_DIR_CHECK='TRUE';
      ALLOW_CONNECT='TRUE';
    'VSS_CC22':
      PIN_NUMBER='(0,0,0,0,0,0,0,0,0,0,0,0,0,0,0,0,0,0,0,0,0,0,0,0,0,0,0,0,0,0,0,0,0,0,0,0,0,0,0,CC22)';
      PINUSE='POWER';
      NO_LOAD_CHECK='Both';
      NO_IO_CHECK='Both';
      NO_ASSERT_CHECK='TRUE';
      NO_DIR_CHECK='TRUE';
      ALLOW_CONNECT='TRUE';
    'VSS_AN20':
      PIN_NUMBER='(0,0,0,0,0,0,0,0,0,0,0,0,0,0,0,0,0,0,0,0,0,0,0,0,0,0,0,0,0,0,0,0,0,0,0,0,0,0,0,AN20)';
      PINUSE='POWER';
      NO_LOAD_CHECK='Both';
      NO_IO_CHECK='Both';
      NO_ASSERT_CHECK='TRUE';
      NO_DIR_CHECK='TRUE';
      ALLOW_CONNECT='TRUE';
    'VSS_P68':
      PIN_NUMBER='(0,0,0,0,0,0,0,0,0,0,0,0,0,0,0,0,0,0,0,0,0,0,0,0,0,0,0,0,0,0,0,0,0,0,0,0,0,0,0,P68)';
      PINUSE='POWER';
      NO_LOAD_CHECK='Both';
      NO_IO_CHECK='Both';
      NO_ASSERT_CHECK='TRUE';
      NO_DIR_CHECK='TRUE';
      ALLOW_CONNECT='TRUE';
    'VSS_P25':
      PIN_NUMBER='(0,0,0,0,0,0,0,0,0,0,0,0,0,0,0,0,0,0,0,0,0,0,0,0,0,0,0,0,0,0,0,0,0,0,0,0,0,0,0,P25)';
      PINUSE='POWER';
      NO_LOAD_CHECK='Both';
      NO_IO_CHECK='Both';
      NO_ASSERT_CHECK='TRUE';
      NO_DIR_CHECK='TRUE';
      ALLOW_CONNECT='TRUE';
    'VSS_CU58':
      PIN_NUMBER='(0,0,0,0,0,0,0,0,0,0,0,0,0,0,0,0,0,0,0,0,0,0,0,0,0,0,0,0,0,0,0,0,0,0,0,0,0,0,0,CU58)';
      PINUSE='POWER';
      NO_LOAD_CHECK='Both';
      NO_IO_CHECK='Both';
      NO_ASSERT_CHECK='TRUE';
      NO_DIR_CHECK='TRUE';
      ALLOW_CONNECT='TRUE';
    'VSS_BW25':
      PIN_NUMBER='(0,0,0,0,0,0,0,0,0,0,0,0,0,0,0,0,0,0,0,0,0,0,0,0,0,0,0,0,0,0,0,0,0,0,0,0,0,0,0,BW25)';
      PINUSE='POWER';
      NO_LOAD_CHECK='Both';
      NO_IO_CHECK='Both';
      NO_ASSERT_CHECK='TRUE';
      NO_DIR_CHECK='TRUE';
      ALLOW_CONNECT='TRUE';
    'VSS_AH33':
      PIN_NUMBER='(0,0,0,0,0,0,0,0,0,0,0,0,0,0,0,0,0,0,0,0,0,0,0,0,0,0,0,0,0,0,0,0,0,0,0,0,0,0,0,AH33)';
      PINUSE='POWER';
      NO_LOAD_CHECK='Both';
      NO_IO_CHECK='Both';
      NO_ASSERT_CHECK='TRUE';
      NO_DIR_CHECK='TRUE';
      ALLOW_CONNECT='TRUE';
    'VSS_AE4':
      PIN_NUMBER='(0,0,0,0,0,0,0,0,0,0,0,0,0,0,0,0,0,0,0,0,0,0,0,0,0,0,0,0,0,0,0,0,0,0,0,0,0,0,0,AE4)';
      PINUSE='POWER';
      NO_LOAD_CHECK='Both';
      NO_IO_CHECK='Both';
      NO_ASSERT_CHECK='TRUE';
      NO_DIR_CHECK='TRUE';
      ALLOW_CONNECT='TRUE';
    'VSS_CG42':
      PIN_NUMBER='(0,0,0,0,0,0,0,0,0,0,0,0,0,0,0,0,0,0,0,0,0,0,0,0,0,0,0,0,0,0,0,0,0,0,0,0,0,0,0,CG42)';
      PINUSE='POWER';
      NO_LOAD_CHECK='Both';
      NO_IO_CHECK='Both';
      NO_ASSERT_CHECK='TRUE';
      NO_DIR_CHECK='TRUE';
      ALLOW_CONNECT='TRUE';
    'VSS_DA56':
      PIN_NUMBER='(0,0,0,0,0,0,0,0,0,0,0,0,0,0,0,0,0,0,0,0,0,0,0,0,0,0,0,0,0,0,0,0,0,0,0,0,0,0,0,DA56)';
      PINUSE='POWER';
      NO_LOAD_CHECK='Both';
      NO_IO_CHECK='Both';
      NO_ASSERT_CHECK='TRUE';
      NO_DIR_CHECK='TRUE';
      ALLOW_CONNECT='TRUE';
    'VSS_K59':
      PIN_NUMBER='(0,0,0,0,0,0,0,0,0,0,0,0,0,0,0,0,0,0,0,0,0,0,0,0,0,0,0,0,0,0,0,0,0,0,0,0,0,0,0,K59)';
      PINUSE='POWER';
      NO_LOAD_CHECK='Both';
      NO_IO_CHECK='Both';
      NO_ASSERT_CHECK='TRUE';
      NO_DIR_CHECK='TRUE';
      ALLOW_CONNECT='TRUE';
    'VSS_CM50':
      PIN_NUMBER='(0,0,0,0,0,0,0,0,0,0,0,0,0,0,0,0,0,0,0,0,0,0,0,0,0,0,0,0,0,0,0,0,0,0,0,0,0,0,0,CM50)';
      PINUSE='POWER';
      NO_LOAD_CHECK='Both';
      NO_IO_CHECK='Both';
      NO_ASSERT_CHECK='TRUE';
      NO_DIR_CHECK='TRUE';
      ALLOW_CONNECT='TRUE';
    'VSS_CT52':
      PIN_NUMBER='(0,0,0,0,0,0,0,0,0,0,0,0,0,0,0,0,0,0,0,0,0,0,0,0,0,0,0,0,0,0,0,0,0,0,0,0,0,0,0,CT52)';
      PINUSE='POWER';
      NO_LOAD_CHECK='Both';
      NO_IO_CHECK='Both';
      NO_ASSERT_CHECK='TRUE';
      NO_DIR_CHECK='TRUE';
      ALLOW_CONNECT='TRUE';
    'VSS_BV42':
      PIN_NUMBER='(0,0,0,0,0,0,0,0,0,0,0,0,0,0,0,0,0,0,0,0,0,0,0,0,0,0,0,0,0,0,0,0,0,0,0,0,0,0,0,BV42)';
      PINUSE='POWER';
      NO_LOAD_CHECK='Both';
      NO_IO_CHECK='Both';
      NO_ASSERT_CHECK='TRUE';
      NO_DIR_CHECK='TRUE';
      ALLOW_CONNECT='TRUE';
    'VSS_V68':
      PIN_NUMBER='(0,0,0,0,0,0,0,0,0,0,0,0,0,0,0,0,0,0,0,0,0,0,0,0,0,0,0,0,0,0,0,0,0,0,0,0,0,0,0,V68)';
      PINUSE='POWER';
      NO_LOAD_CHECK='Both';
      NO_IO_CHECK='Both';
      NO_ASSERT_CHECK='TRUE';
      NO_DIR_CHECK='TRUE';
      ALLOW_CONNECT='TRUE';
  end_pin;
  body
    PART_NAME='GENOA_SP5';
    Value='SP5';
    BODY_NAME='GENOA_SP5';
    PHYS_DES_PREFIX='U';
    CLASS='IC';
    NC_PINS='(MH1,MH2,MH3,MH4,MH5,MH6)';
  end_body;
end_primitive;

END.
